G04 ================== begin FILE IDENTIFICATION RECORD ==================*
G04 Layout Name:  9324_DA0F0TMBIJ0_F0T_Motherboard_J_v01_20230324_0910.brd*
G04 Film Name:    gnd6*
G04 File Format:  Gerber RS274X*
G04 File Origin:  Cadence Allegro 17.2-S081*
G04 Origin Date:  Sat Mar 25 08:45:10 2023*
G04 *
G04 Layer:  DRAWING FORMAT/TITLE_BLOCK_A*
G04 Layer:  PIN/SPECIAL_DRILL*
G04 Layer:  VIA CLASS/GND6*
G04 Layer:  PIN/GND6*
G04 Layer:  MANUFACTURING/PHOTOPLOT_OUTLINE*
G04 Layer:  ETCH/GND6*
G04 Layer:  DRAWING FORMAT/TITLE_BLOCK*
G04 Layer:  DRAWING FORMAT/TITLE_DATA_GND6*
G04 *
G04 Offset:    (0.00 0.00)*
G04 Mirror:    No*
G04 Mode:      Negative*
G04 Rotation:  0*
G04 FullContactRelief:  No*
G04 UndefLineWidth:     6.00*
G04 ================== end FILE IDENTIFICATION RECORD ====================*
%FSLAX25Y25*MOIN*%
%IR0*IPPOS*OFA0.00000B0.00000*MIA0B0*SFA1.00000B1.00000*%
%ADD15C,.03*%
%ADD31C,.06*%
%ADD46C,.061*%
%ADD27C,.07*%
%AMMACRO55*
4,1,36,0.0,.01,
-.001736,.009848,
-.00342,.009397,
-.005,.00866,
-.006428,.00766,
-.00766,.006428,
-.00866,.005,
-.009397,.00342,
-.009848,.001736,
-.01,0.0,
-.009848,-.001736,
-.009397,-.00342,
-.00866,-.005,
-.00766,-.006428,
-.006428,-.00766,
-.005,-.00866,
-.00342,-.009397,
-.001736,-.009848,
0.0,-.01,
.001736,-.009848,
.00342,-.009397,
.005,-.00866,
.006428,-.00766,
.00766,-.006428,
.00866,-.005,
.009397,-.00342,
.009848,-.001736,
.01,0.0,
.009848,.001736,
.009397,.00342,
.00866,.005,
.00766,.006428,
.006428,.00766,
.005,.00866,
.00342,.009397,
.001736,.009848,
0.0,.01,
0.0*
%
%ADD55MACRO55*%
%ADD52C,.071*%
%ADD29C,.062*%
%ADD17C,.026*%
%AMMACRO71*
4,1,36,.0025,0.0,
.002462,.000434,
.002349,.000855,
.002165,.00125,
.001915,.001607,
.001607,.001915,
.00125,.002165,
.000855,.002349,
.000434,.002462,
0.0,.0025,
-.000434,.002462,
-.000855,.002349,
-.00125,.002165,
-.001607,.001915,
-.001915,.001607,
-.002165,.00125,
-.002349,.000855,
-.002462,.000434,
-.0025,0.0,
-.002462,-.000434,
-.002349,-.000855,
-.002165,-.00125,
-.001915,-.001607,
-.001607,-.001915,
-.00125,-.002165,
-.000855,-.002349,
-.000434,-.002462,
0.0,-.0025,
.000434,-.002462,
.000855,-.002349,
.00125,-.002165,
.001607,-.001915,
.001915,-.001607,
.002165,-.00125,
.002349,-.000855,
.002462,-.000434,
.0025,0.0,
135.*
%
%ADD71MACRO71*%
%ADD67C,.064*%
%AMMACRO19*
4,1,36,.0025,0.0,
.002462,.000434,
.002349,.000855,
.002165,.00125,
.001915,.001607,
.001607,.001915,
.00125,.002165,
.000855,.002349,
.000434,.002462,
0.0,.0025,
-.000434,.002462,
-.000855,.002349,
-.00125,.002165,
-.001607,.001915,
-.001915,.001607,
-.002165,.00125,
-.002349,.000855,
-.002462,.000434,
-.0025,0.0,
-.002462,-.000434,
-.002349,-.000855,
-.002165,-.00125,
-.001915,-.001607,
-.001607,-.001915,
-.00125,-.002165,
-.000855,-.002349,
-.000434,-.002462,
0.0,-.0025,
.000434,-.002462,
.000855,-.002349,
.00125,-.002165,
.001607,-.001915,
.001915,-.001607,
.002165,-.00125,
.002349,-.000855,
.002462,-.000434,
.0025,0.0,
225.*
%
%ADD19MACRO19*%
%AMMACRO14*
4,1,36,.0025,0.0,
.002462,.000434,
.002349,.000855,
.002165,.00125,
.001915,.001607,
.001607,.001915,
.00125,.002165,
.000855,.002349,
.000434,.002462,
0.0,.0025,
-.000434,.002462,
-.000855,.002349,
-.00125,.002165,
-.001607,.001915,
-.001915,.001607,
-.002165,.00125,
-.002349,.000855,
-.002462,.000434,
-.0025,0.0,
-.002462,-.000434,
-.002349,-.000855,
-.002165,-.00125,
-.001915,-.001607,
-.001607,-.001915,
-.00125,-.002165,
-.000855,-.002349,
-.000434,-.002462,
0.0,-.0025,
.000434,-.002462,
.000855,-.002349,
.00125,-.002165,
.001607,-.001915,
.001915,-.001607,
.002165,-.00125,
.002349,-.000855,
.002462,-.000434,
.0025,0.0,
180.*
%
%ADD14MACRO14*%
%AMMACRO11*
4,1,36,.0025,0.0,
.002462,.000434,
.002349,.000855,
.002165,.00125,
.001915,.001607,
.001607,.001915,
.00125,.002165,
.000855,.002349,
.000434,.002462,
0.0,.0025,
-.000434,.002462,
-.000855,.002349,
-.00125,.002165,
-.001607,.001915,
-.001915,.001607,
-.002165,.00125,
-.002349,.000855,
-.002462,.000434,
-.0025,0.0,
-.002462,-.000434,
-.002349,-.000855,
-.002165,-.00125,
-.001915,-.001607,
-.001607,-.001915,
-.00125,-.002165,
-.000855,-.002349,
-.000434,-.002462,
0.0,-.0025,
.000434,-.002462,
.000855,-.002349,
.00125,-.002165,
.001607,-.001915,
.001915,-.001607,
.002165,-.00125,
.002349,-.000855,
.002462,-.000434,
.0025,0.0,
270.*
%
%ADD11MACRO11*%
%AMMACRO53*
4,1,36,-.0025,0.0,
-.002462,.000434,
-.002349,.000855,
-.002165,.00125,
-.001915,.001607,
-.001607,.001915,
-.00125,.002165,
-.000855,.002349,
-.000434,.002462,
0.0,.0025,
.000434,.002462,
.000855,.002349,
.00125,.002165,
.001607,.001915,
.001915,.001607,
.002165,.00125,
.002349,.000855,
.002462,.000434,
.0025,0.0,
.002462,-.000434,
.002349,-.000855,
.002165,-.00125,
.001915,-.001607,
.001607,-.001915,
.00125,-.002165,
.000855,-.002349,
.000434,-.002462,
0.0,-.0025,
-.000434,-.002462,
-.000855,-.002349,
-.00125,-.002165,
-.001607,-.001915,
-.001915,-.001607,
-.002165,-.00125,
-.002349,-.000855,
-.002462,-.000434,
-.0025,0.0,
180.*
%
%ADD53MACRO53*%
%AMMACRO44*
4,1,36,.003,0.0,
.002954,.000521,
.002819,.001026,
.002598,.0015,
.002298,.001928,
.001928,.002298,
.0015,.002598,
.001026,.002819,
.000521,.002954,
0.0,.003,
-.000521,.002954,
-.001026,.002819,
-.0015,.002598,
-.001928,.002298,
-.002298,.001928,
-.002598,.0015,
-.002819,.001026,
-.002954,.000521,
-.003,0.0,
-.002954,-.000521,
-.002819,-.001026,
-.002598,-.0015,
-.002298,-.001928,
-.001928,-.002298,
-.0015,-.002598,
-.001026,-.002819,
-.000521,-.002954,
0.0,-.003,
.000521,-.002954,
.001026,-.002819,
.0015,-.002598,
.001928,-.002298,
.002298,-.001928,
.002598,-.0015,
.002819,-.001026,
.002954,-.000521,
.003,0.0,
270.*
%
%ADD44MACRO44*%
%AMMACRO42*
4,1,36,.003,0.0,
.002954,.000521,
.002819,.001026,
.002598,.0015,
.002298,.001928,
.001928,.002298,
.0015,.002598,
.001026,.002819,
.000521,.002954,
0.0,.003,
-.000521,.002954,
-.001026,.002819,
-.0015,.002598,
-.001928,.002298,
-.002298,.001928,
-.002598,.0015,
-.002819,.001026,
-.002954,.000521,
-.003,0.0,
-.002954,-.000521,
-.002819,-.001026,
-.002598,-.0015,
-.002298,-.001928,
-.001928,-.002298,
-.0015,-.002598,
-.001026,-.002819,
-.000521,-.002954,
0.0,-.003,
.000521,-.002954,
.001026,-.002819,
.0015,-.002598,
.001928,-.002298,
.002298,-.001928,
.002598,-.0015,
.002819,-.001026,
.002954,-.000521,
.003,0.0,
180.*
%
%ADD42MACRO42*%
%ADD26C,.074*%
%AMMACRO74*
4,1,36,-.003,0.0,
-.002954,.000521,
-.002819,.001026,
-.002598,.0015,
-.002298,.001928,
-.001928,.002298,
-.0015,.002598,
-.001026,.002819,
-.000521,.002954,
0.0,.003,
.000521,.002954,
.001026,.002819,
.0015,.002598,
.001928,.002298,
.002298,.001928,
.002598,.0015,
.002819,.001026,
.002954,.000521,
.003,0.0,
.002954,-.000521,
.002819,-.001026,
.002598,-.0015,
.002298,-.001928,
.001928,-.002298,
.0015,-.002598,
.001026,-.002819,
.000521,-.002954,
0.0,-.003,
-.000521,-.002954,
-.001026,-.002819,
-.0015,-.002598,
-.001928,-.002298,
-.002298,-.001928,
-.002598,-.0015,
-.002819,-.001026,
-.002954,-.000521,
-.003,0.0,
270.*
%
%ADD74MACRO74*%
%ADD73C,.0435*%
%ADD63C,.06015*%
%ADD50C,.076*%
%ADD49C,.095*%
%ADD24C,.0257*%
%ADD76C,.087*%
%ADD35C,.03417*%
%ADD41C,.0259*%
%ADD22C,.0277*%
%AMMACRO40*
4,1,15,.06231,.03403,
.067273,.022693,
.070191,.010666,
.070977,-.001684,
.069606,-.013984,
.066121,-.025858,
.06231,-.03403,
.06745,-.03917,
.073227,-.026862,
.076779,-.013739,
.077998,-.000197,
.076848,.01335,
.073362,.026492,
.067647,.038828,
.06745,.03917,
.06231,.03403,
0.0*
4,1,15,.03403,-.06231,
.022693,-.067273,
.010666,-.070191,
-.001684,-.070977,
-.013984,-.069606,
-.025858,-.066121,
-.03403,-.06231,
-.03917,-.06745,
-.026862,-.073227,
-.013739,-.076779,
-.000197,-.077998,
.01335,-.076848,
.026492,-.073362,
.038828,-.067647,
.03917,-.06745,
.03403,-.06231,
0.0*
4,1,15,-.06231,-.03403,
-.067273,-.022693,
-.070191,-.010666,
-.070977,.001684,
-.069606,.013984,
-.066121,.025858,
-.06231,.03403,
-.06745,.03917,
-.073227,.026862,
-.076779,.013739,
-.077998,.000197,
-.076848,-.01335,
-.073362,-.026492,
-.067647,-.038828,
-.06745,-.03917,
-.06231,-.03403,
0.0*
4,1,15,-.03403,.06231,
-.022693,.067273,
-.010666,.070191,
.001684,.070977,
.013984,.069606,
.025858,.066121,
.03403,.06231,
.03917,.06745,
.026862,.073227,
.013739,.076779,
.000197,.077998,
-.01335,.076848,
-.026492,.073362,
-.038828,.067647,
-.03917,.06745,
-.03403,.06231,
0.0*
%
%ADD40MACRO40*%
%AMMACRO10*
4,1,18,.09673,.06845,
.107147,.050613,
.114308,.031238,
.117996,.010914,
.118098,-.009741,
.114613,-.030101,
.107644,-.049546,
.097406,-.067485,
.09673,-.06845,
.10175,-.07347,
.112962,-.054685,
.120742,-.034239,
.124853,-.012752,
.125171,.009122,
.121685,.030719,
.114502,.051383,
.10384,.070486,
.10175,.07347,
.09673,.06845,
0.0*
4,1,18,.06845,-.09673,
.050613,-.107147,
.031238,-.114308,
.010914,-.117996,
-.009741,-.118098,
-.030101,-.114613,
-.049546,-.107644,
-.067485,-.097406,
-.06845,-.09673,
-.07347,-.10175,
-.054685,-.112962,
-.034239,-.120742,
-.012752,-.124853,
.009122,-.125171,
.030719,-.121685,
.051383,-.114502,
.070486,-.10384,
.07347,-.10175,
.06845,-.09673,
0.0*
4,1,18,-.09673,-.06845,
-.107147,-.050613,
-.114308,-.031238,
-.117996,-.010914,
-.118098,.009741,
-.114613,.030101,
-.107644,.049546,
-.097406,.067485,
-.09673,.06845,
-.10175,.07347,
-.112962,.054685,
-.120742,.034239,
-.124853,.012752,
-.125171,-.009122,
-.121685,-.030719,
-.114502,-.051383,
-.10384,-.070486,
-.10175,-.07347,
-.09673,-.06845,
0.0*
4,1,18,-.06845,.09673,
-.050613,.107147,
-.031238,.114308,
-.010914,.117996,
.009741,.118098,
.030101,.114613,
.049546,.107644,
.067485,.097406,
.06845,.09673,
.07347,.10175,
.054685,.112962,
.034239,.120742,
.012752,.124853,
-.009122,.125171,
-.030719,.121685,
-.051383,.114502,
-.070486,.10384,
-.07347,.10175,
-.06845,.09673,
0.0*
%
%ADD10MACRO10*%
%ADD36C,.03187*%
%AMMACRO37*
4,1,16,.0711,.04282,
.077455,.029823,
.081457,.01592,
.082984,.001533,
.08199,-.0129,
.078504,-.026942,
.072633,-.040164,
.0711,-.04282,
.07619,-.04791,
.083352,-.033952,
.087981,-.018962,
.089937,-.003396,
.089161,.012273,
.085675,.027569,
.079586,.042027,
.07619,.04791,
.0711,.04282,
0.0*
4,1,16,.04282,-.0711,
.029823,-.077455,
.01592,-.081457,
.001533,-.082984,
-.0129,-.08199,
-.026942,-.078504,
-.040164,-.072633,
-.04282,-.0711,
-.04791,-.07619,
-.033952,-.083352,
-.018962,-.087981,
-.003396,-.089937,
.012273,-.089161,
.027569,-.085675,
.042027,-.079586,
.04791,-.07619,
.04282,-.0711,
0.0*
4,1,16,-.0711,-.04282,
-.077455,-.029823,
-.081457,-.01592,
-.082984,-.001533,
-.08199,.0129,
-.078504,.026942,
-.072633,.040164,
-.0711,.04282,
-.07619,.04791,
-.083352,.033952,
-.087981,.018962,
-.089937,.003396,
-.089161,-.012273,
-.085675,-.027569,
-.079586,-.042027,
-.07619,-.04791,
-.0711,-.04282,
0.0*
4,1,16,-.04282,.0711,
-.029823,.077455,
-.01592,.081457,
-.001533,.082984,
.0129,.08199,
.026942,.078504,
.040164,.072633,
.04282,.0711,
.04791,.07619,
.033952,.083352,
.018962,.087981,
.003396,.089937,
-.012273,.089161,
-.027569,.085675,
-.042027,.079586,
-.04791,.07619,
-.04282,.0711,
0.0*
%
%ADD37MACRO37*%
%AMMACRO32*
4,1,15,.02438,.01377,
.026401,.009327,
.027619,.004601,
.027999,-.000265,
.027527,-.005123,
.02622,-.009825,
.02438,-.01377,
.02948,-.01887,
.032309,-.013464,
.034156,-.007649,
.034965,-.001602,
.034712,.004494,
.033405,.010454,
.031082,.016095,
.02948,.01887,
.02438,.01377,
90.*
4,1,15,.01377,-.02438,
.009327,-.026401,
.004601,-.027619,
-.000265,-.027999,
-.005123,-.027527,
-.009825,-.02622,
-.01377,-.02438,
-.01887,-.02948,
-.013464,-.032309,
-.007649,-.034156,
-.001602,-.034965,
.004494,-.034712,
.010454,-.033405,
.016095,-.031082,
.01887,-.02948,
.01377,-.02438,
90.*
4,1,15,-.02438,-.01377,
-.026401,-.009327,
-.027619,-.004601,
-.027999,.000265,
-.027527,.005123,
-.02622,.009825,
-.02438,.01377,
-.02948,.01887,
-.032309,.013464,
-.034156,.007649,
-.034965,.001602,
-.034712,-.004494,
-.033405,-.010454,
-.031082,-.016095,
-.02948,-.01887,
-.02438,-.01377,
90.*
4,1,15,-.01377,.02438,
-.009327,.026401,
-.004601,.027619,
.000265,.027999,
.005123,.027527,
.009825,.02622,
.01377,.02438,
.01887,.02948,
.013464,.032309,
.007649,.034156,
.001602,.034965,
-.004494,.034712,
-.010454,.033405,
-.016095,.031082,
-.01887,.02948,
-.01377,.02438,
90.*
%
%ADD32MACRO32*%
%AMMACRO30*
4,1,15,.02438,.01377,
.026401,.009327,
.027619,.004601,
.027999,-.000265,
.027527,-.005123,
.02622,-.009825,
.02438,-.01377,
.02948,-.01887,
.032309,-.013464,
.034156,-.007649,
.034965,-.001602,
.034712,.004494,
.033405,.010454,
.031082,.016095,
.02948,.01887,
.02438,.01377,
0.0*
4,1,15,.01377,-.02438,
.009327,-.026401,
.004601,-.027619,
-.000265,-.027999,
-.005123,-.027527,
-.009825,-.02622,
-.01377,-.02438,
-.01887,-.02948,
-.013464,-.032309,
-.007649,-.034156,
-.001602,-.034965,
.004494,-.034712,
.010454,-.033405,
.016095,-.031082,
.01887,-.02948,
.01377,-.02438,
0.0*
4,1,15,-.02438,-.01377,
-.026401,-.009327,
-.027619,-.004601,
-.027999,.000265,
-.027527,.005123,
-.02622,.009825,
-.02438,.01377,
-.02948,.01887,
-.032309,.013464,
-.034156,.007649,
-.034965,.001602,
-.034712,-.004494,
-.033405,-.010454,
-.031082,-.016095,
-.02948,-.01887,
-.02438,-.01377,
0.0*
4,1,15,-.01377,.02438,
-.009327,.026401,
-.004601,.027619,
.000265,.027999,
.005123,.027527,
.009825,.02622,
.01377,.02438,
.01887,.02948,
.013464,.032309,
.007649,.034156,
.001602,.034965,
-.004494,.034712,
-.010454,.033405,
-.016095,.031082,
-.01887,.02948,
-.01377,.02438,
0.0*
%
%ADD30MACRO30*%
%AMMACRO48*
4,1,15,.02475,.01414,
.026829,.009627,
.028094,.004822,
.028504,-.000129,
.028049,-.005077,
.026741,-.009871,
.02475,-.01414,
.02984,-.01923,
.032726,-.013756,
.034617,-.007864,
.035457,-.001734,
.03522,.00445,
.033912,.010498,
.031574,.016227,
.02984,.01923,
.02475,.01414,
90.*
4,1,15,.01414,-.02475,
.009627,-.026829,
.004822,-.028094,
-.000129,-.028504,
-.005077,-.028049,
-.009871,-.026741,
-.01414,-.02475,
-.01923,-.02984,
-.013756,-.032726,
-.007864,-.034617,
-.001734,-.035457,
.00445,-.03522,
.010498,-.033912,
.016227,-.031574,
.01923,-.02984,
.01414,-.02475,
90.*
4,1,15,-.02475,-.01414,
-.026829,-.009627,
-.028094,-.004822,
-.028504,.000129,
-.028049,.005077,
-.026741,.009871,
-.02475,.01414,
-.02984,.01923,
-.032726,.013756,
-.034617,.007864,
-.035457,.001734,
-.03522,-.00445,
-.033912,-.010498,
-.031574,-.016227,
-.02984,-.01923,
-.02475,-.01414,
90.*
4,1,15,-.01414,.02475,
-.009627,.026829,
-.004822,.028094,
.000129,.028504,
.005077,.028049,
.009871,.026741,
.01414,.02475,
.01923,.02984,
.013756,.032726,
.007864,.034617,
.001734,.035457,
-.00445,.03522,
-.010498,.033912,
-.016227,.031574,
-.01923,.02984,
-.01414,.02475,
90.*
%
%ADD48MACRO48*%
%AMMACRO66*
4,1,18,.07103,.05689,
.07983,.043691,
.086204,.029165,
.089959,.013753,
.09098,-.002077,
.089237,-.017844,
.084783,-.033069,
.077753,-.047289,
.07103,-.05689,
.07601,-.06186,
.085597,-.047721,
.092583,-.032132,
.096757,-.015567,
.09799,.001471,
.096246,.018464,
.091577,.034897,
.084126,.050269,
.07601,.06186,
.07103,.05689,
0.0*
4,1,18,.05689,-.07103,
.043691,-.07983,
.029165,-.086204,
.013753,-.089959,
-.002077,-.09098,
-.017844,-.089237,
-.033069,-.084783,
-.047289,-.077753,
-.05689,-.07103,
-.06186,-.07601,
-.047721,-.085597,
-.032132,-.092583,
-.015567,-.096757,
.001471,-.09799,
.018464,-.096246,
.034897,-.091577,
.050269,-.084126,
.06186,-.07601,
.05689,-.07103,
0.0*
4,1,18,-.07103,-.05689,
-.07983,-.043691,
-.086204,-.029165,
-.089959,-.013753,
-.09098,.002077,
-.089237,.017844,
-.084783,.033069,
-.077753,.047289,
-.07103,.05689,
-.07601,.06186,
-.085597,.047721,
-.092583,.032132,
-.096757,.015567,
-.09799,-.001471,
-.096246,-.018464,
-.091577,-.034897,
-.084126,-.050269,
-.07601,-.06186,
-.07103,-.05689,
0.0*
4,1,18,-.05689,.07103,
-.043691,.07983,
-.029165,.086204,
-.013753,.089959,
.002077,.09098,
.017844,.089237,
.033069,.084783,
.047289,.077753,
.05689,.07103,
.06186,.07601,
.047721,.085597,
.032132,.092583,
.015567,.096757,
-.001471,.09799,
-.018464,.096246,
-.034897,.091577,
-.050269,.084126,
-.06186,.07601,
-.05689,.07103,
0.0*
%
%ADD66MACRO66*%
%AMMACRO51*
4,1,15,.02475,.01414,
.026829,.009627,
.028094,.004822,
.028504,-.000129,
.028049,-.005077,
.026741,-.009871,
.02475,-.01414,
.02984,-.01923,
.032726,-.013756,
.034617,-.007864,
.035457,-.001734,
.03522,.00445,
.033912,.010498,
.031574,.016227,
.02984,.01923,
.02475,.01414,
0.0*
4,1,15,.01414,-.02475,
.009627,-.026829,
.004822,-.028094,
-.000129,-.028504,
-.005077,-.028049,
-.009871,-.026741,
-.01414,-.02475,
-.01923,-.02984,
-.013756,-.032726,
-.007864,-.034617,
-.001734,-.035457,
.00445,-.03522,
.010498,-.033912,
.016227,-.031574,
.01923,-.02984,
.01414,-.02475,
0.0*
4,1,15,-.02475,-.01414,
-.026829,-.009627,
-.028094,-.004822,
-.028504,.000129,
-.028049,.005077,
-.026741,.009871,
-.02475,.01414,
-.02984,.01923,
-.032726,.013756,
-.034617,.007864,
-.035457,.001734,
-.03522,-.00445,
-.033912,-.010498,
-.031574,-.016227,
-.02984,-.01923,
-.02475,-.01414,
0.0*
4,1,15,-.01414,.02475,
-.009627,.026829,
-.004822,.028094,
.000129,.028504,
.005077,.028049,
.009871,.026741,
.01414,.02475,
.01923,.02984,
.013756,.032726,
.007864,.034617,
.001734,.035457,
-.00445,.03522,
-.010498,.033912,
-.016227,.031574,
-.01923,.02984,
-.01414,.02475,
0.0*
%
%ADD51MACRO51*%
%AMMACRO38*
4,1,16,.02511,.01451,
.027248,.009929,
.028558,.005047,
.029001,.000011,
.028562,-.005025,
.027256,-.009909,
.025121,-.014491,
.02511,-.01451,
.0302,-.01959,
.033143,-.014048,
.035079,-.00808,
.035949,-.001865,
.035727,.004405,
.034419,.010542,
.032065,.016359,
.0302,.01959,
.02511,.01451,
90.*
4,1,16,.01451,-.02511,
.009929,-.027248,
.005047,-.028558,
.000011,-.029001,
-.005025,-.028562,
-.009909,-.027256,
-.014491,-.025121,
-.01451,-.02511,
-.01959,-.0302,
-.014048,-.033143,
-.00808,-.035079,
-.001865,-.035949,
.004405,-.035727,
.010542,-.034419,
.016359,-.032065,
.01959,-.0302,
.01451,-.02511,
90.*
4,1,16,-.02511,-.01451,
-.027248,-.009929,
-.028558,-.005047,
-.029001,-.000011,
-.028562,.005025,
-.027256,.009909,
-.025121,.014491,
-.02511,.01451,
-.0302,.01959,
-.033143,.014048,
-.035079,.00808,
-.035949,.001865,
-.035727,-.004405,
-.034419,-.010542,
-.032065,-.016359,
-.0302,-.01959,
-.02511,-.01451,
90.*
4,1,16,-.01451,.02511,
-.009929,.027248,
-.005047,.028558,
-.000011,.029001,
.005025,.028562,
.009909,.027256,
.014491,.025121,
.01451,.02511,
.01959,.0302,
.014048,.033143,
.00808,.035079,
.001865,.035949,
-.004405,.035727,
-.010542,.034419,
-.016359,.032065,
-.01959,.0302,
-.01451,.02511,
90.*
%
%ADD38MACRO38*%
%AMMACRO28*
4,1,16,.02511,.01451,
.027248,.009929,
.028558,.005047,
.029001,.000011,
.028562,-.005025,
.027256,-.009909,
.025121,-.014491,
.02511,-.01451,
.0302,-.01959,
.033143,-.014048,
.035079,-.00808,
.035949,-.001865,
.035727,.004405,
.034419,.010542,
.032065,.016359,
.0302,.01959,
.02511,.01451,
0.0*
4,1,16,.01451,-.02511,
.009929,-.027248,
.005047,-.028558,
.000011,-.029001,
-.005025,-.028562,
-.009909,-.027256,
-.014491,-.025121,
-.01451,-.02511,
-.01959,-.0302,
-.014048,-.033143,
-.00808,-.035079,
-.001865,-.035949,
.004405,-.035727,
.010542,-.034419,
.016359,-.032065,
.01959,-.0302,
.01451,-.02511,
0.0*
4,1,16,-.02511,-.01451,
-.027248,-.009929,
-.028558,-.005047,
-.029001,-.000011,
-.028562,.005025,
-.027256,.009909,
-.025121,.014491,
-.02511,.01451,
-.0302,.01959,
-.033143,.014048,
-.035079,.00808,
-.035949,.001865,
-.035727,-.004405,
-.034419,-.010542,
-.032065,-.016359,
-.0302,-.01959,
-.02511,-.01451,
0.0*
4,1,16,-.01451,.02511,
-.009929,.027248,
-.005047,.028558,
-.000011,.029001,
.005025,.028562,
.009909,.027256,
.014491,.025121,
.01451,.02511,
.01959,.0302,
.014048,.033143,
.00808,.035079,
.001865,.035949,
-.004405,.035727,
-.010542,.034419,
-.016359,.032065,
-.01959,.0302,
-.01451,.02511,
0.0*
%
%ADD28MACRO28*%
%AMMACRO78*
4,1,15,.03682,.01914,
.039584,.012455,
.041146,.005393,
.041457,-.001834,
.040509,-.009005,
.03833,-.015903,
.03682,-.01914,
.04197,-.0243,
.045552,-.016643,
.04775,-.00848,
.048497,-.000059,
.047771,.008363,
.045593,.016531,
.042029,.024197,
.04197,.0243,
.03682,.01914,
0.0*
4,1,15,.01914,-.03682,
.012455,-.039584,
.005393,-.041146,
-.001834,-.041457,
-.009005,-.040509,
-.015903,-.03833,
-.01914,-.03682,
-.0243,-.04197,
-.016643,-.045552,
-.00848,-.04775,
-.000059,-.048497,
.008363,-.047771,
.016531,-.045593,
.024197,-.042029,
.0243,-.04197,
.01914,-.03682,
0.0*
4,1,15,-.03682,-.01914,
-.039584,-.012455,
-.041146,-.005393,
-.041457,.001834,
-.040509,.009005,
-.03833,.015903,
-.03682,.01914,
-.04197,.0243,
-.045552,.016643,
-.04775,.00848,
-.048497,.000059,
-.047771,-.008363,
-.045593,-.016531,
-.042029,-.024197,
-.04197,-.0243,
-.03682,-.01914,
0.0*
4,1,15,-.01914,.03682,
-.012455,.039584,
-.005393,.041146,
.001834,.041457,
.009005,.040509,
.015903,.03833,
.01914,.03682,
.0243,.04197,
.016643,.045552,
.00848,.04775,
.000059,.048497,
-.008363,.047771,
-.016531,.045593,
-.024197,.042029,
-.0243,.04197,
-.01914,.03682,
0.0*
%
%ADD78MACRO78*%
%AMMACRO75*
4,1,15,-.03682,.01914,
-.039584,.012455,
-.041146,.005393,
-.041457,-.001834,
-.040509,-.009005,
-.03833,-.015903,
-.03682,-.01914,
-.04197,-.0243,
-.045552,-.016643,
-.04775,-.00848,
-.048497,-.000059,
-.047771,.008363,
-.045593,.016531,
-.042029,.024197,
-.04197,.0243,
-.03682,.01914,
0.0*
4,1,15,-.01914,-.03682,
-.012455,-.039584,
-.005393,-.041146,
.001834,-.041457,
.009005,-.040509,
.015903,-.03833,
.01914,-.03682,
.0243,-.04197,
.016643,-.045552,
.00848,-.04775,
.000059,-.048497,
-.008363,-.047771,
-.016531,-.045593,
-.024197,-.042029,
-.0243,-.04197,
-.01914,-.03682,
0.0*
4,1,15,.03682,-.01914,
.039584,-.012455,
.041146,-.005393,
.041457,.001834,
.040509,.009005,
.03833,.015903,
.03682,.01914,
.04197,.0243,
.045552,.016643,
.04775,.00848,
.048497,.000059,
.047771,-.008363,
.045593,-.016531,
.042029,-.024197,
.04197,-.0243,
.03682,-.01914,
0.0*
4,1,15,.01914,.03682,
.012455,.039584,
.005393,.041146,
-.001834,.041457,
-.009005,.040509,
-.015903,.03833,
-.01914,.03682,
-.0243,.04197,
-.016643,.045552,
-.00848,.04775,
-.000059,.048497,
.008363,.047771,
.016531,.045593,
.024197,.042029,
.0243,.04197,
.01914,.03682,
0.0*
%
%ADD75MACRO75*%
%AMMACRO23*
4,1,25,-.0605,.00499,
-.05909,.011105,
-.05664,.016881,
-.053224,.022145,
-.048946,.026736,
-.043935,.030513,
-.038345,.033364,
-.032345,.0352,
-.02985,.03564,
-.025195,.035958,
-.02422,.03599,
-.005,.03599,
-.005,.03099,
-.02474,.03099,
-.026534,.030943,
-.028322,.030793,
-.02985,.03058,
-.035086,.029247,
-.040011,.027025,
-.044475,.023982,
-.048343,.020209,
-.051497,.015823,
-.053842,.010955,
-.055305,.005754,
-.05544,.00499,
-.0605,.00499,
0.0*
4,1,27,.005,.03599,
.02451,.03599,
.026071,.035998,
.027631,.035916,
.029183,.035743,
.02985,.03564,
.035965,.03423,
.041741,.03178,
.047005,.028364,
.051596,.024086,
.055373,.019075,
.058224,.013485,
.06006,.007485,
.0605,.00499,
.05544,.00499,
.054107,.010226,
.051885,.015151,
.048842,.019615,
.045069,.023483,
.040683,.026637,
.035815,.028982,
.030614,.030445,
.02985,.03058,
.0281,.030818,
.02634,.030955,
.02482,.03099,
.005,.03099,
.005,.03599,
0.0*
4,1,25,-.0605,-.00501,
-.05544,-.00501,
-.054107,-.010246,
-.051885,-.015171,
-.048842,-.019635,
-.045069,-.023503,
-.040683,-.026657,
-.035815,-.029002,
-.030614,-.030465,
-.02985,-.0306,
-.028079,-.03084,
-.026298,-.030976,
-.02487,-.03101,
-.005,-.03101,
-.005,-.03601,
-.02375,-.03601,
-.028562,-.035772,
-.02985,-.03566,
-.035965,-.03425,
-.041741,-.0318,
-.047005,-.028384,
-.051596,-.024106,
-.055373,-.019095,
-.058224,-.013505,
-.06006,-.007505,
-.0605,-.00501,
0.0*
4,1,27,.005,-.03101,
.02485,-.03101,
.02659,-.030963,
.028324,-.030815,
.02985,-.0306,
.035086,-.029267,
.040011,-.027045,
.044475,-.024002,
.048343,-.020229,
.051497,-.015843,
.053842,-.010975,
.055305,-.005774,
.05544,-.00501,
.0605,-.00501,
.05909,-.011125,
.05664,-.016901,
.053224,-.022165,
.048946,-.026756,
.043935,-.030533,
.038345,-.033384,
.032345,-.03522,
.02985,-.03566,
.028758,-.035841,
.027658,-.035958,
.026553,-.036011,
.02578,-.03601,
.005,-.03601,
.005,-.03101,
0.0*
%
%ADD23MACRO23*%
%ADD61R,.285X.23*%
%ADD68C,.142*%
%AMMACRO62*
4,1,36,0.0,.01,
-.001736,.009848,
-.00342,.009397,
-.005,.00866,
-.006428,.00766,
-.00766,.006428,
-.00866,.005,
-.009397,.00342,
-.009848,.001736,
-.01,0.0,
-.009848,-.001736,
-.009397,-.00342,
-.00866,-.005,
-.00766,-.006428,
-.006428,-.00766,
-.005,-.00866,
-.00342,-.009397,
-.001736,-.009848,
0.0,-.01,
.001736,-.009848,
.00342,-.009397,
.005,-.00866,
.006428,-.00766,
.00766,-.006428,
.00866,-.005,
.009397,-.00342,
.009848,-.001736,
.01,0.0,
.009848,.001736,
.009397,.00342,
.00866,.005,
.00766,.006428,
.006428,.00766,
.005,.00866,
.00342,.009397,
.001736,.009848,
0.0,.01,
180.*
%
%ADD62MACRO62*%
%ADD33O,.219X.156*%
%ADD13C,.125*%
%AMMACRO69*
4,1,36,.0025,0.0,
.002462,.000434,
.002349,.000855,
.002165,.00125,
.001915,.001607,
.001607,.001915,
.00125,.002165,
.000855,.002349,
.000434,.002462,
0.0,.0025,
-.000434,.002462,
-.000855,.002349,
-.00125,.002165,
-.001607,.001915,
-.001915,.001607,
-.002165,.00125,
-.002349,.000855,
-.002462,.000434,
-.0025,0.0,
-.002462,-.000434,
-.002349,-.000855,
-.002165,-.00125,
-.001915,-.001607,
-.001607,-.001915,
-.00125,-.002165,
-.000855,-.002349,
-.000434,-.002462,
0.0,-.0025,
.000434,-.002462,
.000855,-.002349,
.00125,-.002165,
.001607,-.001915,
.001915,-.001607,
.002165,-.00125,
.002349,-.000855,
.002462,-.000434,
.0025,0.0,
30.*
%
%ADD69MACRO69*%
%ADD18C,.424*%
%ADD21C,.155*%
%ADD54C,.291*%
%ADD39C,.165*%
%ADD56C,.247*%
%ADD45C,.256*%
%AMMACRO34*
4,1,36,0.0,.0085,
.001476,.008371,
.002907,.007987,
.00425,.007361,
.005464,.006511,
.006511,.005464,
.007361,.00425,
.007987,.002907,
.008371,.001476,
.0085,0.0,
.008371,-.001476,
.007987,-.002907,
.007361,-.00425,
.006511,-.005464,
.005464,-.006511,
.00425,-.007361,
.002907,-.007987,
.001476,-.008371,
0.0,-.0085,
-.001476,-.008371,
-.002907,-.007987,
-.00425,-.007361,
-.005464,-.006511,
-.006511,-.005464,
-.007361,-.00425,
-.007987,-.002907,
-.008371,-.001476,
-.0085,0.0,
-.008371,.001476,
-.007987,.002907,
-.007361,.00425,
-.006511,.005464,
-.005464,.006511,
-.00425,.007361,
-.002907,.007987,
-.001476,.008371,
0.0,.0085,
180.*
%
%ADD34MACRO34*%
%AMMACRO60*
4,1,20,-.0075,-.05555,
-.0075,-.06273,
-.013677,-.060878,
-.019439,-.057981,
-.024611,-.054127,
-.029034,-.049434,
-.032576,-.044045,
-.035127,-.038122,
-.036612,-.031846,
-.037,-.0265,
-.037,-.0075,
-.03,-.0075,
-.03,-.0265,
-.029544,-.03171,
-.028191,-.036762,
-.02598,-.041502,
-.022981,-.045786,
-.019282,-.049484,
-.014998,-.052484,
-.010258,-.054694,
-.0075,-.05555,
90.*
4,1,20,.0075,-.06273,
.0075,-.05555,
.01243,-.053806,
.016983,-.051232,
.02102,-.047906,
.024418,-.043931,
.027073,-.039425,
.028906,-.034527,
.029861,-.029385,
.03,-.0265,
.03,-.0075,
.037,-.0075,
.037,-.0265,
.036438,-.032925,
.034769,-.039154,
.032043,-.044999,
.028344,-.050282,
.023784,-.054842,
.018501,-.058541,
.012656,-.061266,
.0075,-.06273,
90.*
4,1,20,-.0075,.06273,
-.0075,.05555,
-.01243,.053806,
-.016983,.051232,
-.02102,.047906,
-.024418,.043931,
-.027073,.039425,
-.028906,.034527,
-.029861,.029385,
-.03,.0265,
-.03,.0075,
-.037,.0075,
-.037,.0265,
-.036438,.032925,
-.034769,.039154,
-.032043,.044999,
-.028344,.050282,
-.023784,.054842,
-.018501,.058541,
-.012656,.061266,
-.0075,.06273,
90.*
4,1,20,.0075,.05555,
.0075,.06273,
.013677,.060878,
.019439,.057981,
.024611,.054127,
.029034,.049434,
.032576,.044045,
.035127,.038122,
.036612,.031846,
.037,.0265,
.037,.0075,
.03,.0075,
.03,.0265,
.029544,.03171,
.028191,.036762,
.02598,.041502,
.022981,.045786,
.019282,.049484,
.014998,.052484,
.010258,.054694,
.0075,.05555,
90.*
%
%ADD60MACRO60*%
%AMMACRO20*
4,1,36,.0025,0.0,
.002462,.000434,
.002349,.000855,
.002165,.00125,
.001915,.001607,
.001607,.001915,
.00125,.002165,
.000855,.002349,
.000434,.002462,
0.0,.0025,
-.000434,.002462,
-.000855,.002349,
-.00125,.002165,
-.001607,.001915,
-.001915,.001607,
-.002165,.00125,
-.002349,.000855,
-.002462,.000434,
-.0025,0.0,
-.002462,-.000434,
-.002349,-.000855,
-.002165,-.00125,
-.001915,-.001607,
-.001607,-.001915,
-.00125,-.002165,
-.000855,-.002349,
-.000434,-.002462,
0.0,-.0025,
.000434,-.002462,
.000855,-.002349,
.00125,-.002165,
.001607,-.001915,
.001915,-.001607,
.002165,-.00125,
.002349,-.000855,
.002462,-.000434,
.0025,0.0,
90.*
%
%ADD20MACRO20*%
%AMMACRO57*
4,1,36,0.0,.019,
-.003299,.018711,
-.006498,.017854,
-.0095,.016454,
-.012213,.014555,
-.014555,.012213,
-.016454,.0095,
-.017854,.006498,
-.018711,.003299,
-.019,0.0,
-.018711,-.003299,
-.017854,-.006498,
-.016454,-.0095,
-.014555,-.012213,
-.012213,-.014555,
-.0095,-.016454,
-.006498,-.017854,
-.003299,-.018711,
0.0,-.019,
.003299,-.018711,
.006498,-.017854,
.0095,-.016454,
.012213,-.014555,
.014555,-.012213,
.016454,-.0095,
.017854,-.006498,
.018711,-.003299,
.019,0.0,
.018711,.003299,
.017854,.006498,
.016454,.0095,
.014555,.012213,
.012213,.014555,
.0095,.016454,
.006498,.017854,
.003299,.018711,
0.0,.019,
270.*
%
%ADD57MACRO57*%
%AMMACRO43*
4,1,36,.003,0.0,
.002954,.000521,
.002819,.001026,
.002598,.0015,
.002298,.001928,
.001928,.002298,
.0015,.002598,
.001026,.002819,
.000521,.002954,
0.0,.003,
-.000521,.002954,
-.001026,.002819,
-.0015,.002598,
-.001928,.002298,
-.002298,.001928,
-.002598,.0015,
-.002819,.001026,
-.002954,.000521,
-.003,0.0,
-.002954,-.000521,
-.002819,-.001026,
-.002598,-.0015,
-.002298,-.001928,
-.001928,-.002298,
-.0015,-.002598,
-.001026,-.002819,
-.000521,-.002954,
0.0,-.003,
.000521,-.002954,
.001026,-.002819,
.0015,-.002598,
.001928,-.002298,
.002298,-.001928,
.002598,-.0015,
.002819,-.001026,
.002954,-.000521,
.003,0.0,
90.*
%
%ADD43MACRO43*%
%AMMACRO12*
4,1,36,.0025,0.0,
.002462,.000434,
.002349,.000855,
.002165,.00125,
.001915,.001607,
.001607,.001915,
.00125,.002165,
.000855,.002349,
.000434,.002462,
0.0,.0025,
-.000434,.002462,
-.000855,.002349,
-.00125,.002165,
-.001607,.001915,
-.001915,.001607,
-.002165,.00125,
-.002349,.000855,
-.002462,.000434,
-.0025,0.0,
-.002462,-.000434,
-.002349,-.000855,
-.002165,-.00125,
-.001915,-.001607,
-.001607,-.001915,
-.00125,-.002165,
-.000855,-.002349,
-.000434,-.002462,
0.0,-.0025,
.000434,-.002462,
.000855,-.002349,
.00125,-.002165,
.001607,-.001915,
.001915,-.001607,
.002165,-.00125,
.002349,-.000855,
.002462,-.000434,
.0025,0.0,
0.0*
%
%ADD12MACRO12*%
%AMMACRO72*
4,1,36,-.003,0.0,
-.002954,.000521,
-.002819,.001026,
-.002598,.0015,
-.002298,.001928,
-.001928,.002298,
-.0015,.002598,
-.001026,.002819,
-.000521,.002954,
0.0,.003,
.000521,.002954,
.001026,.002819,
.0015,.002598,
.001928,.002298,
.002298,.001928,
.002598,.0015,
.002819,.001026,
.002954,.000521,
.003,0.0,
.002954,-.000521,
.002819,-.001026,
.002598,-.0015,
.002298,-.001928,
.001928,-.002298,
.0015,-.002598,
.001026,-.002819,
.000521,-.002954,
0.0,-.003,
-.000521,-.002954,
-.001026,-.002819,
-.0015,-.002598,
-.001928,-.002298,
-.002298,-.001928,
-.002598,-.0015,
-.002819,-.001026,
-.002954,-.000521,
-.003,0.0,
90.*
%
%ADD72MACRO72*%
%AMMACRO64*
4,1,36,-.0025,0.0,
-.002462,.000434,
-.002349,.000855,
-.002165,.00125,
-.001915,.001607,
-.001607,.001915,
-.00125,.002165,
-.000855,.002349,
-.000434,.002462,
0.0,.0025,
.000434,.002462,
.000855,.002349,
.00125,.002165,
.001607,.001915,
.001915,.001607,
.002165,.00125,
.002349,.000855,
.002462,.000434,
.0025,0.0,
.002462,-.000434,
.002349,-.000855,
.002165,-.00125,
.001915,-.001607,
.001607,-.001915,
.00125,-.002165,
.000855,-.002349,
.000434,-.002462,
0.0,-.0025,
-.000434,-.002462,
-.000855,-.002349,
-.00125,-.002165,
-.001607,-.001915,
-.001915,-.001607,
-.002165,-.00125,
-.002349,-.000855,
-.002462,-.000434,
-.0025,0.0,
0.0*
%
%ADD64MACRO64*%
%ADD58C,.188*%
%AMMACRO16*
4,1,36,.003,0.0,
.002954,.000521,
.002819,.001026,
.002598,.0015,
.002298,.001928,
.001928,.002298,
.0015,.002598,
.001026,.002819,
.000521,.002954,
0.0,.003,
-.000521,.002954,
-.001026,.002819,
-.0015,.002598,
-.001928,.002298,
-.002298,.001928,
-.002598,.0015,
-.002819,.001026,
-.002954,.000521,
-.003,0.0,
-.002954,-.000521,
-.002819,-.001026,
-.002598,-.0015,
-.002298,-.001928,
-.001928,-.002298,
-.0015,-.002598,
-.001026,-.002819,
-.000521,-.002954,
0.0,-.003,
.000521,-.002954,
.001026,-.002819,
.0015,-.002598,
.001928,-.002298,
.002298,-.001928,
.002598,-.0015,
.002819,-.001026,
.002954,-.000521,
.003,0.0,
0.0*
%
%ADD16MACRO16*%
%AMMACRO25*
4,1,16,.02584,.01524,
.028094,.010521,
.029494,.005483,
.029998,.000278,
.029591,-.004935,
.028284,-.009999,
.026118,-.014758,
.02584,-.01524,
.03092,-.02032,
.033979,-.014642,
.036005,-.008519,
.036938,-.002138,
.036748,.004309,
.035441,.010625,
.033058,.016618,
.03092,.02032,
.02584,.01524,
180.*
4,1,16,.01524,-.02584,
.010521,-.028094,
.005483,-.029494,
.000278,-.029998,
-.004935,-.029591,
-.009999,-.028284,
-.014758,-.026118,
-.01524,-.02584,
-.02032,-.03092,
-.014642,-.033979,
-.008519,-.036005,
-.002138,-.036938,
.004309,-.036748,
.010625,-.035441,
.016618,-.033058,
.02032,-.03092,
.01524,-.02584,
180.*
4,1,16,-.02584,-.01524,
-.028094,-.010521,
-.029494,-.005483,
-.029998,-.000278,
-.029591,.004935,
-.028284,.009999,
-.026118,.014758,
-.02584,.01524,
-.03092,.02032,
-.033979,.014642,
-.036005,.008519,
-.036938,.002138,
-.036748,-.004309,
-.035441,-.010625,
-.033058,-.016618,
-.03092,-.02032,
-.02584,-.01524,
180.*
4,1,16,-.01524,.02584,
-.010521,.028094,
-.005483,.029494,
-.000278,.029998,
.004935,.029591,
.009999,.028284,
.014758,.026118,
.01524,.02584,
.02032,.03092,
.014642,.033979,
.008519,.036005,
.002138,.036938,
-.004309,.036748,
-.010625,.035441,
-.016618,.033058,
-.02032,.03092,
-.01524,.02584,
180.*
%
%ADD25MACRO25*%
%AMMACRO65*
4,1,15,.02438,.01377,
.026401,.009327,
.027619,.004601,
.027999,-.000265,
.027527,-.005123,
.02622,-.009825,
.02438,-.01377,
.02948,-.01887,
.032309,-.013464,
.034156,-.007649,
.034965,-.001602,
.034712,.004494,
.033405,.010454,
.031082,.016095,
.02948,.01887,
.02438,.01377,
270.*
4,1,15,.01377,-.02438,
.009327,-.026401,
.004601,-.027619,
-.000265,-.027999,
-.005123,-.027527,
-.009825,-.02622,
-.01377,-.02438,
-.01887,-.02948,
-.013464,-.032309,
-.007649,-.034156,
-.001602,-.034965,
.004494,-.034712,
.010454,-.033405,
.016095,-.031082,
.01887,-.02948,
.01377,-.02438,
270.*
4,1,15,-.02438,-.01377,
-.026401,-.009327,
-.027619,-.004601,
-.027999,.000265,
-.027527,.005123,
-.02622,.009825,
-.02438,.01377,
-.02948,.01887,
-.032309,.013464,
-.034156,.007649,
-.034965,.001602,
-.034712,-.004494,
-.033405,-.010454,
-.031082,-.016095,
-.02948,-.01887,
-.02438,-.01377,
270.*
4,1,15,-.01377,.02438,
-.009327,.026401,
-.004601,.027619,
.000265,.027999,
.005123,.027527,
.009825,.02622,
.01377,.02438,
.01887,.02948,
.013464,.032309,
.007649,.034156,
.001602,.034965,
-.004494,.034712,
-.010454,.033405,
-.016095,.031082,
-.01887,.02948,
-.01377,.02438,
270.*
%
%ADD65MACRO65*%
%AMMACRO70*
4,1,15,.02475,.01414,
.026829,.009627,
.028094,.004822,
.028504,-.000129,
.028049,-.005077,
.026741,-.009871,
.02475,-.01414,
.02984,-.01923,
.032726,-.013756,
.034617,-.007864,
.035457,-.001734,
.03522,.00445,
.033912,.010498,
.031574,.016227,
.02984,.01923,
.02475,.01414,
180.*
4,1,15,.01414,-.02475,
.009627,-.026829,
.004822,-.028094,
-.000129,-.028504,
-.005077,-.028049,
-.009871,-.026741,
-.01414,-.02475,
-.01923,-.02984,
-.013756,-.032726,
-.007864,-.034617,
-.001734,-.035457,
.00445,-.03522,
.010498,-.033912,
.016227,-.031574,
.01923,-.02984,
.01414,-.02475,
180.*
4,1,15,-.02475,-.01414,
-.026829,-.009627,
-.028094,-.004822,
-.028504,.000129,
-.028049,.005077,
-.026741,.009871,
-.02475,.01414,
-.02984,.01923,
-.032726,.013756,
-.034617,.007864,
-.035457,.001734,
-.03522,-.00445,
-.033912,-.010498,
-.031574,-.016227,
-.02984,-.01923,
-.02475,-.01414,
180.*
4,1,15,-.01414,.02475,
-.009627,.026829,
-.004822,.028094,
.000129,.028504,
.005077,.028049,
.009871,.026741,
.01414,.02475,
.01923,.02984,
.013756,.032726,
.007864,.034617,
.001734,.035457,
-.00445,.03522,
-.010498,.033912,
-.016227,.031574,
-.01923,.02984,
-.01414,.02475,
180.*
%
%ADD70MACRO70*%
%AMMACRO47*
4,1,15,.02475,.01414,
.026829,.009627,
.028094,.004822,
.028504,-.000129,
.028049,-.005077,
.026741,-.009871,
.02475,-.01414,
.02984,-.01923,
.032726,-.013756,
.034617,-.007864,
.035457,-.001734,
.03522,.00445,
.033912,.010498,
.031574,.016227,
.02984,.01923,
.02475,.01414,
270.*
4,1,15,.01414,-.02475,
.009627,-.026829,
.004822,-.028094,
-.000129,-.028504,
-.005077,-.028049,
-.009871,-.026741,
-.01414,-.02475,
-.01923,-.02984,
-.013756,-.032726,
-.007864,-.034617,
-.001734,-.035457,
.00445,-.03522,
.010498,-.033912,
.016227,-.031574,
.01923,-.02984,
.01414,-.02475,
270.*
4,1,15,-.02475,-.01414,
-.026829,-.009627,
-.028094,-.004822,
-.028504,.000129,
-.028049,.005077,
-.026741,.009871,
-.02475,.01414,
-.02984,.01923,
-.032726,.013756,
-.034617,.007864,
-.035457,.001734,
-.03522,-.00445,
-.033912,-.010498,
-.031574,-.016227,
-.02984,-.01923,
-.02475,-.01414,
270.*
4,1,15,-.01414,.02475,
-.009627,.026829,
-.004822,.028094,
.000129,.028504,
.005077,.028049,
.009871,.026741,
.01414,.02475,
.01923,.02984,
.013756,.032726,
.007864,.034617,
.001734,.035457,
-.00445,.03522,
-.010498,.033912,
-.016227,.031574,
-.01923,.02984,
-.01414,.02475,
270.*
%
%ADD47MACRO47*%
%AMMACRO59*
4,1,15,.04124,.02356,
.044705,.016041,
.046811,.008034,
.047495,-.000216,
.046736,-.008461,
.044557,-.016448,
.04124,-.02356,
.04635,-.02867,
.050624,-.020186,
.05336,-.011088,
.054475,-.001654,
.053935,.007831,
.051756,.017077,
.048004,.025805,
.04635,.02867,
.04124,.02356,
0.0*
4,1,15,.02356,-.04124,
.016041,-.044705,
.008034,-.046811,
-.000216,-.047495,
-.008461,-.046736,
-.016448,-.044557,
-.02356,-.04124,
-.02867,-.04635,
-.020186,-.050624,
-.011088,-.05336,
-.001654,-.054475,
.007831,-.053935,
.017077,-.051756,
.025805,-.048004,
.02867,-.04635,
.02356,-.04124,
0.0*
4,1,15,-.04124,-.02356,
-.044705,-.016041,
-.046811,-.008034,
-.047495,.000216,
-.046736,.008461,
-.044557,.016448,
-.04124,.02356,
-.04635,.02867,
-.050624,.020186,
-.05336,.011088,
-.054475,.001654,
-.053935,-.007831,
-.051756,-.017077,
-.048004,-.025805,
-.04635,-.02867,
-.04124,-.02356,
0.0*
4,1,15,-.02356,.04124,
-.016041,.044705,
-.008034,.046811,
.000216,.047495,
.008461,.046736,
.016448,.044557,
.02356,.04124,
.02867,.04635,
.020186,.050624,
.011088,.05336,
.001654,.054475,
-.007831,.053935,
-.017077,.051756,
-.025805,.048004,
-.02867,.04635,
-.02356,.04124,
0.0*
%
%ADD59MACRO59*%
%AMMACRO79*
4,1,15,.03682,.01914,
.039584,.012455,
.041146,.005393,
.041457,-.001834,
.040509,-.009005,
.03833,-.015903,
.03682,-.01914,
.04197,-.0243,
.045552,-.016643,
.04775,-.00848,
.048497,-.000059,
.047771,.008363,
.045593,.016531,
.042029,.024197,
.04197,.0243,
.03682,.01914,
180.*
4,1,15,.01914,-.03682,
.012455,-.039584,
.005393,-.041146,
-.001834,-.041457,
-.009005,-.040509,
-.015903,-.03833,
-.01914,-.03682,
-.0243,-.04197,
-.016643,-.045552,
-.00848,-.04775,
-.000059,-.048497,
.008363,-.047771,
.016531,-.045593,
.024197,-.042029,
.0243,-.04197,
.01914,-.03682,
180.*
4,1,15,-.03682,-.01914,
-.039584,-.012455,
-.041146,-.005393,
-.041457,.001834,
-.040509,.009005,
-.03833,.015903,
-.03682,.01914,
-.04197,.0243,
-.045552,.016643,
-.04775,.00848,
-.048497,.000059,
-.047771,-.008363,
-.045593,-.016531,
-.042029,-.024197,
-.04197,-.0243,
-.03682,-.01914,
180.*
4,1,15,-.01914,.03682,
-.012455,.039584,
-.005393,.041146,
.001834,.041457,
.009005,.040509,
.015903,.03833,
.01914,.03682,
.0243,.04197,
.016643,.045552,
.00848,.04775,
.000059,.048497,
-.008363,.047771,
-.016531,.045593,
-.024197,.042029,
-.0243,.04197,
-.01914,.03682,
180.*
%
%ADD79MACRO79*%
%AMMACRO77*
4,1,15,-.03682,.01914,
-.039584,.012455,
-.041146,.005393,
-.041457,-.001834,
-.040509,-.009005,
-.03833,-.015903,
-.03682,-.01914,
-.04197,-.0243,
-.045552,-.016643,
-.04775,-.00848,
-.048497,-.000059,
-.047771,.008363,
-.045593,.016531,
-.042029,.024197,
-.04197,.0243,
-.03682,.01914,
180.*
4,1,15,-.01914,-.03682,
-.012455,-.039584,
-.005393,-.041146,
.001834,-.041457,
.009005,-.040509,
.015903,-.03833,
.01914,-.03682,
.0243,-.04197,
.016643,-.045552,
.00848,-.04775,
.000059,-.048497,
-.008363,-.047771,
-.016531,-.045593,
-.024197,-.042029,
-.0243,-.04197,
-.01914,-.03682,
180.*
4,1,15,.03682,-.01914,
.039584,-.012455,
.041146,-.005393,
.041457,.001834,
.040509,.009005,
.03833,.015903,
.03682,.01914,
.04197,.0243,
.045552,.016643,
.04775,.00848,
.048497,.000059,
.047771,-.008363,
.045593,-.016531,
.042029,-.024197,
.04197,-.0243,
.03682,-.01914,
180.*
4,1,15,.01914,.03682,
.012455,.039584,
.005393,.041146,
-.001834,.041457,
-.009005,.040509,
-.015903,.03833,
-.01914,.03682,
-.0243,.04197,
-.016643,.045552,
-.00848,.04775,
-.000059,.048497,
.008363,.047771,
.016531,.045593,
.024197,.042029,
.0243,.04197,
.01914,.03682,
180.*
%
%ADD77MACRO77*%
%ADD80C,.006*%
%ADD105C,.04006*%
%ADD102C,.03016*%
%ADD98C,.03018*%
%ADD103C,.07008*%
%ADD83C,.07306*%
%ADD90C,.07208*%
%ADD94C,.07308*%
%ADD95C,.07608*%
%ADD93C,.07808*%
%ADD92C,.09708*%
%ADD89O,.1621X.2251*%
%ADD85C,.311*%
%ADD100C,.1621*%
%ADD82O,.03004X.06404*%
%ADD101C,.16211*%
%ADD97C,.1751*%
%ADD81O,.03006X.06406*%
%ADD96C,.43406*%
%ADD84C,.16506*%
%ADD91C,.25806*%
%ADD99C,.43376*%
%ADD104C,.19786*%
%ADD88O,.43374X.77626*%
%ADD86O,.43374X.69752*%
%ADD87O,.43376X.69754*%
G75*
%LPD*%
G75*
G36*
G01X-984580Y-698988D02*
X5868320D01*
Y4193602D01*
X-984580D01*
Y-698988D01*
G37*
%LPC*%
G75*
G36*
G01X1828062Y36504D02*
X1828081Y36500D01*
G03X1828470Y36462I388J1962D01*
G03X1828859Y36500I1J2000D01*
G01X1828878Y36504D01*
X1849606D01*
G02X1855480Y30630I0J-5874D01*
G01Y-40945D01*
G02X1849606Y-46819I-5874J0D01*
G01X7874D01*
G02X2000Y-40945I0J5874D01*
G01Y30630D01*
G02X7874Y36504I5874J0D01*
G01X35835D01*
G02X41709Y30630I0J-5874D01*
G01Y-3937D01*
G03X51583Y-13811I9874J0D01*
G01X321661D01*
G03X331535Y-3937I0J9874D01*
G01Y30630D01*
G02X337409Y36504I5874J0D01*
G01X480717D01*
G02X486591Y30630I0J-5874D01*
G01Y16850D01*
G03X496465Y6976I9874J0D01*
G01X766543D01*
G03X776417Y16850I0J9874D01*
G01Y30630D01*
G02X782291Y36504I5874J0D01*
G01X879134D01*
G03X889008Y46378I0J9874D01*
G01Y122824D01*
X895188Y129004D01*
X1002542D01*
X1009024Y122522D01*
Y46378D01*
G03X1018898Y36504I9874J0D01*
G01X1510244D01*
G02X1516118Y30630I0J-5874D01*
G01Y-3937D01*
G03X1525992Y-13811I9874J0D01*
G01X1796071D01*
G03X1805945Y-3937I0J9874D01*
G01Y30630D01*
G02X1811819Y36504I5874J0D01*
G01X1828062D01*
G37*
G36*
G01X1829886Y1650538D02*
X1829890D01*
Y1650237D01*
X1829888Y1650228D01*
G03X1829820Y1649712I1932J-517D01*
G03X1829886Y1649203I2000J1D01*
G01Y1612316D01*
G03X1832779Y1605332I9877J0D01*
G01X1839978Y1598133D01*
G02X1841697Y1593983I-4151J-4151D01*
G01Y326095D01*
G03X1844590Y319111I9878J1D01*
G01X1853757Y309944D01*
G02X1855476Y305794I-4151J-4151D01*
G01Y54252D01*
G02X1849606Y48382I-5870J0D01*
G01X1829186D01*
Y48378D01*
X1827844D01*
Y48382D01*
X1803945D01*
G03X1794067Y38504I0J-9878D01*
G01Y3937D01*
G02X1792134Y2004I-1933J0D01*
G01X1529929D01*
G02X1527996Y3937I0J1933D01*
G01Y38504D01*
G03X1518118Y48382I-9878J0D01*
G01X1026772D01*
G02X1020902Y54252I0J5870D01*
G01Y131004D01*
G03X1011024Y140882I-9878J0D01*
G01X887008D01*
G03X877130Y131004I0J-9878D01*
G01Y54252D01*
G02X871260Y48382I-5870J0D01*
G01X774417D01*
G03X764539Y38504I0J-9878D01*
G01Y24724D01*
G02X762606Y22791I-1933J0D01*
G01X500402D01*
G02X498469Y24724I0J1933D01*
G01Y38504D01*
G03X488591Y48382I-9878J0D01*
G01X329535D01*
G03X319657Y38504I0J-9878D01*
G01Y3937D01*
G02X317724Y2004I-1933J0D01*
G01X55520D01*
G02X53587Y3937I0J1933D01*
G01Y38504D01*
G03X43709Y48382I-9878J0D01*
G01X7874D01*
G02X2004Y54252I0J5870D01*
G01Y305794D01*
G02X3723Y309944I5870J-1D01*
G01X6985Y313206D01*
G03X9878Y320190I-6984J6984D01*
G01Y1588078D01*
G02X11597Y1592228I5870J-1D01*
G01X24701Y1605332D01*
G03X27595Y1612316I-6983J6985D01*
G01Y1732244D01*
G02X33465Y1738114I5870J0D01*
G01X765732D01*
Y1736890D01*
G03X769705Y1732917I3973J0D01*
G01X1087854D01*
G03X1091827Y1736890I0J3973D01*
G01Y1738114D01*
X1824016D01*
G02X1829886Y1732244I0J-5870D01*
G01Y1650538D01*
G37*
G36*
G01X1867354Y305795D02*
G03X1862156Y318343I-17746J-1D01*
G01X1855296Y325203D01*
G02X1853575Y329357I4153J4154D01*
G01Y1593984D01*
G03X1848377Y1606532I-17746J-1D01*
G01X1843484Y1611425D01*
G02X1841764Y1615579I4156J4154D01*
G01Y1732244D01*
G02X1847638Y1738118I5874J0D01*
G01X1857480D01*
G03X1867354Y1747992I0J9874D01*
G01Y1815072D01*
G02X1873228Y1820946I5874J0D01*
G01X2093700D01*
G02X2099574Y1815072I0J-5874D01*
G01Y1791450D01*
G02X2093700Y1785576I-5874J0D01*
G01X2031574D01*
G03X2021700Y1775702I0J-9874D01*
G01Y1229954D01*
G03X2031574Y1220080I9874J0D01*
G01X2093700D01*
G02X2099574Y1214206I0J-5874D01*
G01Y-40945D01*
G02X2093700Y-46819I-5874J0D01*
G01X1873228D01*
G02X1867354Y-40945I0J5874D01*
G01Y305795D01*
G37*
%LPD*%
G75*
G36*
G01X1758669Y52153D02*
G02X1760173Y50649I0J-1504D01*
G01Y50648D01*
G02X1760172Y50593I-1504J0D01*
G02X1758669Y49100I-1503J10D01*
G01X1755269D01*
G02X1753766Y50593I0J1503D01*
G02X1753765Y50648I1503J55D01*
G01Y50649D01*
G02X1755269Y52153I1504J0D01*
G02X1755620Y52112I2J-1504D01*
G01X1755643Y52106D01*
X1758295D01*
X1758318Y52112D01*
G02X1758669Y52153I349J-1463D01*
G37*
G36*
G01X1394374Y172851D02*
G02X1395334Y173198I960J-1154D01*
G01X1398734D01*
G02X1400236Y171696I0J-1502D01*
G02X1398743Y170194I-1502J0D01*
G02X1398182Y170076I-561J1276D01*
G02X1397656Y170179I0J1394D01*
G01X1397620Y170194D01*
X1395334D01*
G02X1394882Y170264I1J1502D01*
G02X1394184Y170076I-699J1206D01*
G01X1394182D01*
G02Y172864I0J1394D01*
G02X1394374Y172851I2J-1394D01*
G37*
G36*
G01X880168Y504762D02*
Y508162D01*
G02X881670Y509664I1502J0D01*
G02X882945Y508955I0J-1501D01*
G02X883184Y508142I-1265J-813D01*
G01Y508141D01*
G02X883173Y507963I-1504J4D01*
G01X883172Y507952D01*
Y504897D01*
X883173Y504888D01*
G02X883180Y504743I-1493J-145D01*
G01Y504742D01*
G02X881680Y503242I-1500J0D01*
G02X880398Y503963I0J1500D01*
G02X880168Y504762I1273J799D01*
G37*
G36*
G01X963269Y1556947D02*
G03X963539I135J148D01*
G02X965904Y1557866I2365J-2584D01*
G02X969115Y1555762I0J-3502D01*
G02X970504Y1554262I-115J-1500D01*
G02X969016Y1552758I-1504J0D01*
G02X965904Y1550862I-3112J1606D01*
G02X963539Y1551781I0J3503D01*
G03X963269I-135J-148D01*
G02X960904Y1550862I-2365J2584D01*
G02Y1557866I0J3502D01*
G02X963269Y1556947I0J-3503D01*
G37*
G36*
G01X1010001D02*
G03X1010271I135J148D01*
G02X1012636Y1557866I2365J-2584D01*
G02X1015849Y1555757I0J-3502D01*
G02X1016012Y1555766I164J-1495D01*
G02Y1552758I0J-1504D01*
G02X1015759Y1552779I-3J1504D01*
G02X1012636Y1550862I-3123J1585D01*
G02X1010271Y1551781I0J3503D01*
G03X1010001I-135J-148D01*
G02X1007636Y1550862I-2365J2584D01*
G02Y1557866I0J3502D01*
G02X1010001Y1556947I0J-3503D01*
G37*
G36*
G01X1056733D02*
G03X1057003I135J148D01*
G02X1059368Y1557866I2365J-2584D01*
G02X1062579Y1555762I0J-3502D01*
G02X1063968Y1554262I-115J-1500D01*
G02X1062480Y1552758I-1504J0D01*
G02X1059368Y1550862I-3112J1606D01*
G02X1057003Y1551781I0J3503D01*
G03X1056733I-135J-148D01*
G02X1054368Y1550862I-2365J2584D01*
G02Y1557866I0J3502D01*
G02X1056733Y1556947I0J-3503D01*
G37*
G36*
G01X1080099D02*
G03X1080369I135J148D01*
G02X1082734Y1557866I2365J-2584D01*
G02X1085945Y1555762I0J-3502D01*
G02X1087334Y1554262I-115J-1500D01*
G02X1085846Y1552758I-1504J0D01*
G02X1082734Y1550862I-3112J1606D01*
G02X1080369Y1551781I0J3503D01*
G03X1080099I-135J-148D01*
G02X1077734Y1550862I-2365J2584D01*
G02Y1557866I0J3502D01*
G02X1080099Y1556947I0J-3503D01*
G37*
G36*
G01X986635D02*
G03X986905I135J148D01*
G02X989270Y1557866I2365J-2584D01*
G02X992481Y1555762I0J-3502D01*
G02X993966Y1554262I-15J-1500D01*
G02X992466Y1552762I-1500J0D01*
G02X992385Y1552764I-3J1500D01*
G02X989270Y1550862I-3115J1600D01*
G02X986905Y1551781I0J3503D01*
G03X986635I-135J-148D01*
G02X984270Y1550862I-2365J2584D01*
G02Y1557866I0J3502D01*
G02X986635Y1556947I0J-3503D01*
G37*
G36*
G01X1033367D02*
G03X1033637I135J148D01*
G02X1036002Y1557866I2365J-2584D01*
G02X1039214Y1555760I0J-3502D01*
G02X1039298Y1555762I78J-1498D01*
G02Y1552762I0J-1500D01*
G02X1039121Y1552772I-4J1500D01*
G02X1036002Y1550862I-3119J1592D01*
G02X1033637Y1551781I0J3503D01*
G03X1033367I-135J-148D01*
G02X1031002Y1550862I-2365J2584D01*
G02Y1557866I0J3502D01*
G02X1033367Y1556947I0J-3503D01*
G37*
G36*
G01X229206Y1656840D02*
X232906D01*
G02X233208Y1656537I-1J-303D01*
G01Y1646531D01*
G02X232906Y1646228I-302J-1D01*
G01X229206D01*
G02X228904Y1646531I1J303D01*
G01Y1648936D01*
G02X228890Y1649173I2002J237D01*
G02X228904Y1649410I2016J0D01*
G01Y1653660D01*
G02X228890Y1653897I2002J237D01*
G02X228904Y1654134I2016J0D01*
G01Y1656537D01*
G02X229206Y1656840I302J1D01*
G37*
G36*
G01X276450D02*
X280150D01*
G02X280452Y1656537I-1J-303D01*
G01Y1646531D01*
G02X280150Y1646228I-302J-1D01*
G01X276450D01*
G02X276148Y1646531I1J303D01*
G01Y1648936D01*
G02X276134Y1649173I2002J237D01*
G02X276148Y1649410I2016J0D01*
G01Y1653660D01*
G02X276134Y1653897I2002J237D01*
G02X276148Y1654134I2016J0D01*
G01Y1656537D01*
G02X276450Y1656840I302J1D01*
G37*
G36*
G01X237080Y1660776D02*
X240780D01*
G02X241082Y1660474I0J-302D01*
G01Y1650468D01*
G02X240780Y1650166I-302J0D01*
G01X237080D01*
G02X236778Y1650468I0J302D01*
G01Y1652873D01*
G02X236764Y1653110I2002J237D01*
G02X236778Y1653347I2016J0D01*
G01Y1657597D01*
G02X236764Y1657834I2002J237D01*
G02X236778Y1658071I2016J0D01*
G01Y1660474D01*
G02X237080Y1660776I302J0D01*
G37*
G36*
G01X268576D02*
X272276D01*
G02X272578Y1660474I0J-302D01*
G01Y1650468D01*
G02X272276Y1650166I-302J0D01*
G01X268576D01*
G02X268274Y1650468I0J302D01*
G01Y1652873D01*
G02X268260Y1653110I2002J237D01*
G02X268274Y1653347I2016J0D01*
G01Y1657597D01*
G02X268260Y1657834I2002J237D01*
G02X268274Y1658071I2016J0D01*
G01Y1660474D01*
G02X268576Y1660776I302J0D01*
G37*
G36*
G01X284324D02*
X288024D01*
G02X288326Y1660474I0J-302D01*
G01Y1650468D01*
G02X288024Y1650166I-302J0D01*
G01X284324D01*
G02X284022Y1650468I0J302D01*
G01Y1652873D01*
G02X284008Y1653110I2002J237D01*
G02X284022Y1653347I2016J0D01*
G01Y1657597D01*
G02X284008Y1657834I2002J237D01*
G02X284022Y1658071I2016J0D01*
G01Y1660474D01*
G02X284324Y1660776I302J0D01*
G37*
G36*
G01X229206Y1671014D02*
X232906D01*
G02X233208Y1670711I-1J-303D01*
G01Y1660705D01*
G02X232906Y1660402I-302J-1D01*
G01X229206D01*
G02X228904Y1660705I1J303D01*
G01Y1663109D01*
G02X228890Y1663346I2002J237D01*
G02X228904Y1663583I2016J0D01*
G01Y1667833D01*
G02X228890Y1668070I2002J237D01*
G02X228904Y1668307I2016J0D01*
G01Y1670711D01*
G02X229206Y1671014I302J1D01*
G37*
G36*
G01X244954D02*
X248654D01*
G02X248956Y1670711I-1J-303D01*
G01Y1660705D01*
G02X248654Y1660402I-302J-1D01*
G01X244954D01*
G02X244652Y1660705I1J303D01*
G01Y1663109D01*
G02X244638Y1663346I2002J237D01*
G02X244652Y1663583I2016J0D01*
G01Y1667833D01*
G02X244638Y1668070I2002J237D01*
G02X244652Y1668307I2016J0D01*
G01Y1670711D01*
G02X244954Y1671014I302J1D01*
G37*
G36*
G01X276450D02*
X280150D01*
G02X280452Y1670711I-1J-303D01*
G01Y1660705D01*
G02X280150Y1660402I-302J-1D01*
G01X276450D01*
G02X276148Y1660705I1J303D01*
G01Y1663109D01*
G02X276134Y1663346I2002J237D01*
G02X276148Y1663583I2016J0D01*
G01Y1667833D01*
G02X276134Y1668070I2002J237D01*
G02X276148Y1668307I2016J0D01*
G01Y1670711D01*
G02X276450Y1671014I302J1D01*
G37*
G36*
G01X252828Y1674950D02*
X256528D01*
G02X256830Y1674648I0J-302D01*
G01Y1664642D01*
G02X256528Y1664340I-302J0D01*
G01X252828D01*
G02X252526Y1664642I0J302D01*
G01Y1667046D01*
G02X252512Y1667283I2002J237D01*
G02X252526Y1667520I2016J0D01*
G01Y1671770D01*
G02X252512Y1672007I2002J237D01*
G02X252526Y1672244I2016J0D01*
G01Y1674648D01*
G02X252828Y1674950I302J0D01*
G37*
G36*
G01X268576D02*
X272276D01*
G02X272578Y1674648I0J-302D01*
G01Y1664642D01*
G02X272276Y1664340I-302J0D01*
G01X268576D01*
G02X268274Y1664642I0J302D01*
G01Y1667046D01*
G02X268260Y1667283I2002J237D01*
G02X268274Y1667520I2016J0D01*
G01Y1671770D01*
G02X268260Y1672007I2002J237D01*
G02X268274Y1672244I2016J0D01*
G01Y1674648D01*
G02X268576Y1674950I302J0D01*
G37*
G36*
G01X284324D02*
X288024D01*
G02X288326Y1674648I0J-302D01*
G01Y1664642D01*
G02X288024Y1664340I-302J0D01*
G01X284324D01*
G02X284022Y1664642I0J302D01*
G01Y1667046D01*
G02X284008Y1667283I2002J237D01*
G02X284022Y1667520I2016J0D01*
G01Y1671770D01*
G02X284008Y1672007I2002J237D01*
G02X284022Y1672244I2016J0D01*
G01Y1674648D01*
G02X284324Y1674950I302J0D01*
G37*
G36*
G01X229206Y1685186D02*
X232906D01*
G02X233208Y1684884I0J-302D01*
G01Y1674878D01*
G02X232906Y1674576I-302J0D01*
G01X229206D01*
G02X228904Y1674878I0J302D01*
G01Y1677282D01*
G02X228890Y1677519I2002J237D01*
G02X228904Y1677756I2016J0D01*
G01Y1682007D01*
G02X228890Y1682244I2002J237D01*
G02X228904Y1682481I2016J0D01*
G01Y1684884D01*
G02X229206Y1685186I302J0D01*
G37*
G36*
G01X244954D02*
X248654D01*
G02X248956Y1684884I0J-302D01*
G01Y1674878D01*
G02X248654Y1674576I-302J0D01*
G01X244954D01*
G02X244652Y1674878I0J302D01*
G01Y1677282D01*
G02X244638Y1677519I2002J237D01*
G02X244652Y1677756I2016J0D01*
G01Y1682007D01*
G02X244638Y1682244I2002J237D01*
G02X244652Y1682481I2016J0D01*
G01Y1684884D01*
G02X244954Y1685186I302J0D01*
G37*
G36*
G01X260702D02*
X264402D01*
G02X264704Y1684884I0J-302D01*
G01Y1674878D01*
G02X264402Y1674576I-302J0D01*
G01X260702D01*
G02X260400Y1674878I0J302D01*
G01Y1677282D01*
G02X260386Y1677519I2002J237D01*
G02X260400Y1677756I2016J0D01*
G01Y1682007D01*
G02X260386Y1682244I2002J237D01*
G02X260400Y1682481I2016J0D01*
G01Y1684884D01*
G02X260702Y1685186I302J0D01*
G37*
G36*
G01X276450D02*
X280150D01*
G02X280452Y1684884I0J-302D01*
G01Y1674878D01*
G02X280150Y1674576I-302J0D01*
G01X276450D01*
G02X276148Y1674878I0J302D01*
G01Y1677282D01*
G02X276134Y1677519I2002J237D01*
G02X276148Y1677756I2016J0D01*
G01Y1682007D01*
G02X276134Y1682244I2002J237D01*
G02X276148Y1682481I2016J0D01*
G01Y1684884D01*
G02X276450Y1685186I302J0D01*
G37*
G36*
G01X560308D02*
X564008D01*
G02X564310Y1684884I0J-302D01*
G01Y1674878D01*
G02X564008Y1674576I-302J0D01*
G01X560308D01*
G02X560006Y1674878I0J302D01*
G01Y1677282D01*
G02X559992Y1677519I2002J237D01*
G02X560006Y1677756I2016J0D01*
G01Y1682007D01*
G02X559992Y1682244I2002J237D01*
G02X560006Y1682481I2016J0D01*
G01Y1684884D01*
G02X560308Y1685186I302J0D01*
G37*
G36*
G01X576056D02*
X579756D01*
G02X580058Y1684884I0J-302D01*
G01Y1674878D01*
G02X579756Y1674576I-302J0D01*
G01X576056D01*
G02X575754Y1674878I0J302D01*
G01Y1677282D01*
G02X575740Y1677519I2002J237D01*
G02X575754Y1677756I2016J0D01*
G01Y1682007D01*
G02X575740Y1682244I2002J237D01*
G02X575754Y1682481I2016J0D01*
G01Y1684884D01*
G02X576056Y1685186I302J0D01*
G37*
G36*
G01X591804D02*
X595504D01*
G02X595806Y1684884I0J-302D01*
G01Y1674878D01*
G02X595504Y1674576I-302J0D01*
G01X591804D01*
G02X591502Y1674878I0J302D01*
G01Y1677282D01*
G02X591488Y1677519I2002J237D01*
G02X591502Y1677756I2016J0D01*
G01Y1682007D01*
G02X591488Y1682244I2002J237D01*
G02X591502Y1682481I2016J0D01*
G01Y1684884D01*
G02X591804Y1685186I302J0D01*
G37*
G36*
G01X607552D02*
X611252D01*
G02X611554Y1684884I0J-302D01*
G01Y1674878D01*
G02X611252Y1674576I-302J0D01*
G01X607552D01*
G02X607250Y1674878I0J302D01*
G01Y1677282D01*
G02X607236Y1677519I2002J237D01*
G02X607250Y1677756I2016J0D01*
G01Y1682007D01*
G02X607236Y1682244I2002J237D01*
G02X607250Y1682481I2016J0D01*
G01Y1684884D01*
G02X607552Y1685186I302J0D01*
G37*
G36*
G01X1237080D02*
X1240780D01*
G02X1241082Y1684884I0J-302D01*
G01Y1674878D01*
G02X1240780Y1674576I-302J0D01*
G01X1237080D01*
G02X1236778Y1674878I0J302D01*
G01Y1677282D01*
G02X1236764Y1677519I2002J237D01*
G02X1236778Y1677756I2016J0D01*
G01Y1682007D01*
G02X1236764Y1682244I2002J237D01*
G02X1236778Y1682481I2016J0D01*
G01Y1684884D01*
G02X1237080Y1685186I302J0D01*
G37*
G36*
G01X1252828D02*
X1256528D01*
G02X1256830Y1684884I0J-302D01*
G01Y1674878D01*
G02X1256528Y1674576I-302J0D01*
G01X1252828D01*
G02X1252526Y1674878I0J302D01*
G01Y1677282D01*
G02X1252512Y1677519I2002J237D01*
G02X1252526Y1677756I2016J0D01*
G01Y1682007D01*
G02X1252512Y1682244I2002J237D01*
G02X1252526Y1682481I2016J0D01*
G01Y1684884D01*
G02X1252828Y1685186I302J0D01*
G37*
G36*
G01X1268576D02*
X1272276D01*
G02X1272578Y1684884I0J-302D01*
G01Y1674878D01*
G02X1272276Y1674576I-302J0D01*
G01X1268576D01*
G02X1268274Y1674878I0J302D01*
G01Y1677282D01*
G02X1268260Y1677519I2002J237D01*
G02X1268274Y1677756I2016J0D01*
G01Y1682007D01*
G02X1268260Y1682244I2002J237D01*
G02X1268274Y1682481I2016J0D01*
G01Y1684884D01*
G02X1268576Y1685186I302J0D01*
G37*
G36*
G01X1284324D02*
X1288024D01*
G02X1288326Y1684884I0J-302D01*
G01Y1674878D01*
G02X1288024Y1674576I-302J0D01*
G01X1284324D01*
G02X1284022Y1674878I0J302D01*
G01Y1677282D01*
G02X1284008Y1677519I2002J237D01*
G02X1284022Y1677756I2016J0D01*
G01Y1682007D01*
G02X1284008Y1682244I2002J237D01*
G02X1284022Y1682481I2016J0D01*
G01Y1684884D01*
G02X1284324Y1685186I302J0D01*
G37*
G36*
G01X1568182D02*
X1571882D01*
G02X1572184Y1684884I0J-302D01*
G01Y1674878D01*
G02X1571882Y1674576I-302J0D01*
G01X1568182D01*
G02X1567880Y1674878I0J302D01*
G01Y1677282D01*
G02X1567866Y1677519I2002J237D01*
G02X1567880Y1677756I2016J0D01*
G01Y1682007D01*
G02X1567866Y1682244I2002J237D01*
G02X1567880Y1682481I2016J0D01*
G01Y1684884D01*
G02X1568182Y1685186I302J0D01*
G37*
G36*
G01X1583930D02*
X1587630D01*
G02X1587932Y1684884I0J-302D01*
G01Y1674878D01*
G02X1587630Y1674576I-302J0D01*
G01X1583930D01*
G02X1583628Y1674878I0J302D01*
G01Y1677282D01*
G02X1583614Y1677519I2002J237D01*
G02X1583628Y1677756I2016J0D01*
G01Y1682007D01*
G02X1583614Y1682244I2002J237D01*
G02X1583628Y1682481I2016J0D01*
G01Y1684884D01*
G02X1583930Y1685186I302J0D01*
G37*
G36*
G01X1599678D02*
X1603378D01*
G02X1603680Y1684884I0J-302D01*
G01Y1674878D01*
G02X1603378Y1674576I-302J0D01*
G01X1599678D01*
G02X1599376Y1674878I0J302D01*
G01Y1677282D01*
G02X1599362Y1677519I2002J237D01*
G02X1599376Y1677756I2016J0D01*
G01Y1682007D01*
G02X1599362Y1682244I2002J237D01*
G02X1599376Y1682481I2016J0D01*
G01Y1684884D01*
G02X1599678Y1685186I302J0D01*
G37*
G36*
G01X1615426D02*
X1619126D01*
G02X1619428Y1684884I0J-302D01*
G01Y1674878D01*
G02X1619126Y1674576I-302J0D01*
G01X1615426D01*
G02X1615124Y1674878I0J302D01*
G01Y1677282D01*
G02X1615110Y1677519I2002J237D01*
G02X1615124Y1677756I2016J0D01*
G01Y1682007D01*
G02X1615110Y1682244I2002J237D01*
G02X1615124Y1682481I2016J0D01*
G01Y1684884D01*
G02X1615426Y1685186I302J0D01*
G37*
G36*
G01X296135D02*
X299835D01*
G02X300138Y1684884I1J-302D01*
G01Y1674878D01*
G02X299835Y1674576I-303J1D01*
G01X296135D01*
G02X295832Y1674878I-1J302D01*
G01Y1677290D01*
G02X295819Y1677519I2003J229D01*
G02X295832Y1677748I2016J0D01*
G01Y1682015D01*
G02X295819Y1682244I2003J229D01*
G02X295832Y1682473I2016J0D01*
G01Y1684884D01*
G02X296135Y1685186I303J-1D01*
G37*
G36*
G01X311883D02*
X315583D01*
G02X315886Y1684884I1J-302D01*
G01Y1674878D01*
G02X315583Y1674576I-303J1D01*
G01X311883D01*
G02X311580Y1674878I-1J302D01*
G01Y1677290D01*
G02X311567Y1677519I2003J229D01*
G02X311580Y1677748I2016J0D01*
G01Y1682015D01*
G02X311567Y1682244I2003J229D01*
G02X311580Y1682473I2016J0D01*
G01Y1684884D01*
G02X311883Y1685186I303J-1D01*
G37*
G36*
G01X327631D02*
X331331D01*
G02X331634Y1684884I1J-302D01*
G01Y1674878D01*
G02X331331Y1674576I-303J1D01*
G01X327631D01*
G02X327328Y1674878I-1J302D01*
G01Y1677290D01*
G02X327315Y1677519I2003J229D01*
G02X327328Y1677748I2016J0D01*
G01Y1682015D01*
G02X327315Y1682244I2003J229D01*
G02X327328Y1682473I2016J0D01*
G01Y1684884D01*
G02X327631Y1685186I303J-1D01*
G37*
G36*
G01X343379D02*
X347079D01*
G02X347382Y1684884I1J-302D01*
G01Y1674878D01*
G02X347079Y1674576I-303J1D01*
G01X343379D01*
G02X343076Y1674878I-1J302D01*
G01Y1677290D01*
G02X343063Y1677519I2003J229D01*
G02X343076Y1677748I2016J0D01*
G01Y1682015D01*
G02X343063Y1682244I2003J229D01*
G02X343076Y1682473I2016J0D01*
G01Y1684884D01*
G02X343379Y1685186I303J-1D01*
G37*
G36*
G01X493379D02*
X497079D01*
G02X497382Y1684884I1J-302D01*
G01Y1674878D01*
G02X497079Y1674576I-303J1D01*
G01X493379D01*
G02X493076Y1674878I-1J302D01*
G01Y1677290D01*
G02X493063Y1677519I2003J229D01*
G02X493076Y1677748I2016J0D01*
G01Y1682015D01*
G02X493063Y1682244I2003J229D01*
G02X493076Y1682473I2016J0D01*
G01Y1684884D01*
G02X493379Y1685186I303J-1D01*
G37*
G36*
G01X509127D02*
X512827D01*
G02X513130Y1684884I1J-302D01*
G01Y1674878D01*
G02X512827Y1674576I-303J1D01*
G01X509127D01*
G02X508824Y1674878I-1J302D01*
G01Y1677290D01*
G02X508811Y1677519I2003J229D01*
G02X508824Y1677748I2016J0D01*
G01Y1682015D01*
G02X508811Y1682244I2003J229D01*
G02X508824Y1682473I2016J0D01*
G01Y1684884D01*
G02X509127Y1685186I303J-1D01*
G37*
G36*
G01X524875D02*
X528575D01*
G02X528878Y1684884I1J-302D01*
G01Y1674878D01*
G02X528575Y1674576I-303J1D01*
G01X524875D01*
G02X524572Y1674878I-1J302D01*
G01Y1677290D01*
G02X524559Y1677519I2003J229D01*
G02X524572Y1677748I2016J0D01*
G01Y1682015D01*
G02X524559Y1682244I2003J229D01*
G02X524572Y1682473I2016J0D01*
G01Y1684884D01*
G02X524875Y1685186I303J-1D01*
G37*
G36*
G01X540623D02*
X544323D01*
G02X544626Y1684884I1J-302D01*
G01Y1674878D01*
G02X544323Y1674576I-303J1D01*
G01X540623D01*
G02X540320Y1674878I-1J302D01*
G01Y1677290D01*
G02X540307Y1677519I2003J229D01*
G02X540320Y1677748I2016J0D01*
G01Y1682015D01*
G02X540307Y1682244I2003J229D01*
G02X540320Y1682473I2016J0D01*
G01Y1684884D01*
G02X540623Y1685186I303J-1D01*
G37*
G36*
G01X1304009D02*
X1307709D01*
G02X1308012Y1684884I1J-302D01*
G01Y1674878D01*
G02X1307709Y1674576I-303J1D01*
G01X1304009D01*
G02X1303706Y1674878I-1J302D01*
G01Y1677290D01*
G02X1303693Y1677519I2003J229D01*
G02X1303706Y1677748I2016J0D01*
G01Y1682015D01*
G02X1303693Y1682244I2003J229D01*
G02X1303706Y1682473I2016J0D01*
G01Y1684884D01*
G02X1304009Y1685186I303J-1D01*
G37*
G36*
G01X1319757D02*
X1323457D01*
G02X1323760Y1684884I1J-302D01*
G01Y1674878D01*
G02X1323457Y1674576I-303J1D01*
G01X1319757D01*
G02X1319454Y1674878I-1J302D01*
G01Y1677290D01*
G02X1319441Y1677519I2003J229D01*
G02X1319454Y1677748I2016J0D01*
G01Y1682015D01*
G02X1319441Y1682244I2003J229D01*
G02X1319454Y1682473I2016J0D01*
G01Y1684884D01*
G02X1319757Y1685186I303J-1D01*
G37*
G36*
G01X1335505D02*
X1339205D01*
G02X1339508Y1684884I1J-302D01*
G01Y1674878D01*
G02X1339205Y1674576I-303J1D01*
G01X1335505D01*
G02X1335202Y1674878I-1J302D01*
G01Y1677290D01*
G02X1335189Y1677519I2003J229D01*
G02X1335202Y1677748I2016J0D01*
G01Y1682015D01*
G02X1335189Y1682244I2003J229D01*
G02X1335202Y1682473I2016J0D01*
G01Y1684884D01*
G02X1335505Y1685186I303J-1D01*
G37*
G36*
G01X1351253D02*
X1354953D01*
G02X1355256Y1684884I1J-302D01*
G01Y1674878D01*
G02X1354953Y1674576I-303J1D01*
G01X1351253D01*
G02X1350950Y1674878I-1J302D01*
G01Y1677290D01*
G02X1350937Y1677519I2003J229D01*
G02X1350950Y1677748I2016J0D01*
G01Y1682015D01*
G02X1350937Y1682244I2003J229D01*
G02X1350950Y1682473I2016J0D01*
G01Y1684884D01*
G02X1351253Y1685186I303J-1D01*
G37*
G36*
G01X1501253D02*
X1504953D01*
G02X1505256Y1684884I1J-302D01*
G01Y1674878D01*
G02X1504953Y1674576I-303J1D01*
G01X1501253D01*
G02X1500950Y1674878I-1J302D01*
G01Y1677290D01*
G02X1500937Y1677519I2003J229D01*
G02X1500950Y1677748I2016J0D01*
G01Y1682015D01*
G02X1500937Y1682244I2003J229D01*
G02X1500950Y1682473I2016J0D01*
G01Y1684884D01*
G02X1501253Y1685186I303J-1D01*
G37*
G36*
G01X1517001D02*
X1520701D01*
G02X1521004Y1684884I1J-302D01*
G01Y1674878D01*
G02X1520701Y1674576I-303J1D01*
G01X1517001D01*
G02X1516698Y1674878I-1J302D01*
G01Y1677290D01*
G02X1516685Y1677519I2003J229D01*
G02X1516698Y1677748I2016J0D01*
G01Y1682015D01*
G02X1516685Y1682244I2003J229D01*
G02X1516698Y1682473I2016J0D01*
G01Y1684884D01*
G02X1517001Y1685186I303J-1D01*
G37*
G36*
G01X1532749D02*
X1536449D01*
G02X1536752Y1684884I1J-302D01*
G01Y1674878D01*
G02X1536449Y1674576I-303J1D01*
G01X1532749D01*
G02X1532446Y1674878I-1J302D01*
G01Y1677290D01*
G02X1532433Y1677519I2003J229D01*
G02X1532446Y1677748I2016J0D01*
G01Y1682015D01*
G02X1532433Y1682244I2003J229D01*
G02X1532446Y1682473I2016J0D01*
G01Y1684884D01*
G02X1532749Y1685186I303J-1D01*
G37*
G36*
G01X1548497D02*
X1552197D01*
G02X1552500Y1684884I1J-302D01*
G01Y1674878D01*
G02X1552197Y1674576I-303J1D01*
G01X1548497D01*
G02X1548194Y1674878I-1J302D01*
G01Y1677290D01*
G02X1548181Y1677519I2003J229D01*
G02X1548194Y1677748I2016J0D01*
G01Y1682015D01*
G02X1548181Y1682244I2003J229D01*
G02X1548194Y1682473I2016J0D01*
G01Y1684884D01*
G02X1548497Y1685186I303J-1D01*
G37*
G36*
G01X237080Y1689124D02*
X240780D01*
G02X241082Y1688821I-1J-303D01*
G01Y1678815D01*
G02X240780Y1678512I-302J-1D01*
G01X237080D01*
G02X236778Y1678815I1J303D01*
G01Y1681219D01*
G02X236764Y1681456I2002J237D01*
G02X236778Y1681693I2016J0D01*
G01Y1685943D01*
G02X236764Y1686180I2002J237D01*
G02X236778Y1686417I2016J0D01*
G01Y1688821D01*
G02X237080Y1689124I302J1D01*
G37*
G36*
G01X252828D02*
X256528D01*
G02X256830Y1688821I-1J-303D01*
G01Y1678815D01*
G02X256528Y1678512I-302J-1D01*
G01X252828D01*
G02X252526Y1678815I1J303D01*
G01Y1681219D01*
G02X252512Y1681456I2002J237D01*
G02X252526Y1681693I2016J0D01*
G01Y1685943D01*
G02X252512Y1686180I2002J237D01*
G02X252526Y1686417I2016J0D01*
G01Y1688821D01*
G02X252828Y1689124I302J1D01*
G37*
G36*
G01X268576D02*
X272276D01*
G02X272578Y1688821I-1J-303D01*
G01Y1678815D01*
G02X272276Y1678512I-302J-1D01*
G01X268576D01*
G02X268274Y1678815I1J303D01*
G01Y1681219D01*
G02X268260Y1681456I2002J237D01*
G02X268274Y1681693I2016J0D01*
G01Y1685943D01*
G02X268260Y1686180I2002J237D01*
G02X268274Y1686417I2016J0D01*
G01Y1688821D01*
G02X268576Y1689124I302J1D01*
G37*
G36*
G01X284324D02*
X288024D01*
G02X288326Y1688821I-1J-303D01*
G01Y1678815D01*
G02X288024Y1678512I-302J-1D01*
G01X284324D01*
G02X284022Y1678815I1J303D01*
G01Y1681219D01*
G02X284008Y1681456I2002J237D01*
G02X284022Y1681693I2016J0D01*
G01Y1685943D01*
G02X284008Y1686180I2002J237D01*
G02X284022Y1686417I2016J0D01*
G01Y1688821D01*
G02X284324Y1689124I302J1D01*
G37*
G36*
G01X304009D02*
X307709D01*
G02X308012Y1688821I0J-303D01*
G01Y1678815D01*
G02X307709Y1678512I-303J0D01*
G01X304009D01*
G02X303706Y1678815I0J303D01*
G01Y1681227D01*
G02X303693Y1681456I2003J229D01*
G02X303706Y1681685I2016J0D01*
G01Y1685951D01*
G02X303693Y1686180I2003J229D01*
G02X303706Y1686409I2016J0D01*
G01Y1688821D01*
G02X304009Y1689124I303J0D01*
G37*
G36*
G01X319757D02*
X323457D01*
G02X323760Y1688821I0J-303D01*
G01Y1678815D01*
G02X323457Y1678512I-303J0D01*
G01X319757D01*
G02X319454Y1678815I0J303D01*
G01Y1681227D01*
G02X319441Y1681456I2003J229D01*
G02X319454Y1681685I2016J0D01*
G01Y1685951D01*
G02X319441Y1686180I2003J229D01*
G02X319454Y1686409I2016J0D01*
G01Y1688821D01*
G02X319757Y1689124I303J0D01*
G37*
G36*
G01X335505D02*
X339205D01*
G02X339508Y1688821I0J-303D01*
G01Y1678815D01*
G02X339205Y1678512I-303J0D01*
G01X335505D01*
G02X335202Y1678815I0J303D01*
G01Y1681227D01*
G02X335189Y1681456I2003J229D01*
G02X335202Y1681685I2016J0D01*
G01Y1685951D01*
G02X335189Y1686180I2003J229D01*
G02X335202Y1686409I2016J0D01*
G01Y1688821D01*
G02X335505Y1689124I303J0D01*
G37*
G36*
G01X351253D02*
X354953D01*
G02X355256Y1688821I0J-303D01*
G01Y1678815D01*
G02X354953Y1678512I-303J0D01*
G01X351253D01*
G02X350950Y1678815I0J303D01*
G01Y1681227D01*
G02X350937Y1681456I2003J229D01*
G02X350950Y1681685I2016J0D01*
G01Y1685951D01*
G02X350937Y1686180I2003J229D01*
G02X350950Y1686409I2016J0D01*
G01Y1688821D01*
G02X351253Y1689124I303J0D01*
G37*
G36*
G01X501253D02*
X504953D01*
G02X505256Y1688821I0J-303D01*
G01Y1678815D01*
G02X504953Y1678512I-303J0D01*
G01X501253D01*
G02X500950Y1678815I0J303D01*
G01Y1681227D01*
G02X500937Y1681456I2003J229D01*
G02X500950Y1681685I2016J0D01*
G01Y1685951D01*
G02X500937Y1686180I2003J229D01*
G02X500950Y1686409I2016J0D01*
G01Y1688821D01*
G02X501253Y1689124I303J0D01*
G37*
G36*
G01X517001D02*
X520701D01*
G02X521004Y1688821I0J-303D01*
G01Y1678815D01*
G02X520701Y1678512I-303J0D01*
G01X517001D01*
G02X516698Y1678815I0J303D01*
G01Y1681227D01*
G02X516685Y1681456I2003J229D01*
G02X516698Y1681685I2016J0D01*
G01Y1685951D01*
G02X516685Y1686180I2003J229D01*
G02X516698Y1686409I2016J0D01*
G01Y1688821D01*
G02X517001Y1689124I303J0D01*
G37*
G36*
G01X532749D02*
X536449D01*
G02X536752Y1688821I0J-303D01*
G01Y1678815D01*
G02X536449Y1678512I-303J0D01*
G01X532749D01*
G02X532446Y1678815I0J303D01*
G01Y1681227D01*
G02X532433Y1681456I2003J229D01*
G02X532446Y1681685I2016J0D01*
G01Y1685951D01*
G02X532433Y1686180I2003J229D01*
G02X532446Y1686409I2016J0D01*
G01Y1688821D01*
G02X532749Y1689124I303J0D01*
G37*
G36*
G01X548497D02*
X552197D01*
G02X552500Y1688821I0J-303D01*
G01Y1678815D01*
G02X552197Y1678512I-303J0D01*
G01X548497D01*
G02X548194Y1678815I0J303D01*
G01Y1681227D01*
G02X548181Y1681456I2003J229D01*
G02X548194Y1681685I2016J0D01*
G01Y1685951D01*
G02X548181Y1686180I2003J229D01*
G02X548194Y1686409I2016J0D01*
G01Y1688821D01*
G02X548497Y1689124I303J0D01*
G37*
G36*
G01X568182D02*
X571882D01*
G02X572184Y1688821I-1J-303D01*
G01Y1678815D01*
G02X571882Y1678512I-302J-1D01*
G01X568182D01*
G02X567880Y1678815I1J303D01*
G01Y1681219D01*
G02X567866Y1681456I2002J237D01*
G02X567880Y1681693I2016J0D01*
G01Y1685943D01*
G02X567866Y1686180I2002J237D01*
G02X567880Y1686417I2016J0D01*
G01Y1688821D01*
G02X568182Y1689124I302J1D01*
G37*
G36*
G01X583930D02*
X587630D01*
G02X587932Y1688821I-1J-303D01*
G01Y1678815D01*
G02X587630Y1678512I-302J-1D01*
G01X583930D01*
G02X583628Y1678815I1J303D01*
G01Y1681219D01*
G02X583614Y1681456I2002J237D01*
G02X583628Y1681693I2016J0D01*
G01Y1685943D01*
G02X583614Y1686180I2002J237D01*
G02X583628Y1686417I2016J0D01*
G01Y1688821D01*
G02X583930Y1689124I302J1D01*
G37*
G36*
G01X599678D02*
X603378D01*
G02X603680Y1688821I-1J-303D01*
G01Y1678815D01*
G02X603378Y1678512I-302J-1D01*
G01X599678D01*
G02X599376Y1678815I1J303D01*
G01Y1681219D01*
G02X599362Y1681456I2002J237D01*
G02X599376Y1681693I2016J0D01*
G01Y1685943D01*
G02X599362Y1686180I2002J237D01*
G02X599376Y1686417I2016J0D01*
G01Y1688821D01*
G02X599678Y1689124I302J1D01*
G37*
G36*
G01X615426D02*
X619126D01*
G02X619428Y1688821I-1J-303D01*
G01Y1678815D01*
G02X619126Y1678512I-302J-1D01*
G01X615426D01*
G02X615124Y1678815I1J303D01*
G01Y1681219D01*
G02X615110Y1681456I2002J237D01*
G02X615124Y1681693I2016J0D01*
G01Y1685943D01*
G02X615110Y1686180I2002J237D01*
G02X615124Y1686417I2016J0D01*
G01Y1688821D01*
G02X615426Y1689124I302J1D01*
G37*
G36*
G01X1244954D02*
X1248654D01*
G02X1248956Y1688821I-1J-303D01*
G01Y1678815D01*
G02X1248654Y1678512I-302J-1D01*
G01X1244954D01*
G02X1244652Y1678815I1J303D01*
G01Y1681219D01*
G02X1244638Y1681456I2002J237D01*
G02X1244652Y1681693I2016J0D01*
G01Y1685943D01*
G02X1244638Y1686180I2002J237D01*
G02X1244652Y1686417I2016J0D01*
G01Y1688821D01*
G02X1244954Y1689124I302J1D01*
G37*
G36*
G01X1260702D02*
X1264402D01*
G02X1264704Y1688821I-1J-303D01*
G01Y1678815D01*
G02X1264402Y1678512I-302J-1D01*
G01X1260702D01*
G02X1260400Y1678815I1J303D01*
G01Y1681219D01*
G02X1260386Y1681456I2002J237D01*
G02X1260400Y1681693I2016J0D01*
G01Y1685943D01*
G02X1260386Y1686180I2002J237D01*
G02X1260400Y1686417I2016J0D01*
G01Y1688821D01*
G02X1260702Y1689124I302J1D01*
G37*
G36*
G01X1276450D02*
X1280150D01*
G02X1280452Y1688821I-1J-303D01*
G01Y1678815D01*
G02X1280150Y1678512I-302J-1D01*
G01X1276450D01*
G02X1276148Y1678815I1J303D01*
G01Y1681219D01*
G02X1276134Y1681456I2002J237D01*
G02X1276148Y1681693I2016J0D01*
G01Y1685943D01*
G02X1276134Y1686180I2002J237D01*
G02X1276148Y1686417I2016J0D01*
G01Y1688821D01*
G02X1276450Y1689124I302J1D01*
G37*
G36*
G01X1292198D02*
X1295898D01*
G02X1296200Y1688821I-1J-303D01*
G01Y1678815D01*
G02X1295898Y1678512I-302J-1D01*
G01X1292198D01*
G02X1291896Y1678815I1J303D01*
G01Y1681219D01*
G02X1291882Y1681456I2002J237D01*
G02X1291896Y1681693I2016J0D01*
G01Y1685943D01*
G02X1291882Y1686180I2002J237D01*
G02X1291896Y1686417I2016J0D01*
G01Y1688821D01*
G02X1292198Y1689124I302J1D01*
G37*
G36*
G01X1311883D02*
X1315583D01*
G02X1315886Y1688821I0J-303D01*
G01Y1678815D01*
G02X1315583Y1678512I-303J0D01*
G01X1311883D01*
G02X1311580Y1678815I0J303D01*
G01Y1681227D01*
G02X1311567Y1681456I2003J229D01*
G02X1311580Y1681685I2016J0D01*
G01Y1685951D01*
G02X1311567Y1686180I2003J229D01*
G02X1311580Y1686409I2016J0D01*
G01Y1688821D01*
G02X1311883Y1689124I303J0D01*
G37*
G36*
G01X1327631D02*
X1331331D01*
G02X1331634Y1688821I0J-303D01*
G01Y1678815D01*
G02X1331331Y1678512I-303J0D01*
G01X1327631D01*
G02X1327328Y1678815I0J303D01*
G01Y1681227D01*
G02X1327315Y1681456I2003J229D01*
G02X1327328Y1681685I2016J0D01*
G01Y1685951D01*
G02X1327315Y1686180I2003J229D01*
G02X1327328Y1686409I2016J0D01*
G01Y1688821D01*
G02X1327631Y1689124I303J0D01*
G37*
G36*
G01X1343379D02*
X1347079D01*
G02X1347382Y1688821I0J-303D01*
G01Y1678815D01*
G02X1347079Y1678512I-303J0D01*
G01X1343379D01*
G02X1343076Y1678815I0J303D01*
G01Y1681227D01*
G02X1343063Y1681456I2003J229D01*
G02X1343076Y1681685I2016J0D01*
G01Y1685951D01*
G02X1343063Y1686180I2003J229D01*
G02X1343076Y1686409I2016J0D01*
G01Y1688821D01*
G02X1343379Y1689124I303J0D01*
G37*
G36*
G01X1359127D02*
X1362827D01*
G02X1363130Y1688821I0J-303D01*
G01Y1678815D01*
G02X1362827Y1678512I-303J0D01*
G01X1359127D01*
G02X1358824Y1678815I0J303D01*
G01Y1681227D01*
G02X1358811Y1681456I2003J229D01*
G02X1358824Y1681685I2016J0D01*
G01Y1685951D01*
G02X1358811Y1686180I2003J229D01*
G02X1358824Y1686409I2016J0D01*
G01Y1688821D01*
G02X1359127Y1689124I303J0D01*
G37*
G36*
G01X1509127D02*
X1512827D01*
G02X1513130Y1688821I0J-303D01*
G01Y1678815D01*
G02X1512827Y1678512I-303J0D01*
G01X1509127D01*
G02X1508824Y1678815I0J303D01*
G01Y1681227D01*
G02X1508811Y1681456I2003J229D01*
G02X1508824Y1681685I2016J0D01*
G01Y1685951D01*
G02X1508811Y1686180I2003J229D01*
G02X1508824Y1686409I2016J0D01*
G01Y1688821D01*
G02X1509127Y1689124I303J0D01*
G37*
G36*
G01X1524875D02*
X1528575D01*
G02X1528878Y1688821I0J-303D01*
G01Y1678815D01*
G02X1528575Y1678512I-303J0D01*
G01X1524875D01*
G02X1524572Y1678815I0J303D01*
G01Y1681227D01*
G02X1524559Y1681456I2003J229D01*
G02X1524572Y1681685I2016J0D01*
G01Y1685951D01*
G02X1524559Y1686180I2003J229D01*
G02X1524572Y1686409I2016J0D01*
G01Y1688821D01*
G02X1524875Y1689124I303J0D01*
G37*
G36*
G01X1540623D02*
X1544323D01*
G02X1544626Y1688821I0J-303D01*
G01Y1678815D01*
G02X1544323Y1678512I-303J0D01*
G01X1540623D01*
G02X1540320Y1678815I0J303D01*
G01Y1681227D01*
G02X1540307Y1681456I2003J229D01*
G02X1540320Y1681685I2016J0D01*
G01Y1685951D01*
G02X1540307Y1686180I2003J229D01*
G02X1540320Y1686409I2016J0D01*
G01Y1688821D01*
G02X1540623Y1689124I303J0D01*
G37*
G36*
G01X1556371D02*
X1560071D01*
G02X1560374Y1688821I0J-303D01*
G01Y1678815D01*
G02X1560071Y1678512I-303J0D01*
G01X1556371D01*
G02X1556068Y1678815I0J303D01*
G01Y1681227D01*
G02X1556055Y1681456I2003J229D01*
G02X1556068Y1681685I2016J0D01*
G01Y1685951D01*
G02X1556055Y1686180I2003J229D01*
G02X1556068Y1686409I2016J0D01*
G01Y1688821D01*
G02X1556371Y1689124I303J0D01*
G37*
G36*
G01X1576056D02*
X1579756D01*
G02X1580058Y1688821I-1J-303D01*
G01Y1678815D01*
G02X1579756Y1678512I-302J-1D01*
G01X1576056D01*
G02X1575754Y1678815I1J303D01*
G01Y1681219D01*
G02X1575740Y1681456I2002J237D01*
G02X1575754Y1681693I2016J0D01*
G01Y1685943D01*
G02X1575740Y1686180I2002J237D01*
G02X1575754Y1686417I2016J0D01*
G01Y1688821D01*
G02X1576056Y1689124I302J1D01*
G37*
G36*
G01X1591804D02*
X1595504D01*
G02X1595806Y1688821I-1J-303D01*
G01Y1678815D01*
G02X1595504Y1678512I-302J-1D01*
G01X1591804D01*
G02X1591502Y1678815I1J303D01*
G01Y1681219D01*
G02X1591488Y1681456I2002J237D01*
G02X1591502Y1681693I2016J0D01*
G01Y1685943D01*
G02X1591488Y1686180I2002J237D01*
G02X1591502Y1686417I2016J0D01*
G01Y1688821D01*
G02X1591804Y1689124I302J1D01*
G37*
G36*
G01X1607552D02*
X1611252D01*
G02X1611554Y1688821I-1J-303D01*
G01Y1678815D01*
G02X1611252Y1678512I-302J-1D01*
G01X1607552D01*
G02X1607250Y1678815I1J303D01*
G01Y1681219D01*
G02X1607236Y1681456I2002J237D01*
G02X1607250Y1681693I2016J0D01*
G01Y1685943D01*
G02X1607236Y1686180I2002J237D01*
G02X1607250Y1686417I2016J0D01*
G01Y1688821D01*
G02X1607552Y1689124I302J1D01*
G37*
G36*
G01X1623300D02*
X1627000D01*
G02X1627302Y1688821I-1J-303D01*
G01Y1678815D01*
G02X1627000Y1678512I-302J-1D01*
G01X1623300D01*
G02X1622998Y1678815I1J303D01*
G01Y1681219D01*
G02X1622984Y1681456I2002J237D01*
G02X1622998Y1681693I2016J0D01*
G01Y1685943D01*
G02X1622984Y1686180I2002J237D01*
G02X1622998Y1686417I2016J0D01*
G01Y1688821D01*
G02X1623300Y1689124I302J1D01*
G37*
G36*
G01X229206Y1699360D02*
X232906D01*
G02X233208Y1699057I-1J-303D01*
G01Y1689051D01*
G02X232906Y1688748I-302J-1D01*
G01X229206D01*
G02X228904Y1689051I1J303D01*
G01Y1691455D01*
G02X228890Y1691692I2002J237D01*
G02X228904Y1691929I2016J0D01*
G01Y1696180D01*
G02X228890Y1696417I2002J237D01*
G02X228904Y1696654I2016J0D01*
G01Y1699057D01*
G02X229206Y1699360I302J1D01*
G37*
G36*
G01X244954D02*
X248654D01*
G02X248956Y1699057I-1J-303D01*
G01Y1689051D01*
G02X248654Y1688748I-302J-1D01*
G01X244954D01*
G02X244652Y1689051I1J303D01*
G01Y1691455D01*
G02X244638Y1691692I2002J237D01*
G02X244652Y1691929I2016J0D01*
G01Y1696180D01*
G02X244638Y1696417I2002J237D01*
G02X244652Y1696654I2016J0D01*
G01Y1699057D01*
G02X244954Y1699360I302J1D01*
G37*
G36*
G01X260702D02*
X264402D01*
G02X264704Y1699057I-1J-303D01*
G01Y1689051D01*
G02X264402Y1688748I-302J-1D01*
G01X260702D01*
G02X260400Y1689051I1J303D01*
G01Y1691455D01*
G02X260386Y1691692I2002J237D01*
G02X260400Y1691929I2016J0D01*
G01Y1696180D01*
G02X260386Y1696417I2002J237D01*
G02X260400Y1696654I2016J0D01*
G01Y1699057D01*
G02X260702Y1699360I302J1D01*
G37*
G36*
G01X276450D02*
X280150D01*
G02X280452Y1699057I-1J-303D01*
G01Y1689051D01*
G02X280150Y1688748I-302J-1D01*
G01X276450D01*
G02X276148Y1689051I1J303D01*
G01Y1691455D01*
G02X276134Y1691692I2002J237D01*
G02X276148Y1691929I2016J0D01*
G01Y1696180D01*
G02X276134Y1696417I2002J237D01*
G02X276148Y1696654I2016J0D01*
G01Y1699057D01*
G02X276450Y1699360I302J1D01*
G37*
G36*
G01X296135D02*
X299835D01*
G02X300138Y1699057I0J-303D01*
G01Y1689051D01*
G02X299835Y1688748I-303J0D01*
G01X296135D01*
G02X295832Y1689051I0J303D01*
G01Y1691463D01*
G02X295819Y1691692I2003J229D01*
G02X295832Y1691921I2016J0D01*
G01Y1696188D01*
G02X295819Y1696417I2003J229D01*
G02X295832Y1696646I2016J0D01*
G01Y1699057D01*
G02X296135Y1699360I303J0D01*
G37*
G36*
G01X311883D02*
X315583D01*
G02X315886Y1699057I0J-303D01*
G01Y1689051D01*
G02X315583Y1688748I-303J0D01*
G01X311883D01*
G02X311580Y1689051I0J303D01*
G01Y1691463D01*
G02X311567Y1691692I2003J229D01*
G02X311580Y1691921I2016J0D01*
G01Y1696188D01*
G02X311567Y1696417I2003J229D01*
G02X311580Y1696646I2016J0D01*
G01Y1699057D01*
G02X311883Y1699360I303J0D01*
G37*
G36*
G01X327631D02*
X331331D01*
G02X331634Y1699057I0J-303D01*
G01Y1689051D01*
G02X331331Y1688748I-303J0D01*
G01X327631D01*
G02X327328Y1689051I0J303D01*
G01Y1691463D01*
G02X327315Y1691692I2003J229D01*
G02X327328Y1691921I2016J0D01*
G01Y1696188D01*
G02X327315Y1696417I2003J229D01*
G02X327328Y1696646I2016J0D01*
G01Y1699057D01*
G02X327631Y1699360I303J0D01*
G37*
G36*
G01X343379D02*
X347079D01*
G02X347382Y1699057I0J-303D01*
G01Y1689051D01*
G02X347079Y1688748I-303J0D01*
G01X343379D01*
G02X343076Y1689051I0J303D01*
G01Y1691463D01*
G02X343063Y1691692I2003J229D01*
G02X343076Y1691921I2016J0D01*
G01Y1696188D01*
G02X343063Y1696417I2003J229D01*
G02X343076Y1696646I2016J0D01*
G01Y1699057D01*
G02X343379Y1699360I303J0D01*
G37*
G36*
G01X493379D02*
X497079D01*
G02X497382Y1699057I0J-303D01*
G01Y1689051D01*
G02X497079Y1688748I-303J0D01*
G01X493379D01*
G02X493076Y1689051I0J303D01*
G01Y1691463D01*
G02X493063Y1691692I2003J229D01*
G02X493076Y1691921I2016J0D01*
G01Y1696188D01*
G02X493063Y1696417I2003J229D01*
G02X493076Y1696646I2016J0D01*
G01Y1699057D01*
G02X493379Y1699360I303J0D01*
G37*
G36*
G01X509127D02*
X512827D01*
G02X513130Y1699057I0J-303D01*
G01Y1689051D01*
G02X512827Y1688748I-303J0D01*
G01X509127D01*
G02X508824Y1689051I0J303D01*
G01Y1691463D01*
G02X508811Y1691692I2003J229D01*
G02X508824Y1691921I2016J0D01*
G01Y1696188D01*
G02X508811Y1696417I2003J229D01*
G02X508824Y1696646I2016J0D01*
G01Y1699057D01*
G02X509127Y1699360I303J0D01*
G37*
G36*
G01X524875D02*
X528575D01*
G02X528878Y1699057I0J-303D01*
G01Y1689051D01*
G02X528575Y1688748I-303J0D01*
G01X524875D01*
G02X524572Y1689051I0J303D01*
G01Y1691463D01*
G02X524559Y1691692I2003J229D01*
G02X524572Y1691921I2016J0D01*
G01Y1696188D01*
G02X524559Y1696417I2003J229D01*
G02X524572Y1696646I2016J0D01*
G01Y1699057D01*
G02X524875Y1699360I303J0D01*
G37*
G36*
G01X540623D02*
X544323D01*
G02X544626Y1699057I0J-303D01*
G01Y1689051D01*
G02X544323Y1688748I-303J0D01*
G01X540623D01*
G02X540320Y1689051I0J303D01*
G01Y1691463D01*
G02X540307Y1691692I2003J229D01*
G02X540320Y1691921I2016J0D01*
G01Y1696188D01*
G02X540307Y1696417I2003J229D01*
G02X540320Y1696646I2016J0D01*
G01Y1699057D01*
G02X540623Y1699360I303J0D01*
G37*
G36*
G01X560308D02*
X564008D01*
G02X564310Y1699057I-1J-303D01*
G01Y1689051D01*
G02X564008Y1688748I-302J-1D01*
G01X560308D01*
G02X560006Y1689051I1J303D01*
G01Y1691455D01*
G02X559992Y1691692I2002J237D01*
G02X560006Y1691929I2016J0D01*
G01Y1696180D01*
G02X559992Y1696417I2002J237D01*
G02X560006Y1696654I2016J0D01*
G01Y1699057D01*
G02X560308Y1699360I302J1D01*
G37*
G36*
G01X576056D02*
X579756D01*
G02X580058Y1699057I-1J-303D01*
G01Y1689051D01*
G02X579756Y1688748I-302J-1D01*
G01X576056D01*
G02X575754Y1689051I1J303D01*
G01Y1691455D01*
G02X575740Y1691692I2002J237D01*
G02X575754Y1691929I2016J0D01*
G01Y1696180D01*
G02X575740Y1696417I2002J237D01*
G02X575754Y1696654I2016J0D01*
G01Y1699057D01*
G02X576056Y1699360I302J1D01*
G37*
G36*
G01X591804D02*
X595504D01*
G02X595806Y1699057I-1J-303D01*
G01Y1689051D01*
G02X595504Y1688748I-302J-1D01*
G01X591804D01*
G02X591502Y1689051I1J303D01*
G01Y1691455D01*
G02X591488Y1691692I2002J237D01*
G02X591502Y1691929I2016J0D01*
G01Y1696180D01*
G02X591488Y1696417I2002J237D01*
G02X591502Y1696654I2016J0D01*
G01Y1699057D01*
G02X591804Y1699360I302J1D01*
G37*
G36*
G01X607552D02*
X611252D01*
G02X611554Y1699057I-1J-303D01*
G01Y1689051D01*
G02X611252Y1688748I-302J-1D01*
G01X607552D01*
G02X607250Y1689051I1J303D01*
G01Y1691455D01*
G02X607236Y1691692I2002J237D01*
G02X607250Y1691929I2016J0D01*
G01Y1696180D01*
G02X607236Y1696417I2002J237D01*
G02X607250Y1696654I2016J0D01*
G01Y1699057D01*
G02X607552Y1699360I302J1D01*
G37*
G36*
G01X1237080D02*
X1240780D01*
G02X1241082Y1699057I-1J-303D01*
G01Y1689051D01*
G02X1240780Y1688748I-302J-1D01*
G01X1237080D01*
G02X1236778Y1689051I1J303D01*
G01Y1691455D01*
G02X1236764Y1691692I2002J237D01*
G02X1236778Y1691929I2016J0D01*
G01Y1696180D01*
G02X1236764Y1696417I2002J237D01*
G02X1236778Y1696654I2016J0D01*
G01Y1699057D01*
G02X1237080Y1699360I302J1D01*
G37*
G36*
G01X1252828D02*
X1256528D01*
G02X1256830Y1699057I-1J-303D01*
G01Y1689051D01*
G02X1256528Y1688748I-302J-1D01*
G01X1252828D01*
G02X1252526Y1689051I1J303D01*
G01Y1691455D01*
G02X1252512Y1691692I2002J237D01*
G02X1252526Y1691929I2016J0D01*
G01Y1696180D01*
G02X1252512Y1696417I2002J237D01*
G02X1252526Y1696654I2016J0D01*
G01Y1699057D01*
G02X1252828Y1699360I302J1D01*
G37*
G36*
G01X1268576D02*
X1272276D01*
G02X1272578Y1699057I-1J-303D01*
G01Y1689051D01*
G02X1272276Y1688748I-302J-1D01*
G01X1268576D01*
G02X1268274Y1689051I1J303D01*
G01Y1691455D01*
G02X1268260Y1691692I2002J237D01*
G02X1268274Y1691929I2016J0D01*
G01Y1696180D01*
G02X1268260Y1696417I2002J237D01*
G02X1268274Y1696654I2016J0D01*
G01Y1699057D01*
G02X1268576Y1699360I302J1D01*
G37*
G36*
G01X1284324D02*
X1288024D01*
G02X1288326Y1699057I-1J-303D01*
G01Y1689051D01*
G02X1288024Y1688748I-302J-1D01*
G01X1284324D01*
G02X1284022Y1689051I1J303D01*
G01Y1691455D01*
G02X1284008Y1691692I2002J237D01*
G02X1284022Y1691929I2016J0D01*
G01Y1696180D01*
G02X1284008Y1696417I2002J237D01*
G02X1284022Y1696654I2016J0D01*
G01Y1699057D01*
G02X1284324Y1699360I302J1D01*
G37*
G36*
G01X1304009D02*
X1307709D01*
G02X1308012Y1699057I0J-303D01*
G01Y1689051D01*
G02X1307709Y1688748I-303J0D01*
G01X1304009D01*
G02X1303706Y1689051I0J303D01*
G01Y1691463D01*
G02X1303693Y1691692I2003J229D01*
G02X1303706Y1691921I2016J0D01*
G01Y1696188D01*
G02X1303693Y1696417I2003J229D01*
G02X1303706Y1696646I2016J0D01*
G01Y1699057D01*
G02X1304009Y1699360I303J0D01*
G37*
G36*
G01X1319757D02*
X1323457D01*
G02X1323760Y1699057I0J-303D01*
G01Y1689051D01*
G02X1323457Y1688748I-303J0D01*
G01X1319757D01*
G02X1319454Y1689051I0J303D01*
G01Y1691463D01*
G02X1319441Y1691692I2003J229D01*
G02X1319454Y1691921I2016J0D01*
G01Y1696188D01*
G02X1319441Y1696417I2003J229D01*
G02X1319454Y1696646I2016J0D01*
G01Y1699057D01*
G02X1319757Y1699360I303J0D01*
G37*
G36*
G01X1335505D02*
X1339205D01*
G02X1339508Y1699057I0J-303D01*
G01Y1689051D01*
G02X1339205Y1688748I-303J0D01*
G01X1335505D01*
G02X1335202Y1689051I0J303D01*
G01Y1691463D01*
G02X1335189Y1691692I2003J229D01*
G02X1335202Y1691921I2016J0D01*
G01Y1696188D01*
G02X1335189Y1696417I2003J229D01*
G02X1335202Y1696646I2016J0D01*
G01Y1699057D01*
G02X1335505Y1699360I303J0D01*
G37*
G36*
G01X1351253D02*
X1354953D01*
G02X1355256Y1699057I0J-303D01*
G01Y1689051D01*
G02X1354953Y1688748I-303J0D01*
G01X1351253D01*
G02X1350950Y1689051I0J303D01*
G01Y1691463D01*
G02X1350937Y1691692I2003J229D01*
G02X1350950Y1691921I2016J0D01*
G01Y1696188D01*
G02X1350937Y1696417I2003J229D01*
G02X1350950Y1696646I2016J0D01*
G01Y1699057D01*
G02X1351253Y1699360I303J0D01*
G37*
G36*
G01X1501253D02*
X1504953D01*
G02X1505256Y1699057I0J-303D01*
G01Y1689051D01*
G02X1504953Y1688748I-303J0D01*
G01X1501253D01*
G02X1500950Y1689051I0J303D01*
G01Y1691463D01*
G02X1500937Y1691692I2003J229D01*
G02X1500950Y1691921I2016J0D01*
G01Y1696188D01*
G02X1500937Y1696417I2003J229D01*
G02X1500950Y1696646I2016J0D01*
G01Y1699057D01*
G02X1501253Y1699360I303J0D01*
G37*
G36*
G01X1517001D02*
X1520701D01*
G02X1521004Y1699057I0J-303D01*
G01Y1689051D01*
G02X1520701Y1688748I-303J0D01*
G01X1517001D01*
G02X1516698Y1689051I0J303D01*
G01Y1691463D01*
G02X1516685Y1691692I2003J229D01*
G02X1516698Y1691921I2016J0D01*
G01Y1696188D01*
G02X1516685Y1696417I2003J229D01*
G02X1516698Y1696646I2016J0D01*
G01Y1699057D01*
G02X1517001Y1699360I303J0D01*
G37*
G36*
G01X1532749D02*
X1536449D01*
G02X1536752Y1699057I0J-303D01*
G01Y1689051D01*
G02X1536449Y1688748I-303J0D01*
G01X1532749D01*
G02X1532446Y1689051I0J303D01*
G01Y1691463D01*
G02X1532433Y1691692I2003J229D01*
G02X1532446Y1691921I2016J0D01*
G01Y1696188D01*
G02X1532433Y1696417I2003J229D01*
G02X1532446Y1696646I2016J0D01*
G01Y1699057D01*
G02X1532749Y1699360I303J0D01*
G37*
G36*
G01X1548497D02*
X1552197D01*
G02X1552500Y1699057I0J-303D01*
G01Y1689051D01*
G02X1552197Y1688748I-303J0D01*
G01X1548497D01*
G02X1548194Y1689051I0J303D01*
G01Y1691463D01*
G02X1548181Y1691692I2003J229D01*
G02X1548194Y1691921I2016J0D01*
G01Y1696188D01*
G02X1548181Y1696417I2003J229D01*
G02X1548194Y1696646I2016J0D01*
G01Y1699057D01*
G02X1548497Y1699360I303J0D01*
G37*
G36*
G01X1568182D02*
X1571882D01*
G02X1572184Y1699057I-1J-303D01*
G01Y1689051D01*
G02X1571882Y1688748I-302J-1D01*
G01X1568182D01*
G02X1567880Y1689051I1J303D01*
G01Y1691455D01*
G02X1567866Y1691692I2002J237D01*
G02X1567880Y1691929I2016J0D01*
G01Y1696180D01*
G02X1567866Y1696417I2002J237D01*
G02X1567880Y1696654I2016J0D01*
G01Y1699057D01*
G02X1568182Y1699360I302J1D01*
G37*
G36*
G01X1583930D02*
X1587630D01*
G02X1587932Y1699057I-1J-303D01*
G01Y1689051D01*
G02X1587630Y1688748I-302J-1D01*
G01X1583930D01*
G02X1583628Y1689051I1J303D01*
G01Y1691455D01*
G02X1583614Y1691692I2002J237D01*
G02X1583628Y1691929I2016J0D01*
G01Y1696180D01*
G02X1583614Y1696417I2002J237D01*
G02X1583628Y1696654I2016J0D01*
G01Y1699057D01*
G02X1583930Y1699360I302J1D01*
G37*
G36*
G01X1599678D02*
X1603378D01*
G02X1603680Y1699057I-1J-303D01*
G01Y1689051D01*
G02X1603378Y1688748I-302J-1D01*
G01X1599678D01*
G02X1599376Y1689051I1J303D01*
G01Y1691455D01*
G02X1599362Y1691692I2002J237D01*
G02X1599376Y1691929I2016J0D01*
G01Y1696180D01*
G02X1599362Y1696417I2002J237D01*
G02X1599376Y1696654I2016J0D01*
G01Y1699057D01*
G02X1599678Y1699360I302J1D01*
G37*
G36*
G01X1615426D02*
X1619126D01*
G02X1619428Y1699057I-1J-303D01*
G01Y1689051D01*
G02X1619126Y1688748I-302J-1D01*
G01X1615426D01*
G02X1615124Y1689051I1J303D01*
G01Y1691455D01*
G02X1615110Y1691692I2002J237D01*
G02X1615124Y1691929I2016J0D01*
G01Y1696180D01*
G02X1615110Y1696417I2002J237D01*
G02X1615124Y1696654I2016J0D01*
G01Y1699057D01*
G02X1615426Y1699360I302J1D01*
G37*
G36*
G01X237080Y1703296D02*
X240780D01*
G02X241082Y1702994I0J-302D01*
G01Y1692988D01*
G02X240780Y1692686I-302J0D01*
G01X237080D01*
G02X236778Y1692988I0J302D01*
G01Y1695392D01*
G02X236764Y1695629I2002J237D01*
G02X236778Y1695866I2016J0D01*
G01Y1700117D01*
G02X236764Y1700354I2002J237D01*
G02X236778Y1700591I2016J0D01*
G01Y1702994D01*
G02X237080Y1703296I302J0D01*
G37*
G36*
G01X252828D02*
X256528D01*
G02X256830Y1702994I0J-302D01*
G01Y1692988D01*
G02X256528Y1692686I-302J0D01*
G01X252828D01*
G02X252526Y1692988I0J302D01*
G01Y1695392D01*
G02X252512Y1695629I2002J237D01*
G02X252526Y1695866I2016J0D01*
G01Y1700117D01*
G02X252512Y1700354I2002J237D01*
G02X252526Y1700591I2016J0D01*
G01Y1702994D01*
G02X252828Y1703296I302J0D01*
G37*
G36*
G01X268576D02*
X272276D01*
G02X272578Y1702994I0J-302D01*
G01Y1692988D01*
G02X272276Y1692686I-302J0D01*
G01X268576D01*
G02X268274Y1692988I0J302D01*
G01Y1695392D01*
G02X268260Y1695629I2002J237D01*
G02X268274Y1695866I2016J0D01*
G01Y1700117D01*
G02X268260Y1700354I2002J237D01*
G02X268274Y1700591I2016J0D01*
G01Y1702994D01*
G02X268576Y1703296I302J0D01*
G37*
G36*
G01X284324D02*
X288024D01*
G02X288326Y1702994I0J-302D01*
G01Y1692988D01*
G02X288024Y1692686I-302J0D01*
G01X284324D01*
G02X284022Y1692988I0J302D01*
G01Y1695392D01*
G02X284008Y1695629I2002J237D01*
G02X284022Y1695866I2016J0D01*
G01Y1700117D01*
G02X284008Y1700354I2002J237D01*
G02X284022Y1700591I2016J0D01*
G01Y1702994D01*
G02X284324Y1703296I302J0D01*
G37*
G36*
G01X568182D02*
X571882D01*
G02X572184Y1702994I0J-302D01*
G01Y1692988D01*
G02X571882Y1692686I-302J0D01*
G01X568182D01*
G02X567880Y1692988I0J302D01*
G01Y1695392D01*
G02X567866Y1695629I2002J237D01*
G02X567880Y1695866I2016J0D01*
G01Y1700117D01*
G02X567866Y1700354I2002J237D01*
G02X567880Y1700591I2016J0D01*
G01Y1702994D01*
G02X568182Y1703296I302J0D01*
G37*
G36*
G01X583930D02*
X587630D01*
G02X587932Y1702994I0J-302D01*
G01Y1692988D01*
G02X587630Y1692686I-302J0D01*
G01X583930D01*
G02X583628Y1692988I0J302D01*
G01Y1695392D01*
G02X583614Y1695629I2002J237D01*
G02X583628Y1695866I2016J0D01*
G01Y1700117D01*
G02X583614Y1700354I2002J237D01*
G02X583628Y1700591I2016J0D01*
G01Y1702994D01*
G02X583930Y1703296I302J0D01*
G37*
G36*
G01X599678D02*
X603378D01*
G02X603680Y1702994I0J-302D01*
G01Y1692988D01*
G02X603378Y1692686I-302J0D01*
G01X599678D01*
G02X599376Y1692988I0J302D01*
G01Y1695392D01*
G02X599362Y1695629I2002J237D01*
G02X599376Y1695866I2016J0D01*
G01Y1700117D01*
G02X599362Y1700354I2002J237D01*
G02X599376Y1700591I2016J0D01*
G01Y1702994D01*
G02X599678Y1703296I302J0D01*
G37*
G36*
G01X615426D02*
X619126D01*
G02X619428Y1702994I0J-302D01*
G01Y1692988D01*
G02X619126Y1692686I-302J0D01*
G01X615426D01*
G02X615124Y1692988I0J302D01*
G01Y1695392D01*
G02X615110Y1695629I2002J237D01*
G02X615124Y1695866I2016J0D01*
G01Y1700117D01*
G02X615110Y1700354I2002J237D01*
G02X615124Y1700591I2016J0D01*
G01Y1702994D01*
G02X615426Y1703296I302J0D01*
G37*
G36*
G01X1244954D02*
X1248654D01*
G02X1248956Y1702994I0J-302D01*
G01Y1692988D01*
G02X1248654Y1692686I-302J0D01*
G01X1244954D01*
G02X1244652Y1692988I0J302D01*
G01Y1695392D01*
G02X1244638Y1695629I2002J237D01*
G02X1244652Y1695866I2016J0D01*
G01Y1700117D01*
G02X1244638Y1700354I2002J237D01*
G02X1244652Y1700591I2016J0D01*
G01Y1702994D01*
G02X1244954Y1703296I302J0D01*
G37*
G36*
G01X1260702D02*
X1264402D01*
G02X1264704Y1702994I0J-302D01*
G01Y1692988D01*
G02X1264402Y1692686I-302J0D01*
G01X1260702D01*
G02X1260400Y1692988I0J302D01*
G01Y1695392D01*
G02X1260386Y1695629I2002J237D01*
G02X1260400Y1695866I2016J0D01*
G01Y1700117D01*
G02X1260386Y1700354I2002J237D01*
G02X1260400Y1700591I2016J0D01*
G01Y1702994D01*
G02X1260702Y1703296I302J0D01*
G37*
G36*
G01X1276450D02*
X1280150D01*
G02X1280452Y1702994I0J-302D01*
G01Y1692988D01*
G02X1280150Y1692686I-302J0D01*
G01X1276450D01*
G02X1276148Y1692988I0J302D01*
G01Y1695392D01*
G02X1276134Y1695629I2002J237D01*
G02X1276148Y1695866I2016J0D01*
G01Y1700117D01*
G02X1276134Y1700354I2002J237D01*
G02X1276148Y1700591I2016J0D01*
G01Y1702994D01*
G02X1276450Y1703296I302J0D01*
G37*
G36*
G01X1292198D02*
X1295898D01*
G02X1296200Y1702994I0J-302D01*
G01Y1692988D01*
G02X1295898Y1692686I-302J0D01*
G01X1292198D01*
G02X1291896Y1692988I0J302D01*
G01Y1695392D01*
G02X1291882Y1695629I2002J237D01*
G02X1291896Y1695866I2016J0D01*
G01Y1700117D01*
G02X1291882Y1700354I2002J237D01*
G02X1291896Y1700591I2016J0D01*
G01Y1702994D01*
G02X1292198Y1703296I302J0D01*
G37*
G36*
G01X1576056D02*
X1579756D01*
G02X1580058Y1702994I0J-302D01*
G01Y1692988D01*
G02X1579756Y1692686I-302J0D01*
G01X1576056D01*
G02X1575754Y1692988I0J302D01*
G01Y1695392D01*
G02X1575740Y1695629I2002J237D01*
G02X1575754Y1695866I2016J0D01*
G01Y1700117D01*
G02X1575740Y1700354I2002J237D01*
G02X1575754Y1700591I2016J0D01*
G01Y1702994D01*
G02X1576056Y1703296I302J0D01*
G37*
G36*
G01X1591804D02*
X1595504D01*
G02X1595806Y1702994I0J-302D01*
G01Y1692988D01*
G02X1595504Y1692686I-302J0D01*
G01X1591804D01*
G02X1591502Y1692988I0J302D01*
G01Y1695392D01*
G02X1591488Y1695629I2002J237D01*
G02X1591502Y1695866I2016J0D01*
G01Y1700117D01*
G02X1591488Y1700354I2002J237D01*
G02X1591502Y1700591I2016J0D01*
G01Y1702994D01*
G02X1591804Y1703296I302J0D01*
G37*
G36*
G01X1607552D02*
X1611252D01*
G02X1611554Y1702994I0J-302D01*
G01Y1692988D01*
G02X1611252Y1692686I-302J0D01*
G01X1607552D01*
G02X1607250Y1692988I0J302D01*
G01Y1695392D01*
G02X1607236Y1695629I2002J237D01*
G02X1607250Y1695866I2016J0D01*
G01Y1700117D01*
G02X1607236Y1700354I2002J237D01*
G02X1607250Y1700591I2016J0D01*
G01Y1702994D01*
G02X1607552Y1703296I302J0D01*
G37*
G36*
G01X1623300D02*
X1627000D01*
G02X1627302Y1702994I0J-302D01*
G01Y1692988D01*
G02X1627000Y1692686I-302J0D01*
G01X1623300D01*
G02X1622998Y1692988I0J302D01*
G01Y1695392D01*
G02X1622984Y1695629I2002J237D01*
G02X1622998Y1695866I2016J0D01*
G01Y1700117D01*
G02X1622984Y1700354I2002J237D01*
G02X1622998Y1700591I2016J0D01*
G01Y1702994D01*
G02X1623300Y1703296I302J0D01*
G37*
G36*
G01X304009D02*
X307709D01*
G02X308012Y1702994I1J-302D01*
G01Y1692988D01*
G02X307709Y1692686I-303J1D01*
G01X304009D01*
G02X303706Y1692988I-1J302D01*
G01Y1695400D01*
G02X303693Y1695629I2003J229D01*
G02X303706Y1695858I2016J0D01*
G01Y1700125D01*
G02X303693Y1700354I2003J229D01*
G02X303706Y1700583I2016J0D01*
G01Y1702994D01*
G02X304009Y1703296I303J-1D01*
G37*
G36*
G01X319757D02*
X323457D01*
G02X323760Y1702994I1J-302D01*
G01Y1692988D01*
G02X323457Y1692686I-303J1D01*
G01X319757D01*
G02X319454Y1692988I-1J302D01*
G01Y1695400D01*
G02X319441Y1695629I2003J229D01*
G02X319454Y1695858I2016J0D01*
G01Y1700125D01*
G02X319441Y1700354I2003J229D01*
G02X319454Y1700583I2016J0D01*
G01Y1702994D01*
G02X319757Y1703296I303J-1D01*
G37*
G36*
G01X335505D02*
X339205D01*
G02X339508Y1702994I1J-302D01*
G01Y1692988D01*
G02X339205Y1692686I-303J1D01*
G01X335505D01*
G02X335202Y1692988I-1J302D01*
G01Y1695400D01*
G02X335189Y1695629I2003J229D01*
G02X335202Y1695858I2016J0D01*
G01Y1700125D01*
G02X335189Y1700354I2003J229D01*
G02X335202Y1700583I2016J0D01*
G01Y1702994D01*
G02X335505Y1703296I303J-1D01*
G37*
G36*
G01X351253D02*
X354953D01*
G02X355256Y1702994I1J-302D01*
G01Y1692988D01*
G02X354953Y1692686I-303J1D01*
G01X351253D01*
G02X350950Y1692988I-1J302D01*
G01Y1695400D01*
G02X350937Y1695629I2003J229D01*
G02X350950Y1695858I2016J0D01*
G01Y1700125D01*
G02X350937Y1700354I2003J229D01*
G02X350950Y1700583I2016J0D01*
G01Y1702994D01*
G02X351253Y1703296I303J-1D01*
G37*
G36*
G01X501253D02*
X504953D01*
G02X505256Y1702994I1J-302D01*
G01Y1692988D01*
G02X504953Y1692686I-303J1D01*
G01X501253D01*
G02X500950Y1692988I-1J302D01*
G01Y1695400D01*
G02X500937Y1695629I2003J229D01*
G02X500950Y1695858I2016J0D01*
G01Y1700125D01*
G02X500937Y1700354I2003J229D01*
G02X500950Y1700583I2016J0D01*
G01Y1702994D01*
G02X501253Y1703296I303J-1D01*
G37*
G36*
G01X517001D02*
X520701D01*
G02X521004Y1702994I1J-302D01*
G01Y1692988D01*
G02X520701Y1692686I-303J1D01*
G01X517001D01*
G02X516698Y1692988I-1J302D01*
G01Y1695400D01*
G02X516685Y1695629I2003J229D01*
G02X516698Y1695858I2016J0D01*
G01Y1700125D01*
G02X516685Y1700354I2003J229D01*
G02X516698Y1700583I2016J0D01*
G01Y1702994D01*
G02X517001Y1703296I303J-1D01*
G37*
G36*
G01X532749D02*
X536449D01*
G02X536752Y1702994I1J-302D01*
G01Y1692988D01*
G02X536449Y1692686I-303J1D01*
G01X532749D01*
G02X532446Y1692988I-1J302D01*
G01Y1695400D01*
G02X532433Y1695629I2003J229D01*
G02X532446Y1695858I2016J0D01*
G01Y1700125D01*
G02X532433Y1700354I2003J229D01*
G02X532446Y1700583I2016J0D01*
G01Y1702994D01*
G02X532749Y1703296I303J-1D01*
G37*
G36*
G01X548497D02*
X552197D01*
G02X552500Y1702994I1J-302D01*
G01Y1692988D01*
G02X552197Y1692686I-303J1D01*
G01X548497D01*
G02X548194Y1692988I-1J302D01*
G01Y1695400D01*
G02X548181Y1695629I2003J229D01*
G02X548194Y1695858I2016J0D01*
G01Y1700125D01*
G02X548181Y1700354I2003J229D01*
G02X548194Y1700583I2016J0D01*
G01Y1702994D01*
G02X548497Y1703296I303J-1D01*
G37*
G36*
G01X1311883D02*
X1315583D01*
G02X1315886Y1702994I1J-302D01*
G01Y1692988D01*
G02X1315583Y1692686I-303J1D01*
G01X1311883D01*
G02X1311580Y1692988I-1J302D01*
G01Y1695400D01*
G02X1311567Y1695629I2003J229D01*
G02X1311580Y1695858I2016J0D01*
G01Y1700125D01*
G02X1311567Y1700354I2003J229D01*
G02X1311580Y1700583I2016J0D01*
G01Y1702994D01*
G02X1311883Y1703296I303J-1D01*
G37*
G36*
G01X1327631D02*
X1331331D01*
G02X1331634Y1702994I1J-302D01*
G01Y1692988D01*
G02X1331331Y1692686I-303J1D01*
G01X1327631D01*
G02X1327328Y1692988I-1J302D01*
G01Y1695400D01*
G02X1327315Y1695629I2003J229D01*
G02X1327328Y1695858I2016J0D01*
G01Y1700125D01*
G02X1327315Y1700354I2003J229D01*
G02X1327328Y1700583I2016J0D01*
G01Y1702994D01*
G02X1327631Y1703296I303J-1D01*
G37*
G36*
G01X1343379D02*
X1347079D01*
G02X1347382Y1702994I1J-302D01*
G01Y1692988D01*
G02X1347079Y1692686I-303J1D01*
G01X1343379D01*
G02X1343076Y1692988I-1J302D01*
G01Y1695400D01*
G02X1343063Y1695629I2003J229D01*
G02X1343076Y1695858I2016J0D01*
G01Y1700125D01*
G02X1343063Y1700354I2003J229D01*
G02X1343076Y1700583I2016J0D01*
G01Y1702994D01*
G02X1343379Y1703296I303J-1D01*
G37*
G36*
G01X1359127D02*
X1362827D01*
G02X1363130Y1702994I1J-302D01*
G01Y1692988D01*
G02X1362827Y1692686I-303J1D01*
G01X1359127D01*
G02X1358824Y1692988I-1J302D01*
G01Y1695400D01*
G02X1358811Y1695629I2003J229D01*
G02X1358824Y1695858I2016J0D01*
G01Y1700125D01*
G02X1358811Y1700354I2003J229D01*
G02X1358824Y1700583I2016J0D01*
G01Y1702994D01*
G02X1359127Y1703296I303J-1D01*
G37*
G36*
G01X1509127D02*
X1512827D01*
G02X1513130Y1702994I1J-302D01*
G01Y1692988D01*
G02X1512827Y1692686I-303J1D01*
G01X1509127D01*
G02X1508824Y1692988I-1J302D01*
G01Y1695400D01*
G02X1508811Y1695629I2003J229D01*
G02X1508824Y1695858I2016J0D01*
G01Y1700125D01*
G02X1508811Y1700354I2003J229D01*
G02X1508824Y1700583I2016J0D01*
G01Y1702994D01*
G02X1509127Y1703296I303J-1D01*
G37*
G36*
G01X1524875D02*
X1528575D01*
G02X1528878Y1702994I1J-302D01*
G01Y1692988D01*
G02X1528575Y1692686I-303J1D01*
G01X1524875D01*
G02X1524572Y1692988I-1J302D01*
G01Y1695400D01*
G02X1524559Y1695629I2003J229D01*
G02X1524572Y1695858I2016J0D01*
G01Y1700125D01*
G02X1524559Y1700354I2003J229D01*
G02X1524572Y1700583I2016J0D01*
G01Y1702994D01*
G02X1524875Y1703296I303J-1D01*
G37*
G36*
G01X1540623D02*
X1544323D01*
G02X1544626Y1702994I1J-302D01*
G01Y1692988D01*
G02X1544323Y1692686I-303J1D01*
G01X1540623D01*
G02X1540320Y1692988I-1J302D01*
G01Y1695400D01*
G02X1540307Y1695629I2003J229D01*
G02X1540320Y1695858I2016J0D01*
G01Y1700125D01*
G02X1540307Y1700354I2003J229D01*
G02X1540320Y1700583I2016J0D01*
G01Y1702994D01*
G02X1540623Y1703296I303J-1D01*
G37*
G36*
G01X1556371D02*
X1560071D01*
G02X1560374Y1702994I1J-302D01*
G01Y1692988D01*
G02X1560071Y1692686I-303J1D01*
G01X1556371D01*
G02X1556068Y1692988I-1J302D01*
G01Y1695400D01*
G02X1556055Y1695629I2003J229D01*
G02X1556068Y1695858I2016J0D01*
G01Y1700125D01*
G02X1556055Y1700354I2003J229D01*
G02X1556068Y1700583I2016J0D01*
G01Y1702994D01*
G02X1556371Y1703296I303J-1D01*
G37*
G36*
G01X229206Y1713532D02*
X232906D01*
G02X233208Y1713230I0J-302D01*
G01Y1703224D01*
G02X232906Y1702922I-302J0D01*
G01X229206D01*
G02X228904Y1703224I0J302D01*
G01Y1705629D01*
G02X228890Y1705866I2002J237D01*
G02X228904Y1706103I2016J0D01*
G01Y1710353D01*
G02X228890Y1710590I2002J237D01*
G02X228904Y1710827I2016J0D01*
G01Y1713230D01*
G02X229206Y1713532I302J0D01*
G37*
G36*
G01X244954D02*
X248654D01*
G02X248956Y1713230I0J-302D01*
G01Y1703224D01*
G02X248654Y1702922I-302J0D01*
G01X244954D01*
G02X244652Y1703224I0J302D01*
G01Y1705629D01*
G02X244638Y1705866I2002J237D01*
G02X244652Y1706103I2016J0D01*
G01Y1710353D01*
G02X244638Y1710590I2002J237D01*
G02X244652Y1710827I2016J0D01*
G01Y1713230D01*
G02X244954Y1713532I302J0D01*
G37*
G36*
G01X260702D02*
X264402D01*
G02X264704Y1713230I0J-302D01*
G01Y1703224D01*
G02X264402Y1702922I-302J0D01*
G01X260702D01*
G02X260400Y1703224I0J302D01*
G01Y1705629D01*
G02X260386Y1705866I2002J237D01*
G02X260400Y1706103I2016J0D01*
G01Y1710353D01*
G02X260386Y1710590I2002J237D01*
G02X260400Y1710827I2016J0D01*
G01Y1713230D01*
G02X260702Y1713532I302J0D01*
G37*
G36*
G01X276450D02*
X280150D01*
G02X280452Y1713230I0J-302D01*
G01Y1703224D01*
G02X280150Y1702922I-302J0D01*
G01X276450D01*
G02X276148Y1703224I0J302D01*
G01Y1705629D01*
G02X276134Y1705866I2002J237D01*
G02X276148Y1706103I2016J0D01*
G01Y1710353D01*
G02X276134Y1710590I2002J237D01*
G02X276148Y1710827I2016J0D01*
G01Y1713230D01*
G02X276450Y1713532I302J0D01*
G37*
G36*
G01X560308D02*
X564008D01*
G02X564310Y1713230I0J-302D01*
G01Y1703224D01*
G02X564008Y1702922I-302J0D01*
G01X560308D01*
G02X560006Y1703224I0J302D01*
G01Y1705256D01*
G02X559915Y1705866I2002J610D01*
G02X560638Y1707448I2092J0D01*
G01X560956Y1708097D01*
G03Y1708359I-267J131D01*
G01X560638Y1709008D01*
G02X559915Y1710590I1369J1582D01*
G02X560006Y1711200I2093J0D01*
G01Y1713230D01*
G02X560308Y1713532I302J0D01*
G37*
G36*
G01X576056D02*
X579756D01*
G02X580058Y1713230I0J-302D01*
G01Y1703224D01*
G02X579756Y1702922I-302J0D01*
G01X576056D01*
G02X575754Y1703224I0J302D01*
G01Y1705256D01*
G02X575663Y1705866I2002J610D01*
G02X576386Y1707448I2092J0D01*
G01X576704Y1708097D01*
G03Y1708359I-267J131D01*
G01X576386Y1709008D01*
G02X575663Y1710590I1369J1582D01*
G02X575754Y1711200I2093J0D01*
G01Y1713230D01*
G02X576056Y1713532I302J0D01*
G37*
G36*
G01X591804D02*
X595504D01*
G02X595806Y1713230I0J-302D01*
G01Y1703224D01*
G02X595504Y1702922I-302J0D01*
G01X591804D01*
G02X591502Y1703224I0J302D01*
G01Y1705256D01*
G02X591411Y1705866I2002J610D01*
G02X592134Y1707448I2092J0D01*
G01X592452Y1708097D01*
G03Y1708359I-267J131D01*
G01X592134Y1709008D01*
G02X591411Y1710590I1369J1582D01*
G02X591502Y1711200I2093J0D01*
G01Y1713230D01*
G02X591804Y1713532I302J0D01*
G37*
G36*
G01X607552D02*
X611252D01*
G02X611554Y1713230I0J-302D01*
G01Y1703224D01*
G02X611252Y1702922I-302J0D01*
G01X607552D01*
G02X607250Y1703224I0J302D01*
G01Y1705256D01*
G02X607159Y1705866I2002J610D01*
G02X607882Y1707448I2092J0D01*
G01X608200Y1708097D01*
G03Y1708359I-267J131D01*
G01X607882Y1709008D01*
G02X607159Y1710590I1369J1582D01*
G02X607250Y1711200I2093J0D01*
G01Y1713230D01*
G02X607552Y1713532I302J0D01*
G37*
G36*
G01X1237080D02*
X1240780D01*
G02X1241082Y1713230I0J-302D01*
G01Y1703224D01*
G02X1240780Y1702922I-302J0D01*
G01X1237080D01*
G02X1236778Y1703224I0J302D01*
G01Y1705629D01*
G02X1236764Y1705866I2002J237D01*
G02X1236778Y1706103I2016J0D01*
G01Y1710353D01*
G02X1236764Y1710590I2002J237D01*
G02X1236778Y1710827I2016J0D01*
G01Y1713230D01*
G02X1237080Y1713532I302J0D01*
G37*
G36*
G01X1252828D02*
X1256528D01*
G02X1256830Y1713230I0J-302D01*
G01Y1703224D01*
G02X1256528Y1702922I-302J0D01*
G01X1252828D01*
G02X1252526Y1703224I0J302D01*
G01Y1705629D01*
G02X1252512Y1705866I2002J237D01*
G02X1252526Y1706103I2016J0D01*
G01Y1710353D01*
G02X1252512Y1710590I2002J237D01*
G02X1252526Y1710827I2016J0D01*
G01Y1713230D01*
G02X1252828Y1713532I302J0D01*
G37*
G36*
G01X1268576D02*
X1272276D01*
G02X1272578Y1713230I0J-302D01*
G01Y1703224D01*
G02X1272276Y1702922I-302J0D01*
G01X1268576D01*
G02X1268274Y1703224I0J302D01*
G01Y1705629D01*
G02X1268260Y1705866I2002J237D01*
G02X1268274Y1706103I2016J0D01*
G01Y1710353D01*
G02X1268260Y1710590I2002J237D01*
G02X1268274Y1710827I2016J0D01*
G01Y1713230D01*
G02X1268576Y1713532I302J0D01*
G37*
G36*
G01X1284324D02*
X1288024D01*
G02X1288326Y1713230I0J-302D01*
G01Y1703224D01*
G02X1288024Y1702922I-302J0D01*
G01X1284324D01*
G02X1284022Y1703224I0J302D01*
G01Y1705629D01*
G02X1284008Y1705866I2002J237D01*
G02X1284022Y1706103I2016J0D01*
G01Y1710353D01*
G02X1284008Y1710590I2002J237D01*
G02X1284022Y1710827I2016J0D01*
G01Y1713230D01*
G02X1284324Y1713532I302J0D01*
G37*
G36*
G01X1568182D02*
X1571882D01*
G02X1572184Y1713230I0J-302D01*
G01Y1703224D01*
G02X1571882Y1702922I-302J0D01*
G01X1568182D01*
G02X1567880Y1703224I0J302D01*
G01Y1705256D01*
G02X1567789Y1705866I2002J610D01*
G02X1568512Y1707448I2092J0D01*
G01X1568830Y1708097D01*
G03Y1708359I-267J131D01*
G01X1568512Y1709008D01*
G02X1567789Y1710590I1369J1582D01*
G02X1567880Y1711200I2093J0D01*
G01Y1713230D01*
G02X1568182Y1713532I302J0D01*
G37*
G36*
G01X1583930D02*
X1587630D01*
G02X1587932Y1713230I0J-302D01*
G01Y1703224D01*
G02X1587630Y1702922I-302J0D01*
G01X1583930D01*
G02X1583628Y1703224I0J302D01*
G01Y1705256D01*
G02X1583537Y1705866I2002J610D01*
G02X1584260Y1707448I2092J0D01*
G01X1584578Y1708097D01*
G03Y1708359I-267J131D01*
G01X1584260Y1709008D01*
G02X1583537Y1710590I1369J1582D01*
G02X1583628Y1711200I2093J0D01*
G01Y1713230D01*
G02X1583930Y1713532I302J0D01*
G37*
G36*
G01X1599678D02*
X1603378D01*
G02X1603680Y1713230I0J-302D01*
G01Y1703224D01*
G02X1603378Y1702922I-302J0D01*
G01X1599678D01*
G02X1599376Y1703224I0J302D01*
G01Y1705256D01*
G02X1599285Y1705866I2002J610D01*
G02X1600008Y1707448I2092J0D01*
G01X1600326Y1708097D01*
G03Y1708359I-267J131D01*
G01X1600008Y1709008D01*
G02X1599285Y1710590I1369J1582D01*
G02X1599376Y1711200I2093J0D01*
G01Y1713230D01*
G02X1599678Y1713532I302J0D01*
G37*
G36*
G01X1615426D02*
X1619126D01*
G02X1619428Y1713230I0J-302D01*
G01Y1703224D01*
G02X1619126Y1702922I-302J0D01*
G01X1615426D01*
G02X1615124Y1703224I0J302D01*
G01Y1705256D01*
G02X1615033Y1705866I2002J610D01*
G02X1615756Y1707448I2092J0D01*
G01X1616074Y1708097D01*
G03Y1708359I-267J131D01*
G01X1615756Y1709008D01*
G02X1615033Y1710590I1369J1582D01*
G02X1615124Y1711200I2093J0D01*
G01Y1713230D01*
G02X1615426Y1713532I302J0D01*
G37*
G36*
G01X296135D02*
X299835D01*
G02X300138Y1713230I1J-302D01*
G01Y1703224D01*
G02X299835Y1702922I-303J1D01*
G01X296135D01*
G02X295832Y1703224I-1J302D01*
G01Y1705637D01*
G02X295819Y1705866I2003J229D01*
G02X295832Y1706095I2016J0D01*
G01Y1710361D01*
G02X295819Y1710590I2003J229D01*
G02X295832Y1710819I2016J0D01*
G01Y1713230D01*
G02X296135Y1713532I303J-1D01*
G37*
G36*
G01X311883D02*
X315583D01*
G02X315886Y1713230I1J-302D01*
G01Y1703224D01*
G02X315583Y1702922I-303J1D01*
G01X311883D01*
G02X311580Y1703224I-1J302D01*
G01Y1705637D01*
G02X311567Y1705866I2003J229D01*
G02X311580Y1706095I2016J0D01*
G01Y1710361D01*
G02X311567Y1710590I2003J229D01*
G02X311580Y1710819I2016J0D01*
G01Y1713230D01*
G02X311883Y1713532I303J-1D01*
G37*
G36*
G01X327631D02*
X331331D01*
G02X331634Y1713230I1J-302D01*
G01Y1703224D01*
G02X331331Y1702922I-303J1D01*
G01X327631D01*
G02X327328Y1703224I-1J302D01*
G01Y1705637D01*
G02X327315Y1705866I2003J229D01*
G02X327328Y1706095I2016J0D01*
G01Y1710361D01*
G02X327315Y1710590I2003J229D01*
G02X327328Y1710819I2016J0D01*
G01Y1713230D01*
G02X327631Y1713532I303J-1D01*
G37*
G36*
G01X343379D02*
X347079D01*
G02X347382Y1713230I1J-302D01*
G01Y1703224D01*
G02X347079Y1702922I-303J1D01*
G01X343379D01*
G02X343076Y1703224I-1J302D01*
G01Y1705637D01*
G02X343063Y1705866I2003J229D01*
G02X343076Y1706095I2016J0D01*
G01Y1710361D01*
G02X343063Y1710590I2003J229D01*
G02X343076Y1710819I2016J0D01*
G01Y1713230D01*
G02X343379Y1713532I303J-1D01*
G37*
G36*
G01X493379D02*
X497079D01*
G02X497382Y1713230I1J-302D01*
G01Y1703224D01*
G02X497079Y1702922I-303J1D01*
G01X493379D01*
G02X493076Y1703224I-1J302D01*
G01Y1705259D01*
G02X492986Y1705866I2002J607D01*
G02X493709Y1707448I2092J0D01*
G01X494027Y1708097D01*
G03Y1708359I-267J131D01*
G01X493709Y1709008D01*
G02X492986Y1710590I1369J1582D01*
G02X493076Y1711197I2092J0D01*
G01Y1713230D01*
G02X493379Y1713532I303J-1D01*
G37*
G36*
G01X509127D02*
X512827D01*
G02X513130Y1713230I1J-302D01*
G01Y1703224D01*
G02X512827Y1702922I-303J1D01*
G01X509127D01*
G02X508824Y1703224I-1J302D01*
G01Y1705259D01*
G02X508734Y1705866I2002J607D01*
G02X509457Y1707448I2092J0D01*
G01X509775Y1708097D01*
G03Y1708359I-267J131D01*
G01X509457Y1709008D01*
G02X508734Y1710590I1369J1582D01*
G02X508824Y1711197I2092J0D01*
G01Y1713230D01*
G02X509127Y1713532I303J-1D01*
G37*
G36*
G01X524875D02*
X528575D01*
G02X528878Y1713230I1J-302D01*
G01Y1703224D01*
G02X528575Y1702922I-303J1D01*
G01X524875D01*
G02X524572Y1703224I-1J302D01*
G01Y1705259D01*
G02X524482Y1705866I2002J607D01*
G02X525205Y1707448I2092J0D01*
G01X525523Y1708097D01*
G03Y1708359I-267J131D01*
G01X525205Y1709008D01*
G02X524482Y1710590I1369J1582D01*
G02X524572Y1711197I2092J0D01*
G01Y1713230D01*
G02X524875Y1713532I303J-1D01*
G37*
G36*
G01X540623D02*
X544323D01*
G02X544626Y1713230I1J-302D01*
G01Y1703224D01*
G02X544323Y1702922I-303J1D01*
G01X540623D01*
G02X540320Y1703224I-1J302D01*
G01Y1705259D01*
G02X540230Y1705866I2002J607D01*
G02X540953Y1707448I2092J0D01*
G01X541271Y1708097D01*
G03Y1708359I-267J131D01*
G01X540953Y1709008D01*
G02X540230Y1710590I1369J1582D01*
G02X540320Y1711197I2092J0D01*
G01Y1713230D01*
G02X540623Y1713532I303J-1D01*
G37*
G36*
G01X1304009D02*
X1307709D01*
G02X1308012Y1713230I1J-302D01*
G01Y1703224D01*
G02X1307709Y1702922I-303J1D01*
G01X1304009D01*
G02X1303706Y1703224I-1J302D01*
G01Y1705637D01*
G02X1303693Y1705866I2003J229D01*
G02X1303706Y1706095I2016J0D01*
G01Y1710361D01*
G02X1303693Y1710590I2003J229D01*
G02X1303706Y1710819I2016J0D01*
G01Y1713230D01*
G02X1304009Y1713532I303J-1D01*
G37*
G36*
G01X1319757D02*
X1323457D01*
G02X1323760Y1713230I1J-302D01*
G01Y1703224D01*
G02X1323457Y1702922I-303J1D01*
G01X1319757D01*
G02X1319454Y1703224I-1J302D01*
G01Y1705637D01*
G02X1319441Y1705866I2003J229D01*
G02X1319454Y1706095I2016J0D01*
G01Y1710361D01*
G02X1319441Y1710590I2003J229D01*
G02X1319454Y1710819I2016J0D01*
G01Y1713230D01*
G02X1319757Y1713532I303J-1D01*
G37*
G36*
G01X1335505D02*
X1339205D01*
G02X1339508Y1713230I1J-302D01*
G01Y1703224D01*
G02X1339205Y1702922I-303J1D01*
G01X1335505D01*
G02X1335202Y1703224I-1J302D01*
G01Y1705637D01*
G02X1335189Y1705866I2003J229D01*
G02X1335202Y1706095I2016J0D01*
G01Y1710361D01*
G02X1335189Y1710590I2003J229D01*
G02X1335202Y1710819I2016J0D01*
G01Y1713230D01*
G02X1335505Y1713532I303J-1D01*
G37*
G36*
G01X1351253D02*
X1354953D01*
G02X1355256Y1713230I1J-302D01*
G01Y1703224D01*
G02X1354953Y1702922I-303J1D01*
G01X1351253D01*
G02X1350950Y1703224I-1J302D01*
G01Y1705637D01*
G02X1350937Y1705866I2003J229D01*
G02X1350950Y1706095I2016J0D01*
G01Y1710361D01*
G02X1350937Y1710590I2003J229D01*
G02X1350950Y1710819I2016J0D01*
G01Y1713230D01*
G02X1351253Y1713532I303J-1D01*
G37*
G36*
G01X1501253D02*
X1504953D01*
G02X1505256Y1713230I1J-302D01*
G01Y1703224D01*
G02X1504953Y1702922I-303J1D01*
G01X1501253D01*
G02X1500950Y1703224I-1J302D01*
G01Y1705259D01*
G02X1500860Y1705866I2002J607D01*
G02X1501583Y1707448I2092J0D01*
G01X1501901Y1708097D01*
G03Y1708359I-267J131D01*
G01X1501583Y1709008D01*
G02X1500860Y1710590I1369J1582D01*
G02X1500950Y1711197I2092J0D01*
G01Y1713230D01*
G02X1501253Y1713532I303J-1D01*
G37*
G36*
G01X1517001D02*
X1520701D01*
G02X1521004Y1713230I1J-302D01*
G01Y1703224D01*
G02X1520701Y1702922I-303J1D01*
G01X1517001D01*
G02X1516698Y1703224I-1J302D01*
G01Y1705259D01*
G02X1516608Y1705866I2002J607D01*
G02X1517331Y1707448I2092J0D01*
G01X1517649Y1708097D01*
G03Y1708359I-267J131D01*
G01X1517331Y1709008D01*
G02X1516608Y1710590I1369J1582D01*
G02X1516698Y1711197I2092J0D01*
G01Y1713230D01*
G02X1517001Y1713532I303J-1D01*
G37*
G36*
G01X1532749D02*
X1536449D01*
G02X1536752Y1713230I1J-302D01*
G01Y1703224D01*
G02X1536449Y1702922I-303J1D01*
G01X1532749D01*
G02X1532446Y1703224I-1J302D01*
G01Y1705259D01*
G02X1532356Y1705866I2002J607D01*
G02X1533079Y1707448I2092J0D01*
G01X1533397Y1708097D01*
G03Y1708359I-267J131D01*
G01X1533079Y1709008D01*
G02X1532356Y1710590I1369J1582D01*
G02X1532446Y1711197I2092J0D01*
G01Y1713230D01*
G02X1532749Y1713532I303J-1D01*
G37*
G36*
G01X1548497D02*
X1552197D01*
G02X1552500Y1713230I1J-302D01*
G01Y1703224D01*
G02X1552197Y1702922I-303J1D01*
G01X1548497D01*
G02X1548194Y1703224I-1J302D01*
G01Y1705259D01*
G02X1548104Y1705866I2002J607D01*
G02X1548827Y1707448I2092J0D01*
G01X1549145Y1708097D01*
G03Y1708359I-267J131D01*
G01X1548827Y1709008D01*
G02X1548104Y1710590I1369J1582D01*
G02X1548194Y1711197I2092J0D01*
G01Y1713230D01*
G02X1548497Y1713532I303J-1D01*
G37*
G36*
G01X237080Y1717470D02*
X240780D01*
G02X241082Y1717167I-1J-303D01*
G01Y1707161D01*
G02X240780Y1706858I-302J-1D01*
G01X237080D01*
G02X236778Y1707161I1J303D01*
G01Y1709566D01*
G02X236764Y1709803I2002J237D01*
G02X236778Y1710040I2016J0D01*
G01Y1714290D01*
G02X236764Y1714527I2002J237D01*
G02X236778Y1714764I2016J0D01*
G01Y1717167D01*
G02X237080Y1717470I302J1D01*
G37*
G36*
G01X252828D02*
X256528D01*
G02X256830Y1717167I-1J-303D01*
G01Y1707161D01*
G02X256528Y1706858I-302J-1D01*
G01X252828D01*
G02X252526Y1707161I1J303D01*
G01Y1709566D01*
G02X252512Y1709803I2002J237D01*
G02X252526Y1710040I2016J0D01*
G01Y1714290D01*
G02X252512Y1714527I2002J237D01*
G02X252526Y1714764I2016J0D01*
G01Y1717167D01*
G02X252828Y1717470I302J1D01*
G37*
G36*
G01X268576D02*
X272276D01*
G02X272578Y1717167I-1J-303D01*
G01Y1707161D01*
G02X272276Y1706858I-302J-1D01*
G01X268576D01*
G02X268274Y1707161I1J303D01*
G01Y1709566D01*
G02X268260Y1709803I2002J237D01*
G02X268274Y1710040I2016J0D01*
G01Y1714290D01*
G02X268260Y1714527I2002J237D01*
G02X268274Y1714764I2016J0D01*
G01Y1717167D01*
G02X268576Y1717470I302J1D01*
G37*
G36*
G01X284324D02*
X288024D01*
G02X288326Y1717167I-1J-303D01*
G01Y1707161D01*
G02X288024Y1706858I-302J-1D01*
G01X284324D01*
G02X284022Y1707161I1J303D01*
G01Y1709566D01*
G02X284008Y1709803I2002J237D01*
G02X284022Y1710040I2016J0D01*
G01Y1714290D01*
G02X284008Y1714527I2002J237D01*
G02X284022Y1714764I2016J0D01*
G01Y1717167D01*
G02X284324Y1717470I302J1D01*
G37*
G36*
G01X304009D02*
X307709D01*
G02X308012Y1717167I0J-303D01*
G01Y1707161D01*
G02X307709Y1706858I-303J0D01*
G01X304009D01*
G02X303706Y1707161I0J303D01*
G01Y1709574D01*
G02X303693Y1709803I2003J229D01*
G02X303706Y1710032I2016J0D01*
G01Y1714298D01*
G02X303693Y1714527I2003J229D01*
G02X303706Y1714756I2016J0D01*
G01Y1717167D01*
G02X304009Y1717470I303J0D01*
G37*
G36*
G01X319757D02*
X323457D01*
G02X323760Y1717167I0J-303D01*
G01Y1707161D01*
G02X323457Y1706858I-303J0D01*
G01X319757D01*
G02X319454Y1707161I0J303D01*
G01Y1709574D01*
G02X319441Y1709803I2003J229D01*
G02X319454Y1710032I2016J0D01*
G01Y1714298D01*
G02X319441Y1714527I2003J229D01*
G02X319454Y1714756I2016J0D01*
G01Y1717167D01*
G02X319757Y1717470I303J0D01*
G37*
G36*
G01X335505D02*
X339205D01*
G02X339508Y1717167I0J-303D01*
G01Y1707161D01*
G02X339205Y1706858I-303J0D01*
G01X335505D01*
G02X335202Y1707161I0J303D01*
G01Y1709574D01*
G02X335189Y1709803I2003J229D01*
G02X335202Y1710032I2016J0D01*
G01Y1714298D01*
G02X335189Y1714527I2003J229D01*
G02X335202Y1714756I2016J0D01*
G01Y1717167D01*
G02X335505Y1717470I303J0D01*
G37*
G36*
G01X351253D02*
X354953D01*
G02X355256Y1717167I0J-303D01*
G01Y1707161D01*
G02X354953Y1706858I-303J0D01*
G01X351253D01*
G02X350950Y1707161I0J303D01*
G01Y1709574D01*
G02X350937Y1709803I2003J229D01*
G02X350950Y1710032I2016J0D01*
G01Y1714298D01*
G02X350937Y1714527I2003J229D01*
G02X350950Y1714756I2016J0D01*
G01Y1717167D01*
G02X351253Y1717470I303J0D01*
G37*
G36*
G01X501253D02*
X504953D01*
G02X505256Y1717167I0J-303D01*
G01Y1707161D01*
G02X504953Y1706858I-303J0D01*
G01X501253D01*
G02X500950Y1707161I0J303D01*
G01Y1709196D01*
G02X500860Y1709803I2002J607D01*
G02X501583Y1711385I2092J0D01*
G01X501901Y1712034D01*
G03Y1712296I-267J131D01*
G01X501583Y1712945D01*
G02X500860Y1714527I1369J1582D01*
G02X500950Y1715134I2092J0D01*
G01Y1717167D01*
G02X501253Y1717470I303J0D01*
G37*
G36*
G01X517001D02*
X520701D01*
G02X521004Y1717167I0J-303D01*
G01Y1707161D01*
G02X520701Y1706858I-303J0D01*
G01X517001D01*
G02X516698Y1707161I0J303D01*
G01Y1709196D01*
G02X516608Y1709803I2002J607D01*
G02X517331Y1711385I2092J0D01*
G01X517649Y1712034D01*
G03Y1712296I-267J131D01*
G01X517331Y1712945D01*
G02X516608Y1714527I1369J1582D01*
G02X516698Y1715134I2092J0D01*
G01Y1717167D01*
G02X517001Y1717470I303J0D01*
G37*
G36*
G01X532749D02*
X536449D01*
G02X536752Y1717167I0J-303D01*
G01Y1707161D01*
G02X536449Y1706858I-303J0D01*
G01X532749D01*
G02X532446Y1707161I0J303D01*
G01Y1709196D01*
G02X532356Y1709803I2002J607D01*
G02X533079Y1711385I2092J0D01*
G01X533397Y1712034D01*
G03Y1712296I-267J131D01*
G01X533079Y1712945D01*
G02X532356Y1714527I1369J1582D01*
G02X532446Y1715134I2092J0D01*
G01Y1717167D01*
G02X532749Y1717470I303J0D01*
G37*
G36*
G01X548497D02*
X552197D01*
G02X552500Y1717167I0J-303D01*
G01Y1707161D01*
G02X552197Y1706858I-303J0D01*
G01X548497D01*
G02X548194Y1707161I0J303D01*
G01Y1709196D01*
G02X548104Y1709803I2002J607D01*
G02X548827Y1711385I2092J0D01*
G01X549145Y1712034D01*
G03Y1712296I-267J131D01*
G01X548827Y1712945D01*
G02X548104Y1714527I1369J1582D01*
G02X548194Y1715134I2092J0D01*
G01Y1717167D01*
G02X548497Y1717470I303J0D01*
G37*
G36*
G01X568182D02*
X571882D01*
G02X572184Y1717167I-1J-303D01*
G01Y1707161D01*
G02X571882Y1706858I-302J-1D01*
G01X568182D01*
G02X567880Y1707161I1J303D01*
G01Y1709193D01*
G02X567789Y1709803I2002J610D01*
G02X568512Y1711385I2092J0D01*
G01X568830Y1712034D01*
G03Y1712296I-267J131D01*
G01X568512Y1712945D01*
G02X567789Y1714527I1369J1582D01*
G02X567880Y1715137I2093J0D01*
G01Y1717167D01*
G02X568182Y1717470I302J1D01*
G37*
G36*
G01X583930D02*
X587630D01*
G02X587932Y1717167I-1J-303D01*
G01Y1707161D01*
G02X587630Y1706858I-302J-1D01*
G01X583930D01*
G02X583628Y1707161I1J303D01*
G01Y1709193D01*
G02X583537Y1709803I2002J610D01*
G02X584260Y1711385I2092J0D01*
G01X584578Y1712034D01*
G03Y1712296I-267J131D01*
G01X584260Y1712945D01*
G02X583537Y1714527I1369J1582D01*
G02X583628Y1715137I2093J0D01*
G01Y1717167D01*
G02X583930Y1717470I302J1D01*
G37*
G36*
G01X599678D02*
X603378D01*
G02X603680Y1717167I-1J-303D01*
G01Y1707161D01*
G02X603378Y1706858I-302J-1D01*
G01X599678D01*
G02X599376Y1707161I1J303D01*
G01Y1709193D01*
G02X599285Y1709803I2002J610D01*
G02X600008Y1711385I2092J0D01*
G01X600326Y1712034D01*
G03Y1712296I-267J131D01*
G01X600008Y1712945D01*
G02X599285Y1714527I1369J1582D01*
G02X599376Y1715137I2093J0D01*
G01Y1717167D01*
G02X599678Y1717470I302J1D01*
G37*
G36*
G01X615426D02*
X619126D01*
G02X619428Y1717167I-1J-303D01*
G01Y1707161D01*
G02X619126Y1706858I-302J-1D01*
G01X615426D01*
G02X615124Y1707161I1J303D01*
G01Y1709193D01*
G02X615033Y1709803I2002J610D01*
G02X615756Y1711385I2092J0D01*
G01X616074Y1712034D01*
G03Y1712296I-267J131D01*
G01X615756Y1712945D01*
G02X615033Y1714527I1369J1582D01*
G02X615124Y1715137I2093J0D01*
G01Y1717167D01*
G02X615426Y1717470I302J1D01*
G37*
G36*
G01X1244954D02*
X1248654D01*
G02X1248956Y1717167I-1J-303D01*
G01Y1707161D01*
G02X1248654Y1706858I-302J-1D01*
G01X1244954D01*
G02X1244652Y1707161I1J303D01*
G01Y1709566D01*
G02X1244638Y1709803I2002J237D01*
G02X1244652Y1710040I2016J0D01*
G01Y1714290D01*
G02X1244638Y1714527I2002J237D01*
G02X1244652Y1714764I2016J0D01*
G01Y1717167D01*
G02X1244954Y1717470I302J1D01*
G37*
G36*
G01X1260702D02*
X1264402D01*
G02X1264704Y1717167I-1J-303D01*
G01Y1707161D01*
G02X1264402Y1706858I-302J-1D01*
G01X1260702D01*
G02X1260400Y1707161I1J303D01*
G01Y1709566D01*
G02X1260386Y1709803I2002J237D01*
G02X1260400Y1710040I2016J0D01*
G01Y1714290D01*
G02X1260386Y1714527I2002J237D01*
G02X1260400Y1714764I2016J0D01*
G01Y1717167D01*
G02X1260702Y1717470I302J1D01*
G37*
G36*
G01X1276450D02*
X1280150D01*
G02X1280452Y1717167I-1J-303D01*
G01Y1707161D01*
G02X1280150Y1706858I-302J-1D01*
G01X1276450D01*
G02X1276148Y1707161I1J303D01*
G01Y1709566D01*
G02X1276134Y1709803I2002J237D01*
G02X1276148Y1710040I2016J0D01*
G01Y1714290D01*
G02X1276134Y1714527I2002J237D01*
G02X1276148Y1714764I2016J0D01*
G01Y1717167D01*
G02X1276450Y1717470I302J1D01*
G37*
G36*
G01X1292198D02*
X1295898D01*
G02X1296200Y1717167I-1J-303D01*
G01Y1707161D01*
G02X1295898Y1706858I-302J-1D01*
G01X1292198D01*
G02X1291896Y1707161I1J303D01*
G01Y1709566D01*
G02X1291882Y1709803I2002J237D01*
G02X1291896Y1710040I2016J0D01*
G01Y1714290D01*
G02X1291882Y1714527I2002J237D01*
G02X1291896Y1714764I2016J0D01*
G01Y1717167D01*
G02X1292198Y1717470I302J1D01*
G37*
G36*
G01X1311883D02*
X1315583D01*
G02X1315886Y1717167I0J-303D01*
G01Y1707161D01*
G02X1315583Y1706858I-303J0D01*
G01X1311883D01*
G02X1311580Y1707161I0J303D01*
G01Y1709574D01*
G02X1311567Y1709803I2003J229D01*
G02X1311580Y1710032I2016J0D01*
G01Y1714298D01*
G02X1311567Y1714527I2003J229D01*
G02X1311580Y1714756I2016J0D01*
G01Y1717167D01*
G02X1311883Y1717470I303J0D01*
G37*
G36*
G01X1327631D02*
X1331331D01*
G02X1331634Y1717167I0J-303D01*
G01Y1707161D01*
G02X1331331Y1706858I-303J0D01*
G01X1327631D01*
G02X1327328Y1707161I0J303D01*
G01Y1709574D01*
G02X1327315Y1709803I2003J229D01*
G02X1327328Y1710032I2016J0D01*
G01Y1714298D01*
G02X1327315Y1714527I2003J229D01*
G02X1327328Y1714756I2016J0D01*
G01Y1717167D01*
G02X1327631Y1717470I303J0D01*
G37*
G36*
G01X1343379D02*
X1347079D01*
G02X1347382Y1717167I0J-303D01*
G01Y1707161D01*
G02X1347079Y1706858I-303J0D01*
G01X1343379D01*
G02X1343076Y1707161I0J303D01*
G01Y1709574D01*
G02X1343063Y1709803I2003J229D01*
G02X1343076Y1710032I2016J0D01*
G01Y1714298D01*
G02X1343063Y1714527I2003J229D01*
G02X1343076Y1714756I2016J0D01*
G01Y1717167D01*
G02X1343379Y1717470I303J0D01*
G37*
G36*
G01X1359127D02*
X1362827D01*
G02X1363130Y1717167I0J-303D01*
G01Y1707161D01*
G02X1362827Y1706858I-303J0D01*
G01X1359127D01*
G02X1358824Y1707161I0J303D01*
G01Y1709574D01*
G02X1358811Y1709803I2003J229D01*
G02X1358824Y1710032I2016J0D01*
G01Y1714298D01*
G02X1358811Y1714527I2003J229D01*
G02X1358824Y1714756I2016J0D01*
G01Y1717167D01*
G02X1359127Y1717470I303J0D01*
G37*
G36*
G01X1509127D02*
X1512827D01*
G02X1513130Y1717167I0J-303D01*
G01Y1707161D01*
G02X1512827Y1706858I-303J0D01*
G01X1509127D01*
G02X1508824Y1707161I0J303D01*
G01Y1709196D01*
G02X1508734Y1709803I2002J607D01*
G02X1509457Y1711385I2092J0D01*
G01X1509775Y1712034D01*
G03Y1712296I-267J131D01*
G01X1509457Y1712945D01*
G02X1508734Y1714527I1369J1582D01*
G02X1508824Y1715134I2092J0D01*
G01Y1717167D01*
G02X1509127Y1717470I303J0D01*
G37*
G36*
G01X1524875D02*
X1528575D01*
G02X1528878Y1717167I0J-303D01*
G01Y1707161D01*
G02X1528575Y1706858I-303J0D01*
G01X1524875D01*
G02X1524572Y1707161I0J303D01*
G01Y1709196D01*
G02X1524482Y1709803I2002J607D01*
G02X1525205Y1711385I2092J0D01*
G01X1525523Y1712034D01*
G03Y1712296I-267J131D01*
G01X1525205Y1712945D01*
G02X1524482Y1714527I1369J1582D01*
G02X1524572Y1715134I2092J0D01*
G01Y1717167D01*
G02X1524875Y1717470I303J0D01*
G37*
G36*
G01X1540623D02*
X1544323D01*
G02X1544626Y1717167I0J-303D01*
G01Y1707161D01*
G02X1544323Y1706858I-303J0D01*
G01X1540623D01*
G02X1540320Y1707161I0J303D01*
G01Y1709196D01*
G02X1540230Y1709803I2002J607D01*
G02X1540953Y1711385I2092J0D01*
G01X1541271Y1712034D01*
G03Y1712296I-267J131D01*
G01X1540953Y1712945D01*
G02X1540230Y1714527I1369J1582D01*
G02X1540320Y1715134I2092J0D01*
G01Y1717167D01*
G02X1540623Y1717470I303J0D01*
G37*
G36*
G01X1556371D02*
X1560071D01*
G02X1560374Y1717167I0J-303D01*
G01Y1707161D01*
G02X1560071Y1706858I-303J0D01*
G01X1556371D01*
G02X1556068Y1707161I0J303D01*
G01Y1709196D01*
G02X1555978Y1709803I2002J607D01*
G02X1556701Y1711385I2092J0D01*
G01X1557019Y1712034D01*
G03Y1712296I-267J131D01*
G01X1556701Y1712945D01*
G02X1555978Y1714527I1369J1582D01*
G02X1556068Y1715134I2092J0D01*
G01Y1717167D01*
G02X1556371Y1717470I303J0D01*
G37*
G36*
G01X1576056D02*
X1579756D01*
G02X1580058Y1717167I-1J-303D01*
G01Y1707161D01*
G02X1579756Y1706858I-302J-1D01*
G01X1576056D01*
G02X1575754Y1707161I1J303D01*
G01Y1709193D01*
G02X1575663Y1709803I2002J610D01*
G02X1576386Y1711385I2092J0D01*
G01X1576704Y1712034D01*
G03Y1712296I-267J131D01*
G01X1576386Y1712945D01*
G02X1575663Y1714527I1369J1582D01*
G02X1575754Y1715137I2093J0D01*
G01Y1717167D01*
G02X1576056Y1717470I302J1D01*
G37*
G36*
G01X1591804D02*
X1595504D01*
G02X1595806Y1717167I-1J-303D01*
G01Y1707161D01*
G02X1595504Y1706858I-302J-1D01*
G01X1591804D01*
G02X1591502Y1707161I1J303D01*
G01Y1709193D01*
G02X1591411Y1709803I2002J610D01*
G02X1592134Y1711385I2092J0D01*
G01X1592452Y1712034D01*
G03Y1712296I-267J131D01*
G01X1592134Y1712945D01*
G02X1591411Y1714527I1369J1582D01*
G02X1591502Y1715137I2093J0D01*
G01Y1717167D01*
G02X1591804Y1717470I302J1D01*
G37*
G36*
G01X1607552D02*
X1611252D01*
G02X1611554Y1717167I-1J-303D01*
G01Y1707161D01*
G02X1611252Y1706858I-302J-1D01*
G01X1607552D01*
G02X1607250Y1707161I1J303D01*
G01Y1709193D01*
G02X1607159Y1709803I2002J610D01*
G02X1607882Y1711385I2092J0D01*
G01X1608200Y1712034D01*
G03Y1712296I-267J131D01*
G01X1607882Y1712945D01*
G02X1607159Y1714527I1369J1582D01*
G02X1607250Y1715137I2093J0D01*
G01Y1717167D01*
G02X1607552Y1717470I302J1D01*
G37*
G36*
G01X1623300D02*
X1627000D01*
G02X1627302Y1717167I-1J-303D01*
G01Y1707161D01*
G02X1627000Y1706858I-302J-1D01*
G01X1623300D01*
G02X1622998Y1707161I1J303D01*
G01Y1709193D01*
G02X1622907Y1709803I2002J610D01*
G02X1623630Y1711385I2092J0D01*
G01X1623948Y1712034D01*
G03Y1712296I-267J131D01*
G01X1623630Y1712945D01*
G02X1622907Y1714527I1369J1582D01*
G02X1622998Y1715137I2093J0D01*
G01Y1717167D01*
G02X1623300Y1717470I302J1D01*
G37*
G36*
G01X229206Y1727706D02*
X232906D01*
G02X233208Y1727404I0J-302D01*
G01Y1717398D01*
G02X232906Y1717096I-302J0D01*
G01X229206D01*
G02X228904Y1717398I0J302D01*
G01Y1719429D01*
G02X228813Y1720039I2002J610D01*
G02X229535Y1721621I2094J0D01*
G01X229854Y1722271D01*
G03Y1722533I-267J131D01*
G01X229537Y1723180D01*
G02X228813Y1724763I1369J1583D01*
G02X228904Y1725373I2093J0D01*
G01Y1727404D01*
G02X229206Y1727706I302J0D01*
G37*
G36*
G01X244954D02*
X248654D01*
G02X248956Y1727404I0J-302D01*
G01Y1717398D01*
G02X248654Y1717096I-302J0D01*
G01X244954D01*
G02X244652Y1717398I0J302D01*
G01Y1719429D01*
G02X244561Y1720039I2002J610D01*
G02X245283Y1721621I2094J0D01*
G01X245602Y1722271D01*
G03Y1722533I-267J131D01*
G01X245285Y1723180D01*
G02X244561Y1724763I1369J1583D01*
G02X244652Y1725373I2093J0D01*
G01Y1727404D01*
G02X244954Y1727706I302J0D01*
G37*
G36*
G01X260702D02*
X264402D01*
G02X264704Y1727404I0J-302D01*
G01Y1717398D01*
G02X264402Y1717096I-302J0D01*
G01X260702D01*
G02X260400Y1717398I0J302D01*
G01Y1719429D01*
G02X260309Y1720039I2002J610D01*
G02X261031Y1721621I2094J0D01*
G01X261350Y1722271D01*
G03Y1722533I-267J131D01*
G01X261033Y1723180D01*
G02X260309Y1724763I1369J1583D01*
G02X260400Y1725373I2093J0D01*
G01Y1727404D01*
G02X260702Y1727706I302J0D01*
G37*
G36*
G01X276450D02*
X280150D01*
G02X280452Y1727404I0J-302D01*
G01Y1717398D01*
G02X280150Y1717096I-302J0D01*
G01X276450D01*
G02X276148Y1717398I0J302D01*
G01Y1719429D01*
G02X276057Y1720039I2002J610D01*
G02X276779Y1721621I2094J0D01*
G01X277098Y1722271D01*
G03Y1722533I-267J131D01*
G01X276781Y1723180D01*
G02X276057Y1724763I1369J1583D01*
G02X276148Y1725373I2093J0D01*
G01Y1727404D01*
G02X276450Y1727706I302J0D01*
G37*
G36*
G01X560308D02*
X564008D01*
G02X564310Y1727404I0J-302D01*
G01Y1717398D01*
G02X564008Y1717096I-302J0D01*
G01X560308D01*
G02X560006Y1717398I0J302D01*
G01Y1719802D01*
G02X559992Y1720039I2002J237D01*
G02X560006Y1720276I2016J0D01*
G01Y1724526D01*
G02X559992Y1724763I2002J237D01*
G02X560006Y1725000I2016J0D01*
G01Y1727404D01*
G02X560308Y1727706I302J0D01*
G37*
G36*
G01X576056D02*
X579756D01*
G02X580058Y1727404I0J-302D01*
G01Y1717398D01*
G02X579756Y1717096I-302J0D01*
G01X576056D01*
G02X575754Y1717398I0J302D01*
G01Y1719802D01*
G02X575740Y1720039I2002J237D01*
G02X575754Y1720276I2016J0D01*
G01Y1724526D01*
G02X575740Y1724763I2002J237D01*
G02X575754Y1725000I2016J0D01*
G01Y1727404D01*
G02X576056Y1727706I302J0D01*
G37*
G36*
G01X591804D02*
X595504D01*
G02X595806Y1727404I0J-302D01*
G01Y1717398D01*
G02X595504Y1717096I-302J0D01*
G01X591804D01*
G02X591502Y1717398I0J302D01*
G01Y1719802D01*
G02X591488Y1720039I2002J237D01*
G02X591502Y1720276I2016J0D01*
G01Y1724526D01*
G02X591488Y1724763I2002J237D01*
G02X591502Y1725000I2016J0D01*
G01Y1727404D01*
G02X591804Y1727706I302J0D01*
G37*
G36*
G01X607552D02*
X611252D01*
G02X611554Y1727404I0J-302D01*
G01Y1717398D01*
G02X611252Y1717096I-302J0D01*
G01X607552D01*
G02X607250Y1717398I0J302D01*
G01Y1719802D01*
G02X607236Y1720039I2002J237D01*
G02X607250Y1720276I2016J0D01*
G01Y1724526D01*
G02X607236Y1724763I2002J237D01*
G02X607250Y1725000I2016J0D01*
G01Y1727404D01*
G02X607552Y1727706I302J0D01*
G37*
G36*
G01X1237080D02*
X1240780D01*
G02X1241082Y1727404I0J-302D01*
G01Y1717398D01*
G02X1240780Y1717096I-302J0D01*
G01X1237080D01*
G02X1236778Y1717398I0J302D01*
G01Y1719429D01*
G02X1236687Y1720039I2002J610D01*
G02X1237409Y1721621I2094J0D01*
G01X1237728Y1722271D01*
G03Y1722533I-267J131D01*
G01X1237411Y1723180D01*
G02X1236687Y1724763I1369J1583D01*
G02X1236778Y1725373I2093J0D01*
G01Y1727404D01*
G02X1237080Y1727706I302J0D01*
G37*
G36*
G01X1252828D02*
X1256528D01*
G02X1256830Y1727404I0J-302D01*
G01Y1717398D01*
G02X1256528Y1717096I-302J0D01*
G01X1252828D01*
G02X1252526Y1717398I0J302D01*
G01Y1719429D01*
G02X1252435Y1720039I2002J610D01*
G02X1253157Y1721621I2094J0D01*
G01X1253476Y1722271D01*
G03Y1722533I-267J131D01*
G01X1253159Y1723180D01*
G02X1252435Y1724763I1369J1583D01*
G02X1252526Y1725373I2093J0D01*
G01Y1727404D01*
G02X1252828Y1727706I302J0D01*
G37*
G36*
G01X1268576D02*
X1272276D01*
G02X1272578Y1727404I0J-302D01*
G01Y1717398D01*
G02X1272276Y1717096I-302J0D01*
G01X1268576D01*
G02X1268274Y1717398I0J302D01*
G01Y1719429D01*
G02X1268183Y1720039I2002J610D01*
G02X1268905Y1721621I2094J0D01*
G01X1269224Y1722271D01*
G03Y1722533I-267J131D01*
G01X1268907Y1723180D01*
G02X1268183Y1724763I1369J1583D01*
G02X1268274Y1725373I2093J0D01*
G01Y1727404D01*
G02X1268576Y1727706I302J0D01*
G37*
G36*
G01X1284324D02*
X1288024D01*
G02X1288326Y1727404I0J-302D01*
G01Y1717398D01*
G02X1288024Y1717096I-302J0D01*
G01X1284324D01*
G02X1284022Y1717398I0J302D01*
G01Y1719429D01*
G02X1283931Y1720039I2002J610D01*
G02X1284653Y1721621I2094J0D01*
G01X1284972Y1722271D01*
G03Y1722533I-267J131D01*
G01X1284655Y1723180D01*
G02X1283931Y1724763I1369J1583D01*
G02X1284022Y1725373I2093J0D01*
G01Y1727404D01*
G02X1284324Y1727706I302J0D01*
G37*
G36*
G01X1568182D02*
X1571882D01*
G02X1572184Y1727404I0J-302D01*
G01Y1717398D01*
G02X1571882Y1717096I-302J0D01*
G01X1568182D01*
G02X1567880Y1717398I0J302D01*
G01Y1719802D01*
G02X1567866Y1720039I2002J237D01*
G02X1567880Y1720276I2016J0D01*
G01Y1724526D01*
G02X1567866Y1724763I2002J237D01*
G02X1567880Y1725000I2016J0D01*
G01Y1727404D01*
G02X1568182Y1727706I302J0D01*
G37*
G36*
G01X1583930D02*
X1587630D01*
G02X1587932Y1727404I0J-302D01*
G01Y1717398D01*
G02X1587630Y1717096I-302J0D01*
G01X1583930D01*
G02X1583628Y1717398I0J302D01*
G01Y1719802D01*
G02X1583614Y1720039I2002J237D01*
G02X1583628Y1720276I2016J0D01*
G01Y1724526D01*
G02X1583614Y1724763I2002J237D01*
G02X1583628Y1725000I2016J0D01*
G01Y1727404D01*
G02X1583930Y1727706I302J0D01*
G37*
G36*
G01X1599678D02*
X1603378D01*
G02X1603680Y1727404I0J-302D01*
G01Y1717398D01*
G02X1603378Y1717096I-302J0D01*
G01X1599678D01*
G02X1599376Y1717398I0J302D01*
G01Y1719802D01*
G02X1599362Y1720039I2002J237D01*
G02X1599376Y1720276I2016J0D01*
G01Y1724526D01*
G02X1599362Y1724763I2002J237D01*
G02X1599376Y1725000I2016J0D01*
G01Y1727404D01*
G02X1599678Y1727706I302J0D01*
G37*
G36*
G01X1615426D02*
X1619126D01*
G02X1619428Y1727404I0J-302D01*
G01Y1717398D01*
G02X1619126Y1717096I-302J0D01*
G01X1615426D01*
G02X1615124Y1717398I0J302D01*
G01Y1719802D01*
G02X1615110Y1720039I2002J237D01*
G02X1615124Y1720276I2016J0D01*
G01Y1724526D01*
G02X1615110Y1724763I2002J237D01*
G02X1615124Y1725000I2016J0D01*
G01Y1727404D01*
G02X1615426Y1727706I302J0D01*
G37*
G36*
G01X296135D02*
X299835D01*
G02X300138Y1727404I1J-302D01*
G01Y1717398D01*
G02X299835Y1717096I-303J1D01*
G01X296135D01*
G02X295832Y1717398I-1J302D01*
G01Y1719432D01*
G02X295742Y1720039I2002J607D01*
G02X296464Y1721621I2094J0D01*
G01X296783Y1722271D01*
G03Y1722533I-267J131D01*
G01X296466Y1723180D01*
G02X295742Y1724763I1369J1583D01*
G02X295832Y1725370I2092J0D01*
G01Y1727404D01*
G02X296135Y1727706I303J-1D01*
G37*
G36*
G01X311883D02*
X315583D01*
G02X315886Y1727404I1J-302D01*
G01Y1717398D01*
G02X315583Y1717096I-303J1D01*
G01X311883D01*
G02X311580Y1717398I-1J302D01*
G01Y1719432D01*
G02X311490Y1720039I2002J607D01*
G02X312212Y1721621I2094J0D01*
G01X312531Y1722271D01*
G03Y1722533I-267J131D01*
G01X312214Y1723180D01*
G02X311490Y1724763I1369J1583D01*
G02X311580Y1725370I2092J0D01*
G01Y1727404D01*
G02X311883Y1727706I303J-1D01*
G37*
G36*
G01X327631D02*
X331331D01*
G02X331634Y1727404I1J-302D01*
G01Y1717398D01*
G02X331331Y1717096I-303J1D01*
G01X327631D01*
G02X327328Y1717398I-1J302D01*
G01Y1719432D01*
G02X327238Y1720039I2002J607D01*
G02X327960Y1721621I2094J0D01*
G01X328279Y1722271D01*
G03Y1722533I-267J131D01*
G01X327962Y1723180D01*
G02X327238Y1724763I1369J1583D01*
G02X327328Y1725370I2092J0D01*
G01Y1727404D01*
G02X327631Y1727706I303J-1D01*
G37*
G36*
G01X343379D02*
X347079D01*
G02X347382Y1727404I1J-302D01*
G01Y1717398D01*
G02X347079Y1717096I-303J1D01*
G01X343379D01*
G02X343076Y1717398I-1J302D01*
G01Y1719432D01*
G02X342986Y1720039I2002J607D01*
G02X343708Y1721621I2094J0D01*
G01X344027Y1722271D01*
G03Y1722533I-267J131D01*
G01X343710Y1723180D01*
G02X342986Y1724763I1369J1583D01*
G02X343076Y1725370I2092J0D01*
G01Y1727404D01*
G02X343379Y1727706I303J-1D01*
G37*
G36*
G01X493379D02*
X497079D01*
G02X497382Y1727404I1J-302D01*
G01Y1717398D01*
G02X497079Y1717096I-303J1D01*
G01X493379D01*
G02X493076Y1717398I-1J302D01*
G01Y1719810D01*
G02X493063Y1720039I2003J229D01*
G02X493076Y1720268I2016J0D01*
G01Y1724534D01*
G02X493063Y1724763I2003J229D01*
G02X493076Y1724992I2016J0D01*
G01Y1727404D01*
G02X493379Y1727706I303J-1D01*
G37*
G36*
G01X509127D02*
X512827D01*
G02X513130Y1727404I1J-302D01*
G01Y1717398D01*
G02X512827Y1717096I-303J1D01*
G01X509127D01*
G02X508824Y1717398I-1J302D01*
G01Y1719810D01*
G02X508811Y1720039I2003J229D01*
G02X508824Y1720268I2016J0D01*
G01Y1724534D01*
G02X508811Y1724763I2003J229D01*
G02X508824Y1724992I2016J0D01*
G01Y1727404D01*
G02X509127Y1727706I303J-1D01*
G37*
G36*
G01X524875D02*
X528575D01*
G02X528878Y1727404I1J-302D01*
G01Y1717398D01*
G02X528575Y1717096I-303J1D01*
G01X524875D01*
G02X524572Y1717398I-1J302D01*
G01Y1719810D01*
G02X524559Y1720039I2003J229D01*
G02X524572Y1720268I2016J0D01*
G01Y1724534D01*
G02X524559Y1724763I2003J229D01*
G02X524572Y1724992I2016J0D01*
G01Y1727404D01*
G02X524875Y1727706I303J-1D01*
G37*
G36*
G01X540623D02*
X544323D01*
G02X544626Y1727404I1J-302D01*
G01Y1717398D01*
G02X544323Y1717096I-303J1D01*
G01X540623D01*
G02X540320Y1717398I-1J302D01*
G01Y1719810D01*
G02X540307Y1720039I2003J229D01*
G02X540320Y1720268I2016J0D01*
G01Y1724534D01*
G02X540307Y1724763I2003J229D01*
G02X540320Y1724992I2016J0D01*
G01Y1727404D01*
G02X540623Y1727706I303J-1D01*
G37*
G36*
G01X1304009D02*
X1307709D01*
G02X1308012Y1727404I1J-302D01*
G01Y1717398D01*
G02X1307709Y1717096I-303J1D01*
G01X1304009D01*
G02X1303706Y1717398I-1J302D01*
G01Y1719432D01*
G02X1303616Y1720039I2002J607D01*
G02X1304338Y1721621I2094J0D01*
G01X1304657Y1722271D01*
G03Y1722533I-267J131D01*
G01X1304340Y1723180D01*
G02X1303616Y1724763I1369J1583D01*
G02X1303706Y1725370I2092J0D01*
G01Y1727404D01*
G02X1304009Y1727706I303J-1D01*
G37*
G36*
G01X1319757D02*
X1323457D01*
G02X1323760Y1727404I1J-302D01*
G01Y1717398D01*
G02X1323457Y1717096I-303J1D01*
G01X1319757D01*
G02X1319454Y1717398I-1J302D01*
G01Y1719432D01*
G02X1319364Y1720039I2002J607D01*
G02X1320086Y1721621I2094J0D01*
G01X1320405Y1722271D01*
G03Y1722533I-267J131D01*
G01X1320088Y1723180D01*
G02X1319364Y1724763I1369J1583D01*
G02X1319454Y1725370I2092J0D01*
G01Y1727404D01*
G02X1319757Y1727706I303J-1D01*
G37*
G36*
G01X1335505D02*
X1339205D01*
G02X1339508Y1727404I1J-302D01*
G01Y1717398D01*
G02X1339205Y1717096I-303J1D01*
G01X1335505D01*
G02X1335202Y1717398I-1J302D01*
G01Y1719432D01*
G02X1335112Y1720039I2002J607D01*
G02X1335834Y1721621I2094J0D01*
G01X1336153Y1722271D01*
G03Y1722533I-267J131D01*
G01X1335836Y1723180D01*
G02X1335112Y1724763I1369J1583D01*
G02X1335202Y1725370I2092J0D01*
G01Y1727404D01*
G02X1335505Y1727706I303J-1D01*
G37*
G36*
G01X1351253D02*
X1354953D01*
G02X1355256Y1727404I1J-302D01*
G01Y1717398D01*
G02X1354953Y1717096I-303J1D01*
G01X1351253D01*
G02X1350950Y1717398I-1J302D01*
G01Y1719432D01*
G02X1350860Y1720039I2002J607D01*
G02X1351582Y1721621I2094J0D01*
G01X1351901Y1722271D01*
G03Y1722533I-267J131D01*
G01X1351584Y1723180D01*
G02X1350860Y1724763I1369J1583D01*
G02X1350950Y1725370I2092J0D01*
G01Y1727404D01*
G02X1351253Y1727706I303J-1D01*
G37*
G36*
G01X1501253D02*
X1504953D01*
G02X1505256Y1727404I1J-302D01*
G01Y1717398D01*
G02X1504953Y1717096I-303J1D01*
G01X1501253D01*
G02X1500950Y1717398I-1J302D01*
G01Y1719810D01*
G02X1500937Y1720039I2003J229D01*
G02X1500950Y1720268I2016J0D01*
G01Y1724534D01*
G02X1500937Y1724763I2003J229D01*
G02X1500950Y1724992I2016J0D01*
G01Y1727404D01*
G02X1501253Y1727706I303J-1D01*
G37*
G36*
G01X1517001D02*
X1520701D01*
G02X1521004Y1727404I1J-302D01*
G01Y1717398D01*
G02X1520701Y1717096I-303J1D01*
G01X1517001D01*
G02X1516698Y1717398I-1J302D01*
G01Y1719810D01*
G02X1516685Y1720039I2003J229D01*
G02X1516698Y1720268I2016J0D01*
G01Y1724534D01*
G02X1516685Y1724763I2003J229D01*
G02X1516698Y1724992I2016J0D01*
G01Y1727404D01*
G02X1517001Y1727706I303J-1D01*
G37*
G36*
G01X1532749D02*
X1536449D01*
G02X1536752Y1727404I1J-302D01*
G01Y1717398D01*
G02X1536449Y1717096I-303J1D01*
G01X1532749D01*
G02X1532446Y1717398I-1J302D01*
G01Y1719810D01*
G02X1532433Y1720039I2003J229D01*
G02X1532446Y1720268I2016J0D01*
G01Y1724534D01*
G02X1532433Y1724763I2003J229D01*
G02X1532446Y1724992I2016J0D01*
G01Y1727404D01*
G02X1532749Y1727706I303J-1D01*
G37*
G36*
G01X1548497D02*
X1552197D01*
G02X1552500Y1727404I1J-302D01*
G01Y1717398D01*
G02X1552197Y1717096I-303J1D01*
G01X1548497D01*
G02X1548194Y1717398I-1J302D01*
G01Y1719810D01*
G02X1548181Y1720039I2003J229D01*
G02X1548194Y1720268I2016J0D01*
G01Y1724534D01*
G02X1548181Y1724763I2003J229D01*
G02X1548194Y1724992I2016J0D01*
G01Y1727404D01*
G02X1548497Y1727706I303J-1D01*
G37*
G36*
G01X237080Y1731644D02*
X240780D01*
G02X241082Y1731341I-1J-303D01*
G01Y1721335D01*
G02X240780Y1721032I-302J-1D01*
G01X237080D01*
G02X236778Y1721335I1J303D01*
G01Y1723366D01*
G02X236687Y1723976I2002J610D01*
G02X237409Y1725558I2094J0D01*
G01X237728Y1726208D01*
G03Y1726470I-267J131D01*
G01X237411Y1727117D01*
G02X236687Y1728700I1369J1583D01*
G02X236778Y1729310I2093J0D01*
G01Y1731341D01*
G02X237080Y1731644I302J1D01*
G37*
G36*
G01X252828D02*
X256528D01*
G02X256830Y1731341I-1J-303D01*
G01Y1721335D01*
G02X256528Y1721032I-302J-1D01*
G01X252828D01*
G02X252526Y1721335I1J303D01*
G01Y1723366D01*
G02X252435Y1723976I2002J610D01*
G02X253157Y1725558I2094J0D01*
G01X253476Y1726208D01*
G03Y1726470I-267J131D01*
G01X253159Y1727117D01*
G02X252435Y1728700I1369J1583D01*
G02X252526Y1729310I2093J0D01*
G01Y1731341D01*
G02X252828Y1731644I302J1D01*
G37*
G36*
G01X268576D02*
X272276D01*
G02X272578Y1731341I-1J-303D01*
G01Y1721335D01*
G02X272276Y1721032I-302J-1D01*
G01X268576D01*
G02X268274Y1721335I1J303D01*
G01Y1723366D01*
G02X268183Y1723976I2002J610D01*
G02X268905Y1725558I2094J0D01*
G01X269224Y1726208D01*
G03Y1726470I-267J131D01*
G01X268907Y1727117D01*
G02X268183Y1728700I1369J1583D01*
G02X268274Y1729310I2093J0D01*
G01Y1731341D01*
G02X268576Y1731644I302J1D01*
G37*
G36*
G01X284324D02*
X288024D01*
G02X288326Y1731341I-1J-303D01*
G01Y1721335D01*
G02X288024Y1721032I-302J-1D01*
G01X284324D01*
G02X284022Y1721335I1J303D01*
G01Y1723366D01*
G02X283931Y1723976I2002J610D01*
G02X284653Y1725558I2094J0D01*
G01X284972Y1726208D01*
G03Y1726470I-267J131D01*
G01X284655Y1727117D01*
G02X283931Y1728700I1369J1583D01*
G02X284022Y1729310I2093J0D01*
G01Y1731341D01*
G02X284324Y1731644I302J1D01*
G37*
G36*
G01X304009D02*
X307709D01*
G02X308012Y1731341I0J-303D01*
G01Y1721335D01*
G02X307709Y1721032I-303J0D01*
G01X304009D01*
G02X303706Y1721335I0J303D01*
G01Y1723369D01*
G02X303616Y1723976I2002J607D01*
G02X304338Y1725558I2094J0D01*
G01X304657Y1726208D01*
G03Y1726470I-267J131D01*
G01X304340Y1727117D01*
G02X303616Y1728700I1369J1583D01*
G02X303706Y1729307I2092J0D01*
G01Y1731341D01*
G02X304009Y1731644I303J0D01*
G37*
G36*
G01X319757D02*
X323457D01*
G02X323760Y1731341I0J-303D01*
G01Y1721335D01*
G02X323457Y1721032I-303J0D01*
G01X319757D01*
G02X319454Y1721335I0J303D01*
G01Y1723369D01*
G02X319364Y1723976I2002J607D01*
G02X320086Y1725558I2094J0D01*
G01X320405Y1726208D01*
G03Y1726470I-267J131D01*
G01X320088Y1727117D01*
G02X319364Y1728700I1369J1583D01*
G02X319454Y1729307I2092J0D01*
G01Y1731341D01*
G02X319757Y1731644I303J0D01*
G37*
G36*
G01X335505D02*
X339205D01*
G02X339508Y1731341I0J-303D01*
G01Y1721335D01*
G02X339205Y1721032I-303J0D01*
G01X335505D01*
G02X335202Y1721335I0J303D01*
G01Y1723369D01*
G02X335112Y1723976I2002J607D01*
G02X335834Y1725558I2094J0D01*
G01X336153Y1726208D01*
G03Y1726470I-267J131D01*
G01X335836Y1727117D01*
G02X335112Y1728700I1369J1583D01*
G02X335202Y1729307I2092J0D01*
G01Y1731341D01*
G02X335505Y1731644I303J0D01*
G37*
G36*
G01X351253D02*
X354953D01*
G02X355256Y1731341I0J-303D01*
G01Y1721335D01*
G02X354953Y1721032I-303J0D01*
G01X351253D01*
G02X350950Y1721335I0J303D01*
G01Y1723369D01*
G02X350860Y1723976I2002J607D01*
G02X351582Y1725558I2094J0D01*
G01X351901Y1726208D01*
G03Y1726470I-267J131D01*
G01X351584Y1727117D01*
G02X350860Y1728700I1369J1583D01*
G02X350950Y1729307I2092J0D01*
G01Y1731341D01*
G02X351253Y1731644I303J0D01*
G37*
G36*
G01X501253D02*
X504953D01*
G02X505256Y1731341I0J-303D01*
G01Y1721335D01*
G02X504953Y1721032I-303J0D01*
G01X501253D01*
G02X500950Y1721335I0J303D01*
G01Y1723747D01*
G02X500937Y1723976I2003J229D01*
G02X500950Y1724205I2016J0D01*
G01Y1728471D01*
G02X500937Y1728700I2003J229D01*
G02X500950Y1728929I2016J0D01*
G01Y1731341D01*
G02X501253Y1731644I303J0D01*
G37*
G36*
G01X517001D02*
X520701D01*
G02X521004Y1731341I0J-303D01*
G01Y1721335D01*
G02X520701Y1721032I-303J0D01*
G01X517001D01*
G02X516698Y1721335I0J303D01*
G01Y1723747D01*
G02X516685Y1723976I2003J229D01*
G02X516698Y1724205I2016J0D01*
G01Y1728471D01*
G02X516685Y1728700I2003J229D01*
G02X516698Y1728929I2016J0D01*
G01Y1731341D01*
G02X517001Y1731644I303J0D01*
G37*
G36*
G01X532749D02*
X536449D01*
G02X536752Y1731341I0J-303D01*
G01Y1721335D01*
G02X536449Y1721032I-303J0D01*
G01X532749D01*
G02X532446Y1721335I0J303D01*
G01Y1723747D01*
G02X532433Y1723976I2003J229D01*
G02X532446Y1724205I2016J0D01*
G01Y1728471D01*
G02X532433Y1728700I2003J229D01*
G02X532446Y1728929I2016J0D01*
G01Y1731341D01*
G02X532749Y1731644I303J0D01*
G37*
G36*
G01X548497D02*
X552197D01*
G02X552500Y1731341I0J-303D01*
G01Y1721335D01*
G02X552197Y1721032I-303J0D01*
G01X548497D01*
G02X548194Y1721335I0J303D01*
G01Y1723747D01*
G02X548181Y1723976I2003J229D01*
G02X548194Y1724205I2016J0D01*
G01Y1728471D01*
G02X548181Y1728700I2003J229D01*
G02X548194Y1728929I2016J0D01*
G01Y1731341D01*
G02X548497Y1731644I303J0D01*
G37*
G36*
G01X568182D02*
X571882D01*
G02X572184Y1731341I-1J-303D01*
G01Y1721335D01*
G02X571882Y1721032I-302J-1D01*
G01X568182D01*
G02X567880Y1721335I1J303D01*
G01Y1723739D01*
G02X567866Y1723976I2002J237D01*
G02X567880Y1724213I2016J0D01*
G01Y1728463D01*
G02X567866Y1728700I2002J237D01*
G02X567880Y1728937I2016J0D01*
G01Y1731341D01*
G02X568182Y1731644I302J1D01*
G37*
G36*
G01X583930D02*
X587630D01*
G02X587932Y1731341I-1J-303D01*
G01Y1721335D01*
G02X587630Y1721032I-302J-1D01*
G01X583930D01*
G02X583628Y1721335I1J303D01*
G01Y1723739D01*
G02X583614Y1723976I2002J237D01*
G02X583628Y1724213I2016J0D01*
G01Y1728463D01*
G02X583614Y1728700I2002J237D01*
G02X583628Y1728937I2016J0D01*
G01Y1731341D01*
G02X583930Y1731644I302J1D01*
G37*
G36*
G01X599678D02*
X603378D01*
G02X603680Y1731341I-1J-303D01*
G01Y1721335D01*
G02X603378Y1721032I-302J-1D01*
G01X599678D01*
G02X599376Y1721335I1J303D01*
G01Y1723739D01*
G02X599362Y1723976I2002J237D01*
G02X599376Y1724213I2016J0D01*
G01Y1728463D01*
G02X599362Y1728700I2002J237D01*
G02X599376Y1728937I2016J0D01*
G01Y1731341D01*
G02X599678Y1731644I302J1D01*
G37*
G36*
G01X615426D02*
X619126D01*
G02X619428Y1731341I-1J-303D01*
G01Y1721335D01*
G02X619126Y1721032I-302J-1D01*
G01X615426D01*
G02X615124Y1721335I1J303D01*
G01Y1723739D01*
G02X615110Y1723976I2002J237D01*
G02X615124Y1724213I2016J0D01*
G01Y1728463D01*
G02X615110Y1728700I2002J237D01*
G02X615124Y1728937I2016J0D01*
G01Y1731341D01*
G02X615426Y1731644I302J1D01*
G37*
G36*
G01X1244954D02*
X1248654D01*
G02X1248956Y1731341I-1J-303D01*
G01Y1721335D01*
G02X1248654Y1721032I-302J-1D01*
G01X1244954D01*
G02X1244652Y1721335I1J303D01*
G01Y1723366D01*
G02X1244561Y1723976I2002J610D01*
G02X1245283Y1725558I2094J0D01*
G01X1245602Y1726208D01*
G03Y1726470I-267J131D01*
G01X1245285Y1727117D01*
G02X1244561Y1728700I1369J1583D01*
G02X1244652Y1729310I2093J0D01*
G01Y1731341D01*
G02X1244954Y1731644I302J1D01*
G37*
G36*
G01X1260702D02*
X1264402D01*
G02X1264704Y1731341I-1J-303D01*
G01Y1721335D01*
G02X1264402Y1721032I-302J-1D01*
G01X1260702D01*
G02X1260400Y1721335I1J303D01*
G01Y1723366D01*
G02X1260309Y1723976I2002J610D01*
G02X1261031Y1725558I2094J0D01*
G01X1261350Y1726208D01*
G03Y1726470I-267J131D01*
G01X1261033Y1727117D01*
G02X1260309Y1728700I1369J1583D01*
G02X1260400Y1729310I2093J0D01*
G01Y1731341D01*
G02X1260702Y1731644I302J1D01*
G37*
G36*
G01X1276450D02*
X1280150D01*
G02X1280452Y1731341I-1J-303D01*
G01Y1721335D01*
G02X1280150Y1721032I-302J-1D01*
G01X1276450D01*
G02X1276148Y1721335I1J303D01*
G01Y1723366D01*
G02X1276057Y1723976I2002J610D01*
G02X1276779Y1725558I2094J0D01*
G01X1277098Y1726208D01*
G03Y1726470I-267J131D01*
G01X1276781Y1727117D01*
G02X1276057Y1728700I1369J1583D01*
G02X1276148Y1729310I2093J0D01*
G01Y1731341D01*
G02X1276450Y1731644I302J1D01*
G37*
G36*
G01X1292198D02*
X1295898D01*
G02X1296200Y1731341I-1J-303D01*
G01Y1721335D01*
G02X1295898Y1721032I-302J-1D01*
G01X1292198D01*
G02X1291896Y1721335I1J303D01*
G01Y1723366D01*
G02X1291805Y1723976I2002J610D01*
G02X1292527Y1725558I2094J0D01*
G01X1292846Y1726208D01*
G03Y1726470I-267J131D01*
G01X1292529Y1727117D01*
G02X1291805Y1728700I1369J1583D01*
G02X1291896Y1729310I2093J0D01*
G01Y1731341D01*
G02X1292198Y1731644I302J1D01*
G37*
G36*
G01X1311883D02*
X1315583D01*
G02X1315886Y1731341I0J-303D01*
G01Y1721335D01*
G02X1315583Y1721032I-303J0D01*
G01X1311883D01*
G02X1311580Y1721335I0J303D01*
G01Y1723369D01*
G02X1311490Y1723976I2002J607D01*
G02X1312212Y1725558I2094J0D01*
G01X1312531Y1726208D01*
G03Y1726470I-267J131D01*
G01X1312214Y1727117D01*
G02X1311490Y1728700I1369J1583D01*
G02X1311580Y1729307I2092J0D01*
G01Y1731341D01*
G02X1311883Y1731644I303J0D01*
G37*
G36*
G01X1327631D02*
X1331331D01*
G02X1331634Y1731341I0J-303D01*
G01Y1721335D01*
G02X1331331Y1721032I-303J0D01*
G01X1327631D01*
G02X1327328Y1721335I0J303D01*
G01Y1723369D01*
G02X1327238Y1723976I2002J607D01*
G02X1327960Y1725558I2094J0D01*
G01X1328279Y1726208D01*
G03Y1726470I-267J131D01*
G01X1327962Y1727117D01*
G02X1327238Y1728700I1369J1583D01*
G02X1327328Y1729307I2092J0D01*
G01Y1731341D01*
G02X1327631Y1731644I303J0D01*
G37*
G36*
G01X1343379D02*
X1347079D01*
G02X1347382Y1731341I0J-303D01*
G01Y1721335D01*
G02X1347079Y1721032I-303J0D01*
G01X1343379D01*
G02X1343076Y1721335I0J303D01*
G01Y1723369D01*
G02X1342986Y1723976I2002J607D01*
G02X1343708Y1725558I2094J0D01*
G01X1344027Y1726208D01*
G03Y1726470I-267J131D01*
G01X1343710Y1727117D01*
G02X1342986Y1728700I1369J1583D01*
G02X1343076Y1729307I2092J0D01*
G01Y1731341D01*
G02X1343379Y1731644I303J0D01*
G37*
G36*
G01X1359127D02*
X1362827D01*
G02X1363130Y1731341I0J-303D01*
G01Y1721335D01*
G02X1362827Y1721032I-303J0D01*
G01X1359127D01*
G02X1358824Y1721335I0J303D01*
G01Y1723369D01*
G02X1358734Y1723976I2002J607D01*
G02X1359456Y1725558I2094J0D01*
G01X1359775Y1726208D01*
G03Y1726470I-267J131D01*
G01X1359458Y1727117D01*
G02X1358734Y1728700I1369J1583D01*
G02X1358824Y1729307I2092J0D01*
G01Y1731341D01*
G02X1359127Y1731644I303J0D01*
G37*
G36*
G01X1509127D02*
X1512827D01*
G02X1513130Y1731341I0J-303D01*
G01Y1721335D01*
G02X1512827Y1721032I-303J0D01*
G01X1509127D01*
G02X1508824Y1721335I0J303D01*
G01Y1723747D01*
G02X1508811Y1723976I2003J229D01*
G02X1508824Y1724205I2016J0D01*
G01Y1728471D01*
G02X1508811Y1728700I2003J229D01*
G02X1508824Y1728929I2016J0D01*
G01Y1731341D01*
G02X1509127Y1731644I303J0D01*
G37*
G36*
G01X1524875D02*
X1528575D01*
G02X1528878Y1731341I0J-303D01*
G01Y1721335D01*
G02X1528575Y1721032I-303J0D01*
G01X1524875D01*
G02X1524572Y1721335I0J303D01*
G01Y1723747D01*
G02X1524559Y1723976I2003J229D01*
G02X1524572Y1724205I2016J0D01*
G01Y1728471D01*
G02X1524559Y1728700I2003J229D01*
G02X1524572Y1728929I2016J0D01*
G01Y1731341D01*
G02X1524875Y1731644I303J0D01*
G37*
G36*
G01X1540623D02*
X1544323D01*
G02X1544626Y1731341I0J-303D01*
G01Y1721335D01*
G02X1544323Y1721032I-303J0D01*
G01X1540623D01*
G02X1540320Y1721335I0J303D01*
G01Y1723747D01*
G02X1540307Y1723976I2003J229D01*
G02X1540320Y1724205I2016J0D01*
G01Y1728471D01*
G02X1540307Y1728700I2003J229D01*
G02X1540320Y1728929I2016J0D01*
G01Y1731341D01*
G02X1540623Y1731644I303J0D01*
G37*
G36*
G01X1556371D02*
X1560071D01*
G02X1560374Y1731341I0J-303D01*
G01Y1721335D01*
G02X1560071Y1721032I-303J0D01*
G01X1556371D01*
G02X1556068Y1721335I0J303D01*
G01Y1723747D01*
G02X1556055Y1723976I2003J229D01*
G02X1556068Y1724205I2016J0D01*
G01Y1728471D01*
G02X1556055Y1728700I2003J229D01*
G02X1556068Y1728929I2016J0D01*
G01Y1731341D01*
G02X1556371Y1731644I303J0D01*
G37*
G36*
G01X1576056D02*
X1579756D01*
G02X1580058Y1731341I-1J-303D01*
G01Y1721335D01*
G02X1579756Y1721032I-302J-1D01*
G01X1576056D01*
G02X1575754Y1721335I1J303D01*
G01Y1723739D01*
G02X1575740Y1723976I2002J237D01*
G02X1575754Y1724213I2016J0D01*
G01Y1728463D01*
G02X1575740Y1728700I2002J237D01*
G02X1575754Y1728937I2016J0D01*
G01Y1731341D01*
G02X1576056Y1731644I302J1D01*
G37*
G36*
G01X1591804D02*
X1595504D01*
G02X1595806Y1731341I-1J-303D01*
G01Y1721335D01*
G02X1595504Y1721032I-302J-1D01*
G01X1591804D01*
G02X1591502Y1721335I1J303D01*
G01Y1723739D01*
G02X1591488Y1723976I2002J237D01*
G02X1591502Y1724213I2016J0D01*
G01Y1728463D01*
G02X1591488Y1728700I2002J237D01*
G02X1591502Y1728937I2016J0D01*
G01Y1731341D01*
G02X1591804Y1731644I302J1D01*
G37*
G36*
G01X1607552D02*
X1611252D01*
G02X1611554Y1731341I-1J-303D01*
G01Y1721335D01*
G02X1611252Y1721032I-302J-1D01*
G01X1607552D01*
G02X1607250Y1721335I1J303D01*
G01Y1723739D01*
G02X1607236Y1723976I2002J237D01*
G02X1607250Y1724213I2016J0D01*
G01Y1728463D01*
G02X1607236Y1728700I2002J237D01*
G02X1607250Y1728937I2016J0D01*
G01Y1731341D01*
G02X1607552Y1731644I302J1D01*
G37*
G36*
G01X1623300D02*
X1627000D01*
G02X1627302Y1731341I-1J-303D01*
G01Y1721335D01*
G02X1627000Y1721032I-302J-1D01*
G01X1623300D01*
G02X1622998Y1721335I1J303D01*
G01Y1723739D01*
G02X1622984Y1723976I2002J237D01*
G02X1622998Y1724213I2016J0D01*
G01Y1728463D01*
G02X1622984Y1728700I2002J237D01*
G02X1622998Y1728937I2016J0D01*
G01Y1731341D01*
G02X1623300Y1731644I302J1D01*
G37*
G36*
G01X816942Y1721140D02*
X901218D01*
G02X902102Y1720774I0J-1251D01*
G01X909144Y1713732D01*
G02X909510Y1712848I-885J-884D01*
G01Y1667718D01*
X918658Y1658570D01*
X1064940D01*
G02X1065824Y1658204I0J-1251D01*
G01X1085928Y1638100D01*
X1102078D01*
G02X1102962Y1637734I0J-1251D01*
G01X1105274Y1635422D01*
G02X1105640Y1634538I-885J-884D01*
G01Y1606962D01*
G02X1105274Y1606078I-1251J0D01*
G01X1103642Y1604446D01*
G02X1102758Y1604080I-884J885D01*
G01X943752D01*
G02X942868Y1604446I0J1251D01*
G01X916564Y1630750D01*
X815802D01*
G02X814918Y1631116I0J1251D01*
G01X810826Y1635208D01*
G02X810460Y1636092I885J884D01*
G01Y1714658D01*
G02X810826Y1715542I1251J0D01*
G01X816058Y1720774D01*
G02X816942Y1721140I884J-885D01*
G37*
G36*
G01X944340Y1584840D02*
X1103630D01*
G02X1104337Y1584547I0J-999D01*
G01X1105077Y1583807D01*
G02X1105370Y1583100I-706J-707D01*
G01Y1564620D01*
G02X1105077Y1563913I-999J0D01*
G01X1104017Y1562853D01*
G02X1103310Y1562560I-707J706D01*
G01X945140D01*
G02X944433Y1562853I0J999D01*
G01X942903Y1564383D01*
G02X942610Y1565090I706J707D01*
G01Y1583110D01*
G02X942903Y1583817I999J0D01*
G01X943633Y1584547D01*
G02X944340Y1584840I707J-706D01*
G37*
G36*
G01X105651Y1575002D02*
X102251D01*
G02Y1578006I0J1502D01*
G01X105651D01*
G02Y1575002I0J-1502D01*
G37*
G36*
G01X74218Y1574006D02*
X77618D01*
G02Y1571002I0J-1502D01*
G01X74218D01*
G02Y1574006I0J1502D01*
G37*
G36*
G01X76369Y1508958D02*
X79769D01*
G02Y1505954I0J-1502D01*
G01X76369D01*
G02Y1508958I0J1502D01*
G37*
G36*
G01X391330Y1583652D02*
X387930D01*
G02Y1586658I0J1503D01*
G01X391330D01*
G02Y1583652I0J-1503D01*
G37*
G36*
G01X148938Y1515872D02*
X145538D01*
G02Y1518876I0J1502D01*
G01X148938D01*
G02Y1515872I0J-1502D01*
G37*
G36*
G01X164710Y1519516D02*
X168110D01*
G02Y1516512I0J-1502D01*
G01X164710D01*
G02Y1519516I0J1502D01*
G37*
G36*
G01X89264Y1509114D02*
X92664D01*
G02Y1506108I0J-1503D01*
G01X89264D01*
G02Y1509114I0J1503D01*
G37*
G36*
G01X167266Y1571470D02*
X170666D01*
G02Y1568466I0J-1502D01*
G01X167266D01*
G02Y1571470I0J1502D01*
G37*
G36*
G01X1346792Y1615794D02*
X1350192D01*
G02Y1612790I0J-1502D01*
G01X1346792D01*
G02Y1615794I0J1502D01*
G37*
G36*
G01X1358852D02*
X1362252D01*
G02Y1612790I0J-1502D01*
G01X1358852D01*
G02Y1615794I0J1502D01*
G37*
G36*
G01X1365612Y1591596D02*
X1369012D01*
G02Y1588592I0J-1502D01*
G01X1365612D01*
G02Y1591596I0J1502D01*
G37*
G36*
G01Y1579684D02*
X1369012D01*
G02Y1576680I0J-1502D01*
G01X1365612D01*
G02Y1579684I0J1502D01*
G37*
G36*
G01X1305312D02*
X1308712D01*
G02Y1576680I0J-1502D01*
G01X1305312D01*
G02Y1579684I0J1502D01*
G37*
G36*
G01X1293252Y1591596D02*
X1296652D01*
G02Y1588592I0J-1502D01*
G01X1293252D01*
G02Y1591596I0J1502D01*
G37*
G36*
G01X1310612Y1615794D02*
X1314012D01*
G02Y1612790I0J-1502D01*
G01X1310612D01*
G02Y1615794I0J1502D01*
G37*
G36*
G01X1262372Y1603882D02*
X1265772D01*
G02Y1600878I0J-1502D01*
G01X1262372D01*
G02Y1603882I0J1502D01*
G37*
G36*
G01X1286492Y1615794D02*
X1289892D01*
G02Y1612790I0J-1502D01*
G01X1286492D01*
G02Y1615794I0J1502D01*
G37*
G36*
G01X1262372D02*
X1265772D01*
G02Y1612790I0J-1502D01*
G01X1262372D01*
G02Y1615794I0J1502D01*
G37*
G36*
G01X1334732Y1603882D02*
X1338132D01*
G02Y1600878I0J-1502D01*
G01X1334732D01*
G02Y1603882I0J1502D01*
G37*
G36*
G01X1220892Y1579684D02*
X1224292D01*
G02Y1576680I0J-1502D01*
G01X1220892D01*
G02Y1579684I0J1502D01*
G37*
G36*
G01X1334732Y1615794D02*
X1338132D01*
G02Y1612790I0J-1502D01*
G01X1334732D01*
G02Y1615794I0J1502D01*
G37*
G36*
G01X1370912Y1603882D02*
X1374312D01*
G02Y1600878I0J-1502D01*
G01X1370912D01*
G02Y1603882I0J1502D01*
G37*
G36*
G01X1214132D02*
X1217532D01*
G02Y1600878I0J-1502D01*
G01X1214132D01*
G02Y1603882I0J1502D01*
G37*
G36*
G01X1286492D02*
X1289892D01*
G02Y1600878I0J-1502D01*
G01X1286492D01*
G02Y1603882I0J1502D01*
G37*
G36*
G01X1298552D02*
X1301952D01*
G02Y1600878I0J-1502D01*
G01X1298552D01*
G02Y1603882I0J1502D01*
G37*
G36*
G01X1353552Y1579684D02*
X1356952D01*
G02Y1576680I0J-1502D01*
G01X1353552D01*
G02Y1579684I0J1502D01*
G37*
G36*
G01X1341492Y1591596D02*
X1344892D01*
G02Y1588592I0J-1502D01*
G01X1341492D01*
G02Y1591596I0J1502D01*
G37*
G36*
G01X1370912Y1615794D02*
X1374312D01*
G02Y1612790I0J-1502D01*
G01X1370912D01*
G02Y1615794I0J1502D01*
G37*
G36*
G01X1269132Y1591596D02*
X1272532D01*
G02Y1588592I0J-1502D01*
G01X1269132D01*
G02Y1591596I0J1502D01*
G37*
G36*
G01X1238252Y1603882D02*
X1241652D01*
G02Y1600878I0J-1502D01*
G01X1238252D01*
G02Y1603882I0J1502D01*
G37*
G36*
G01X1353552Y1591596D02*
X1356952D01*
G02Y1588592I0J-1502D01*
G01X1353552D01*
G02Y1591596I0J1502D01*
G37*
G36*
G01X1214132Y1615794D02*
X1217532D01*
G02Y1612790I0J-1502D01*
G01X1214132D01*
G02Y1615794I0J1502D01*
G37*
G36*
G01X1226192Y1603882D02*
X1229592D01*
G02Y1600878I0J-1502D01*
G01X1226192D01*
G02Y1603882I0J1502D01*
G37*
G36*
G01X1208832Y1579684D02*
X1212232D01*
G02Y1576680I0J-1502D01*
G01X1208832D01*
G02Y1579684I0J1502D01*
G37*
G36*
G01Y1591596D02*
X1212232D01*
G02Y1588592I0J-1502D01*
G01X1208832D01*
G02Y1591596I0J1502D01*
G37*
G36*
G01X1341492Y1579684D02*
X1344892D01*
G02Y1576680I0J-1502D01*
G01X1341492D01*
G02Y1579684I0J1502D01*
G37*
G36*
G01X1250312Y1615794D02*
X1253712D01*
G02Y1612790I0J-1502D01*
G01X1250312D01*
G02Y1615794I0J1502D01*
G37*
G36*
G01X1232952Y1579684D02*
X1236352D01*
G02Y1576680I0J-1502D01*
G01X1232952D01*
G02Y1579684I0J1502D01*
G37*
G36*
G01Y1591596D02*
X1236352D01*
G02Y1588592I0J-1502D01*
G01X1232952D01*
G02Y1591596I0J1502D01*
G37*
G36*
G01X1196772Y1579684D02*
X1200172D01*
G02Y1576680I0J-1502D01*
G01X1196772D01*
G02Y1579684I0J1502D01*
G37*
G36*
G01X1257072D02*
X1260472D01*
G02Y1576680I0J-1502D01*
G01X1257072D01*
G02Y1579684I0J1502D01*
G37*
G36*
G01X1220892Y1591596D02*
X1224292D01*
G02Y1588592I0J-1502D01*
G01X1220892D01*
G02Y1591596I0J1502D01*
G37*
G36*
G01X1269132Y1579684D02*
X1272532D01*
G02Y1576680I0J-1502D01*
G01X1269132D01*
G02Y1579684I0J1502D01*
G37*
G36*
G01X1305312Y1591596D02*
X1308712D01*
G02Y1588592I0J-1502D01*
G01X1305312D01*
G02Y1591596I0J1502D01*
G37*
G36*
G01X1245012D02*
X1248412D01*
G02Y1588592I0J-1502D01*
G01X1245012D01*
G02Y1591596I0J1502D01*
G37*
G36*
G01X1250312Y1603882D02*
X1253712D01*
G02Y1600878I0J-1502D01*
G01X1250312D01*
G02Y1603882I0J1502D01*
G37*
G36*
G01X1317372Y1579684D02*
X1320772D01*
G02Y1576680I0J-1502D01*
G01X1317372D01*
G02Y1579684I0J1502D01*
G37*
G36*
G01X1358852Y1603882D02*
X1362252D01*
G02Y1600878I0J-1502D01*
G01X1358852D01*
G02Y1603882I0J1502D01*
G37*
G36*
G01X1202072D02*
X1205472D01*
G02Y1600878I0J-1502D01*
G01X1202072D01*
G02Y1603882I0J1502D01*
G37*
G36*
G01Y1615794D02*
X1205472D01*
G02Y1612790I0J-1502D01*
G01X1202072D01*
G02Y1615794I0J1502D01*
G37*
G36*
G01X1322672Y1603882D02*
X1326072D01*
G02Y1600878I0J-1502D01*
G01X1322672D01*
G02Y1603882I0J1502D01*
G37*
G36*
G01X1310612D02*
X1314012D01*
G02Y1600878I0J-1502D01*
G01X1310612D01*
G02Y1603882I0J1502D01*
G37*
G36*
G01X1274432Y1615794D02*
X1277832D01*
G02Y1612790I0J-1502D01*
G01X1274432D01*
G02Y1615794I0J1502D01*
G37*
G36*
G01X1329432Y1579684D02*
X1332832D01*
G02Y1576680I0J-1502D01*
G01X1329432D01*
G02Y1579684I0J1502D01*
G37*
G36*
G01X1346792Y1603882D02*
X1350192D01*
G02Y1600878I0J-1502D01*
G01X1346792D01*
G02Y1603882I0J1502D01*
G37*
G36*
G01X1317372Y1591596D02*
X1320772D01*
G02Y1588592I0J-1502D01*
G01X1317372D01*
G02Y1591596I0J1502D01*
G37*
G36*
G01X1329432D02*
X1332832D01*
G02Y1588592I0J-1502D01*
G01X1329432D01*
G02Y1591596I0J1502D01*
G37*
G36*
G01X1322672Y1615794D02*
X1326072D01*
G02Y1612790I0J-1502D01*
G01X1322672D01*
G02Y1615794I0J1502D01*
G37*
G36*
G01X1281192Y1591596D02*
X1284592D01*
G02Y1588592I0J-1502D01*
G01X1281192D01*
G02Y1591596I0J1502D01*
G37*
G36*
G01X1196772D02*
X1200172D01*
G02Y1588592I0J-1502D01*
G01X1196772D01*
G02Y1591596I0J1502D01*
G37*
G36*
G01X1226192Y1615794D02*
X1229592D01*
G02Y1612790I0J-1502D01*
G01X1226192D01*
G02Y1615794I0J1502D01*
G37*
G36*
G01X1293252Y1579684D02*
X1296652D01*
G02Y1576680I0J-1502D01*
G01X1293252D01*
G02Y1579684I0J1502D01*
G37*
G36*
G01X1298552Y1615794D02*
X1301952D01*
G02Y1612790I0J-1502D01*
G01X1298552D01*
G02Y1615794I0J1502D01*
G37*
G36*
G01X1281192Y1579684D02*
X1284592D01*
G02Y1576680I0J-1502D01*
G01X1281192D01*
G02Y1579684I0J1502D01*
G37*
G36*
G01X1245012D02*
X1248412D01*
G02Y1576680I0J-1502D01*
G01X1245012D01*
G02Y1579684I0J1502D01*
G37*
G36*
G01X1257072Y1591596D02*
X1260472D01*
G02Y1588592I0J-1502D01*
G01X1257072D01*
G02Y1591596I0J1502D01*
G37*
G36*
G01X1274432Y1603882D02*
X1277832D01*
G02Y1600878I0J-1502D01*
G01X1274432D01*
G02Y1603882I0J1502D01*
G37*
G36*
G01X1238252Y1615794D02*
X1241652D01*
G02Y1612790I0J-1502D01*
G01X1238252D01*
G02Y1615794I0J1502D01*
G37*
G36*
G01X1474516Y730492D02*
G02X1473515Y728758I-2002J0D01*
G01X1469877Y726657D01*
G02X1468878Y726390I-999J1736D01*
G01X1468876D01*
G02X1466874Y728392I0J2002D01*
G02X1467875Y730126I2002J0D01*
G01X1471513Y732227D01*
G02X1472512Y732494I999J-1736D01*
G01X1472514D01*
G02X1474516Y730492I0J-2002D01*
G37*
G36*
G01X1477716Y717492D02*
G02X1476715Y715758I-2002J0D01*
G01X1473077Y713657D01*
G02X1472078Y713390I-999J1736D01*
G01X1472076D01*
G02X1470074Y715392I0J2002D01*
G02X1471075Y717126I2002J0D01*
G01X1474713Y719227D01*
G02X1475712Y719494I999J-1736D01*
G01X1475714D01*
G02X1477716Y717492I0J-2002D01*
G37*
G36*
G01Y702992D02*
G02X1476715Y701258I-2002J0D01*
G01X1473077Y699157D01*
G02X1472078Y698890I-999J1736D01*
G01X1472076D01*
G02X1470074Y700892I0J2002D01*
G02X1471075Y702626I2002J0D01*
G01X1474713Y704727D01*
G02X1475712Y704994I999J-1736D01*
G01X1475714D01*
G02X1477716Y702992I0J-2002D01*
G37*
G36*
G01Y688492D02*
G02X1476715Y686758I-2002J0D01*
G01X1473077Y684657D01*
G02X1472078Y684390I-999J1736D01*
G01X1472076D01*
G02X1470074Y686392I0J2002D01*
G02X1471075Y688126I2002J0D01*
G01X1474713Y690227D01*
G02X1475712Y690494I999J-1736D01*
G01X1475714D01*
G02X1477716Y688492I0J-2002D01*
G37*
G36*
G01Y673992D02*
G02X1476715Y672258I-2002J0D01*
G01X1473077Y670157D01*
G02X1472078Y669890I-999J1736D01*
G01X1472076D01*
G02X1470074Y671892I0J2002D01*
G02X1471075Y673626I2002J0D01*
G01X1474713Y675727D01*
G02X1475712Y675994I999J-1736D01*
G01X1475714D01*
G02X1477716Y673992I0J-2002D01*
G37*
G36*
G01Y659492D02*
G02X1476715Y657758I-2002J0D01*
G01X1473077Y655657D01*
G02X1472078Y655390I-999J1736D01*
G01X1472076D01*
G02X1470074Y657392I0J2002D01*
G02X1471075Y659126I2002J0D01*
G01X1474713Y661227D01*
G02X1475712Y661494I999J-1736D01*
G01X1475714D01*
G02X1477716Y659492I0J-2002D01*
G37*
G36*
G01X1455174Y716992D02*
G02X1457176Y718994I2002J0D01*
G01X1457178D01*
G02X1458177Y718727I0J-2003D01*
G01X1461815Y716626D01*
G02X1462816Y714892I-1001J-1734D01*
G02X1460814Y712890I-2002J0D01*
G01X1460812D01*
G02X1459813Y713157I0J2003D01*
G01X1456175Y715258D01*
G02X1455174Y716992I1001J1734D01*
G37*
G36*
G01Y704992D02*
G02X1457176Y706994I2002J0D01*
G01X1457178D01*
G02X1458177Y706727I0J-2003D01*
G01X1461815Y704626D01*
G02X1462816Y702892I-1001J-1734D01*
G02X1460814Y700890I-2002J0D01*
G01X1460812D01*
G02X1459813Y701157I0J2003D01*
G01X1456175Y703258D01*
G02X1455174Y704992I1001J1734D01*
G37*
G36*
G01Y692992D02*
G02X1457176Y694994I2002J0D01*
G01X1457178D01*
G02X1458177Y694727I0J-2003D01*
G01X1461815Y692626D01*
G02X1462816Y690892I-1001J-1734D01*
G02X1460814Y688890I-2002J0D01*
G01X1460812D01*
G02X1459813Y689157I0J2003D01*
G01X1456175Y691258D01*
G02X1455174Y692992I1001J1734D01*
G37*
G36*
G01Y680992D02*
G02X1457176Y682994I2002J0D01*
G01X1457178D01*
G02X1458177Y682727I0J-2003D01*
G01X1461815Y680626D01*
G02X1462816Y678892I-1001J-1734D01*
G02X1460814Y676890I-2002J0D01*
G01X1460812D01*
G02X1459813Y677157I0J2003D01*
G01X1456175Y679258D01*
G02X1455174Y680992I1001J1734D01*
G37*
G36*
G01Y668992D02*
G02X1457176Y670994I2002J0D01*
G01X1457178D01*
G02X1458177Y670727I0J-2003D01*
G01X1461815Y668626D01*
G02X1462816Y666892I-1001J-1734D01*
G02X1460814Y664890I-2002J0D01*
G01X1460812D01*
G02X1459813Y665157I0J2003D01*
G01X1456175Y667258D01*
G02X1455174Y668992I1001J1734D01*
G37*
G36*
G01Y656992D02*
G02X1457176Y658994I2002J0D01*
G01X1457178D01*
G02X1458177Y658727I0J-2003D01*
G01X1461815Y656626D01*
G02X1462816Y654892I-1001J-1734D01*
G02X1460814Y652890I-2002J0D01*
G01X1460812D01*
G02X1459813Y653157I0J2003D01*
G01X1456175Y655258D01*
G02X1455174Y656992I1001J1734D01*
G37*
G36*
G01X1390978Y737198D02*
G02X1389977Y735464I-2002J0D01*
G01X1386339Y733363D01*
G02X1385340Y733096I-999J1736D01*
G01X1385338D01*
G02X1383336Y735098I0J2002D01*
G02X1384337Y736832I2002J0D01*
G01X1387975Y738933D01*
G02X1388974Y739200I999J-1736D01*
G01X1388976D01*
G02X1390978Y737198I0J-2002D01*
G37*
G36*
G01X1395208Y722735D02*
G02X1394207Y721001I-2002J0D01*
G01X1390569Y718900D01*
G02X1389570Y718632I-1001J1735D01*
G01X1389568D01*
G02X1387566Y720635I1J2003D01*
G02X1388567Y722369I2002J0D01*
G01X1392205Y724470D01*
G02X1393204Y724738I1001J-1735D01*
G01X1393206D01*
G02X1395208Y722735I-1J-2003D01*
G37*
G36*
G01Y693708D02*
G02X1394207Y691974I-2002J0D01*
G01X1390569Y689873D01*
G02X1389570Y689606I-999J1736D01*
G01X1389568D01*
G02X1387566Y691608I0J2002D01*
G02X1388567Y693342I2002J0D01*
G01X1392205Y695443D01*
G02X1393204Y695710I999J-1736D01*
G01X1393206D01*
G02X1395208Y693708I0J-2002D01*
G37*
G36*
G01Y708208D02*
G02X1394207Y706474I-2002J0D01*
G01X1390569Y704373D01*
G02X1389570Y704106I-999J1736D01*
G01X1389568D01*
G02X1387566Y706108I0J2002D01*
G02X1388567Y707842I2002J0D01*
G01X1392205Y709943D01*
G02X1393204Y710210I999J-1736D01*
G01X1393206D01*
G02X1395208Y708208I0J-2002D01*
G37*
G36*
G01Y679208D02*
G02X1394207Y677474I-2002J0D01*
G01X1390569Y675373D01*
G02X1389570Y675106I-999J1736D01*
G01X1389568D01*
G02X1387566Y677108I0J2002D01*
G02X1388567Y678842I2002J0D01*
G01X1392205Y680943D01*
G02X1393204Y681210I999J-1736D01*
G01X1393206D01*
G02X1395208Y679208I0J-2002D01*
G37*
G36*
G01Y664708D02*
G02X1394207Y662974I-2002J0D01*
G01X1390569Y660873D01*
G02X1389570Y660606I-999J1736D01*
G01X1389568D01*
G02X1387566Y662608I0J2002D01*
G02X1388567Y664342I2002J0D01*
G01X1392205Y666443D01*
G02X1393204Y666710I999J-1736D01*
G01X1393206D01*
G02X1395208Y664708I0J-2002D01*
G37*
G36*
G01X1372666Y719708D02*
G02X1374668Y721710I2002J0D01*
G01X1374670D01*
G02X1375669Y721443I0J-2003D01*
G01X1379307Y719342D01*
G02X1380308Y717608I-1001J-1734D01*
G02X1378306Y715606I-2002J0D01*
G01X1378304D01*
G02X1377305Y715873I0J2003D01*
G01X1373667Y717974D01*
G02X1372666Y719708I1001J1734D01*
G37*
G36*
G01Y695708D02*
G02X1374668Y697710I2002J0D01*
G01X1374670D01*
G02X1375669Y697443I0J-2003D01*
G01X1379307Y695342D01*
G02X1380308Y693608I-1001J-1734D01*
G02X1378306Y691606I-2002J0D01*
G01X1378304D01*
G02X1377305Y691873I0J2003D01*
G01X1373667Y693974D01*
G02X1372666Y695708I1001J1734D01*
G37*
G36*
G01Y707708D02*
G02X1374668Y709710I2002J0D01*
G01X1374670D01*
G02X1375669Y709443I0J-2003D01*
G01X1379307Y707342D01*
G02X1380308Y705608I-1001J-1734D01*
G02X1378306Y703606I-2002J0D01*
G01X1378304D01*
G02X1377305Y703873I0J2003D01*
G01X1373667Y705974D01*
G02X1372666Y707708I1001J1734D01*
G37*
G36*
G01Y683708D02*
G02X1374668Y685710I2002J0D01*
G01X1374670D01*
G02X1375669Y685443I0J-2003D01*
G01X1379307Y683342D01*
G02X1380308Y681608I-1001J-1734D01*
G02X1378306Y679606I-2002J0D01*
G01X1378304D01*
G02X1377305Y679873I0J2003D01*
G01X1373667Y681974D01*
G02X1372666Y683708I1001J1734D01*
G37*
G36*
G01Y671708D02*
G02X1374668Y673710I2002J0D01*
G01X1374670D01*
G02X1375669Y673443I0J-2003D01*
G01X1379307Y671342D01*
G02X1380308Y669608I-1001J-1734D01*
G02X1378306Y667606I-2002J0D01*
G01X1378304D01*
G02X1377305Y667873I0J2003D01*
G01X1373667Y669974D01*
G02X1372666Y671708I1001J1734D01*
G37*
G36*
G01Y659708D02*
G02X1374668Y661710I2002J0D01*
G01X1374670D01*
G02X1375669Y661443I0J-2003D01*
G01X1379307Y659342D01*
G02X1380308Y657608I-1001J-1734D01*
G02X1378306Y655606I-2002J0D01*
G01X1378304D01*
G02X1377305Y655873I0J2003D01*
G01X1373667Y657974D01*
G02X1372666Y659708I1001J1734D01*
G37*
G36*
G01X146312Y1571028D02*
X149712D01*
G02Y1568022I0J-1503D01*
G01X146312D01*
G02Y1571028I0J1503D01*
G37*
G36*
G01X1701934Y76800D02*
X1705334D01*
G02Y73794I0J-1503D01*
G01X1701934D01*
G02Y76800I0J1503D01*
G37*
G36*
G01X1690934Y70800D02*
X1694334D01*
G02Y67794I0J-1503D01*
G01X1690934D01*
G02Y70800I0J1503D01*
G37*
G36*
G01X1679934Y76800D02*
X1683334D01*
G02Y73794I0J-1503D01*
G01X1679934D01*
G02Y76800I0J1503D01*
G37*
G36*
G01X1657800D02*
X1661200D01*
G02Y73794I0J-1503D01*
G01X1657800D01*
G02Y76800I0J1503D01*
G37*
G36*
G01X1668800Y70800D02*
X1672200D01*
G02Y67794I0J-1503D01*
G01X1668800D01*
G02Y70800I0J1503D01*
G37*
G36*
G01X1646800D02*
X1650200D01*
G02Y67794I0J-1503D01*
G01X1646800D01*
G02Y70800I0J1503D01*
G37*
G36*
G01X1635800Y76800D02*
X1639200D01*
G02Y73794I0J-1503D01*
G01X1635800D01*
G02Y76800I0J1503D01*
G37*
G36*
G01X1612596D02*
X1615996D01*
G02Y73794I0J-1503D01*
G01X1612596D01*
G02Y76800I0J1503D01*
G37*
G36*
G01X1623596Y70800D02*
X1626996D01*
G02Y67794I0J-1503D01*
G01X1623596D01*
G02Y70800I0J1503D01*
G37*
G36*
G01X1601596D02*
X1604996D01*
G02Y67794I0J-1503D01*
G01X1601596D01*
G02Y70800I0J1503D01*
G37*
G36*
G01X1590596Y76800D02*
X1593996D01*
G02Y73794I0J-1503D01*
G01X1590596D01*
G02Y76800I0J1503D01*
G37*
G36*
G01X1579596Y70800D02*
X1582996D01*
G02Y67794I0J-1503D01*
G01X1579596D01*
G02Y70800I0J1503D01*
G37*
G36*
G01X1568596Y76800D02*
X1571996D01*
G02Y73794I0J-1503D01*
G01X1568596D01*
G02Y76800I0J1503D01*
G37*
G36*
G01X1546596D02*
X1549996D01*
G02Y73794I0J-1503D01*
G01X1546596D01*
G02Y76800I0J1503D01*
G37*
G36*
G01X1557596Y70800D02*
X1560996D01*
G02Y67794I0J-1503D01*
G01X1557596D01*
G02Y70800I0J1503D01*
G37*
G36*
G01X1535596D02*
X1538996D01*
G02Y67794I0J-1503D01*
G01X1535596D01*
G02Y70800I0J1503D01*
G37*
G36*
G01X230895Y73838D02*
X227495D01*
G02Y76842I0J1502D01*
G01X230895D01*
G02Y73838I0J-1502D01*
G37*
G36*
G01X219895Y67838D02*
X216495D01*
G02Y70842I0J1502D01*
G01X219895D01*
G02Y67838I0J-1502D01*
G37*
G36*
G01X208895Y73838D02*
X205495D01*
G02Y76842I0J1502D01*
G01X208895D01*
G02Y73838I0J-1502D01*
G37*
G36*
G01X194361Y70842D02*
X197761D01*
G02Y67838I0J-1502D01*
G01X194361D01*
G02Y70842I0J1502D01*
G37*
G36*
G01X183361Y76842D02*
X186761D01*
G02Y73838I0J-1502D01*
G01X183361D01*
G02Y76842I0J1502D01*
G37*
G36*
G01X161361D02*
X164761D01*
G02Y73838I0J-1502D01*
G01X161361D01*
G02Y76842I0J1502D01*
G37*
G36*
G01X172361Y70842D02*
X175761D01*
G02Y67838I0J-1502D01*
G01X172361D01*
G02Y70842I0J1502D01*
G37*
G36*
G01X149157D02*
X152557D01*
G02Y67838I0J-1502D01*
G01X149157D01*
G02Y70842I0J1502D01*
G37*
G36*
G01X138157Y76842D02*
X141557D01*
G02Y73838I0J-1502D01*
G01X138157D01*
G02Y76842I0J1502D01*
G37*
G36*
G01X116157D02*
X119557D01*
G02Y73838I0J-1502D01*
G01X116157D01*
G02Y76842I0J1502D01*
G37*
G36*
G01X127157Y70842D02*
X130557D01*
G02Y67838I0J-1502D01*
G01X127157D01*
G02Y70842I0J1502D01*
G37*
G36*
G01X105157D02*
X108557D01*
G02Y67838I0J-1502D01*
G01X105157D01*
G02Y70842I0J1502D01*
G37*
G36*
G01X94157Y76842D02*
X97557D01*
G02Y73838I0J-1502D01*
G01X94157D01*
G02Y76842I0J1502D01*
G37*
G36*
G01X83157Y70842D02*
X86557D01*
G02Y67838I0J-1502D01*
G01X83157D01*
G02Y70842I0J1502D01*
G37*
G36*
G01X72157Y76842D02*
X75557D01*
G02Y73838I0J-1502D01*
G01X72157D01*
G02Y76842I0J1502D01*
G37*
G36*
G01X61157Y70842D02*
X64557D01*
G02Y67838I0J-1502D01*
G01X61157D01*
G02Y70842I0J1502D01*
G37*
G36*
G01X1619075Y1579684D02*
X1622475D01*
G02Y1576680I0J-1502D01*
G01X1619075D01*
G02Y1579684I0J1502D01*
G37*
G36*
G01X326857Y1603882D02*
X330257D01*
G02Y1600878I0J-1502D01*
G01X326857D01*
G02Y1603882I0J1502D01*
G37*
G36*
G01X363037Y1615794D02*
X366437D01*
G02Y1612790I0J-1502D01*
G01X363037D01*
G02Y1615794I0J1502D01*
G37*
G36*
G01X545411Y1579684D02*
X548811D01*
G02Y1576680I0J-1502D01*
G01X545411D01*
G02Y1579684I0J1502D01*
G37*
G36*
G01Y1591596D02*
X548811D01*
G02Y1588592I0J-1502D01*
G01X545411D01*
G02Y1591596I0J1502D01*
G37*
G36*
G01X1377672D02*
X1381072D01*
G02Y1588592I0J-1502D01*
G01X1377672D01*
G02Y1591596I0J1502D01*
G37*
G36*
G01X533351D02*
X536751D01*
G02Y1588592I0J-1502D01*
G01X533351D01*
G02Y1591596I0J1502D01*
G37*
G36*
G01Y1579684D02*
X536751D01*
G02Y1576680I0J-1502D01*
G01X533351D01*
G02Y1579684I0J1502D01*
G37*
G36*
G01X1594955Y1591596D02*
X1598355D01*
G02Y1588592I0J-1502D01*
G01X1594955D01*
G02Y1591596I0J1502D01*
G37*
G36*
G01X581591D02*
X584991D01*
G02Y1588592I0J-1502D01*
G01X581591D01*
G02Y1591596I0J1502D01*
G37*
G36*
G01Y1579684D02*
X584991D01*
G02Y1576680I0J-1502D01*
G01X581591D01*
G02Y1579684I0J1502D01*
G37*
G36*
G01X1594955D02*
X1598355D01*
G02Y1576680I0J-1502D01*
G01X1594955D01*
G02Y1579684I0J1502D01*
G37*
G36*
G01X605711Y1591596D02*
X609111D01*
G02Y1588592I0J-1502D01*
G01X605711D01*
G02Y1591596I0J1502D01*
G37*
G36*
G01X333617Y1579684D02*
X337017D01*
G02Y1576680I0J-1502D01*
G01X333617D01*
G02Y1579684I0J1502D01*
G37*
G36*
G01X345677D02*
X349077D01*
G02Y1576680I0J-1502D01*
G01X345677D01*
G02Y1579684I0J1502D01*
G37*
G36*
G01X617771D02*
X621171D01*
G02Y1576680I0J-1502D01*
G01X617771D01*
G02Y1579684I0J1502D01*
G37*
G36*
G01Y1591596D02*
X621171D01*
G02Y1588592I0J-1502D01*
G01X617771D01*
G02Y1591596I0J1502D01*
G37*
G36*
G01X629831Y1579684D02*
X633231D01*
G02Y1576680I0J-1502D01*
G01X629831D01*
G02Y1579684I0J1502D01*
G37*
G36*
G01X1582895D02*
X1586295D01*
G02Y1576680I0J-1502D01*
G01X1582895D01*
G02Y1579684I0J1502D01*
G37*
G36*
G01X1570835D02*
X1574235D01*
G02Y1576680I0J-1502D01*
G01X1570835D01*
G02Y1579684I0J1502D01*
G37*
G36*
G01X1558775D02*
X1562175D01*
G02Y1576680I0J-1502D01*
G01X1558775D01*
G02Y1579684I0J1502D01*
G37*
G36*
G01X321557D02*
X324957D01*
G02Y1576680I0J-1502D01*
G01X321557D01*
G02Y1579684I0J1502D01*
G37*
G36*
G01X278617Y1603882D02*
X282017D01*
G02Y1600878I0J-1502D01*
G01X278617D01*
G02Y1603882I0J1502D01*
G37*
G36*
G01X1534655Y1591596D02*
X1538055D01*
G02Y1588592I0J-1502D01*
G01X1534655D01*
G02Y1591596I0J1502D01*
G37*
G36*
G01Y1579684D02*
X1538055D01*
G02Y1576680I0J-1502D01*
G01X1534655D01*
G02Y1579684I0J1502D01*
G37*
G36*
G01X1510535Y1591596D02*
X1513935D01*
G02Y1588592I0J-1502D01*
G01X1510535D01*
G02Y1591596I0J1502D01*
G37*
G36*
G01X1522595D02*
X1525995D01*
G02Y1588592I0J-1502D01*
G01X1522595D01*
G02Y1591596I0J1502D01*
G37*
G36*
G01X309497Y1579684D02*
X312897D01*
G02Y1576680I0J-1502D01*
G01X309497D01*
G02Y1579684I0J1502D01*
G37*
G36*
G01X302737Y1603882D02*
X306137D01*
G02Y1600878I0J-1502D01*
G01X302737D01*
G02Y1603882I0J1502D01*
G37*
G36*
G01X1498475Y1579684D02*
X1501875D01*
G02Y1576680I0J-1502D01*
G01X1498475D01*
G02Y1579684I0J1502D01*
G37*
G36*
G01X314797Y1615794D02*
X318197D01*
G02Y1612790I0J-1502D01*
G01X314797D01*
G02Y1615794I0J1502D01*
G37*
G36*
G01X278617D02*
X282017D01*
G02Y1612790I0J-1502D01*
G01X278617D01*
G02Y1615794I0J1502D01*
G37*
G36*
G01X497171Y1591596D02*
X500571D01*
G02Y1588592I0J-1502D01*
G01X497171D01*
G02Y1591596I0J1502D01*
G37*
G36*
G01X509231D02*
X512631D01*
G02Y1588592I0J-1502D01*
G01X509231D01*
G02Y1591596I0J1502D01*
G37*
G36*
G01Y1579684D02*
X512631D01*
G02Y1576680I0J-1502D01*
G01X509231D01*
G02Y1579684I0J1502D01*
G37*
G36*
G01X1486415Y1591596D02*
X1489815D01*
G02Y1588592I0J-1502D01*
G01X1486415D01*
G02Y1591596I0J1502D01*
G37*
G36*
G01Y1579684D02*
X1489815D01*
G02Y1576680I0J-1502D01*
G01X1486415D01*
G02Y1579684I0J1502D01*
G37*
G36*
G01X321557Y1591596D02*
X324957D01*
G02Y1588592I0J-1502D01*
G01X321557D01*
G02Y1591596I0J1502D01*
G37*
G36*
G01X1462295D02*
X1465695D01*
G02Y1588592I0J-1502D01*
G01X1462295D01*
G02Y1591596I0J1502D01*
G37*
G36*
G01X1474355D02*
X1477755D01*
G02Y1588592I0J-1502D01*
G01X1474355D01*
G02Y1591596I0J1502D01*
G37*
G36*
G01X641891Y1579684D02*
X645291D01*
G02Y1576680I0J-1502D01*
G01X641891D01*
G02Y1579684I0J1502D01*
G37*
G36*
G01Y1591596D02*
X645291D01*
G02Y1588592I0J-1502D01*
G01X641891D01*
G02Y1591596I0J1502D01*
G37*
G36*
G01X285377Y1579684D02*
X288777D01*
G02Y1576680I0J-1502D01*
G01X285377D01*
G02Y1579684I0J1502D01*
G37*
G36*
G01X1462295D02*
X1465695D01*
G02Y1576680I0J-1502D01*
G01X1462295D01*
G02Y1579684I0J1502D01*
G37*
G36*
G01X206257Y1615794D02*
X209657D01*
G02Y1612790I0J-1502D01*
G01X206257D01*
G02Y1615794I0J1502D01*
G37*
G36*
G01X338917D02*
X342317D01*
G02Y1612790I0J-1502D01*
G01X338917D01*
G02Y1615794I0J1502D01*
G37*
G36*
G01X1474355Y1579684D02*
X1477755D01*
G02Y1576680I0J-1502D01*
G01X1474355D01*
G02Y1579684I0J1502D01*
G37*
G36*
G01X261257D02*
X264657D01*
G02Y1576680I0J-1502D01*
G01X261257D01*
G02Y1579684I0J1502D01*
G37*
G36*
G01X485111D02*
X488511D01*
G02Y1576680I0J-1502D01*
G01X485111D01*
G02Y1579684I0J1502D01*
G37*
G36*
G01Y1591596D02*
X488511D01*
G02Y1588592I0J-1502D01*
G01X485111D01*
G02Y1591596I0J1502D01*
G37*
G36*
G01X338917Y1603882D02*
X342317D01*
G02Y1600878I0J-1502D01*
G01X338917D01*
G02Y1603882I0J1502D01*
G37*
G36*
G01X1648495Y1615794D02*
X1651895D01*
G02Y1612790I0J-1502D01*
G01X1648495D01*
G02Y1615794I0J1502D01*
G37*
G36*
G01Y1603882D02*
X1651895D01*
G02Y1600878I0J-1502D01*
G01X1648495D01*
G02Y1603882I0J1502D01*
G37*
G36*
G01X1624375Y1615794D02*
X1627775D01*
G02Y1612790I0J-1502D01*
G01X1624375D01*
G02Y1615794I0J1502D01*
G37*
G36*
G01X266557D02*
X269957D01*
G02Y1612790I0J-1502D01*
G01X266557D01*
G02Y1615794I0J1502D01*
G37*
G36*
G01X254497Y1603882D02*
X257897D01*
G02Y1600878I0J-1502D01*
G01X254497D01*
G02Y1603882I0J1502D01*
G37*
G36*
G01X653951Y1591596D02*
X657351D01*
G02Y1588592I0J-1502D01*
G01X653951D01*
G02Y1591596I0J1502D01*
G37*
G36*
G01Y1579684D02*
X657351D01*
G02Y1576680I0J-1502D01*
G01X653951D01*
G02Y1579684I0J1502D01*
G37*
G36*
G01X369797Y1591596D02*
X373197D01*
G02Y1588592I0J-1502D01*
G01X369797D01*
G02Y1591596I0J1502D01*
G37*
G36*
G01X1636435Y1603882D02*
X1639835D01*
G02Y1600878I0J-1502D01*
G01X1636435D01*
G02Y1603882I0J1502D01*
G37*
G36*
G01X266557D02*
X269957D01*
G02Y1600878I0J-1502D01*
G01X266557D01*
G02Y1603882I0J1502D01*
G37*
G36*
G01X1624375D02*
X1627775D01*
G02Y1600878I0J-1502D01*
G01X1624375D01*
G02Y1603882I0J1502D01*
G37*
G36*
G01X254497Y1615794D02*
X257897D01*
G02Y1612790I0J-1502D01*
G01X254497D01*
G02Y1615794I0J1502D01*
G37*
G36*
G01X194197Y1603882D02*
X197597D01*
G02Y1600878I0J-1502D01*
G01X194197D01*
G02Y1603882I0J1502D01*
G37*
G36*
G01X242437D02*
X245837D01*
G02Y1600878I0J-1502D01*
G01X242437D01*
G02Y1603882I0J1502D01*
G37*
G36*
G01X1612315D02*
X1615715D01*
G02Y1600878I0J-1502D01*
G01X1612315D01*
G02Y1603882I0J1502D01*
G37*
G36*
G01Y1615794D02*
X1615715D01*
G02Y1612790I0J-1502D01*
G01X1612315D01*
G02Y1615794I0J1502D01*
G37*
G36*
G01X230377D02*
X233777D01*
G02Y1612790I0J-1502D01*
G01X230377D01*
G02Y1615794I0J1502D01*
G37*
G36*
G01X521291Y1579684D02*
X524691D01*
G02Y1576680I0J-1502D01*
G01X521291D01*
G02Y1579684I0J1502D01*
G37*
G36*
G01Y1591596D02*
X524691D01*
G02Y1588592I0J-1502D01*
G01X521291D01*
G02Y1591596I0J1502D01*
G37*
G36*
G01X497171Y1579684D02*
X500571D01*
G02Y1576680I0J-1502D01*
G01X497171D01*
G02Y1579684I0J1502D01*
G37*
G36*
G01X593651D02*
X597051D01*
G02Y1576680I0J-1502D01*
G01X593651D01*
G02Y1579684I0J1502D01*
G37*
G36*
G01Y1591596D02*
X597051D01*
G02Y1588592I0J-1502D01*
G01X593651D01*
G02Y1591596I0J1502D01*
G37*
G36*
G01X1600255Y1603882D02*
X1603655D01*
G02Y1600878I0J-1502D01*
G01X1600255D01*
G02Y1603882I0J1502D01*
G37*
G36*
G01Y1615794D02*
X1603655D01*
G02Y1612790I0J-1502D01*
G01X1600255D01*
G02Y1615794I0J1502D01*
G37*
G36*
G01X557471Y1579684D02*
X560871D01*
G02Y1576680I0J-1502D01*
G01X557471D01*
G02Y1579684I0J1502D01*
G37*
G36*
G01X569531D02*
X572931D01*
G02Y1576680I0J-1502D01*
G01X569531D01*
G02Y1579684I0J1502D01*
G37*
G36*
G01Y1591596D02*
X572931D01*
G02Y1588592I0J-1502D01*
G01X569531D01*
G02Y1591596I0J1502D01*
G37*
G36*
G01X557471D02*
X560871D01*
G02Y1588592I0J-1502D01*
G01X557471D01*
G02Y1591596I0J1502D01*
G37*
G36*
G01X333617D02*
X337017D01*
G02Y1588592I0J-1502D01*
G01X333617D01*
G02Y1591596I0J1502D01*
G37*
G36*
G01X345677D02*
X349077D01*
G02Y1588592I0J-1502D01*
G01X345677D01*
G02Y1591596I0J1502D01*
G37*
G36*
G01X1607015Y1579684D02*
X1610415D01*
G02Y1576680I0J-1502D01*
G01X1607015D01*
G02Y1579684I0J1502D01*
G37*
G36*
G01X1576135Y1615794D02*
X1579535D01*
G02Y1612790I0J-1502D01*
G01X1576135D01*
G02Y1615794I0J1502D01*
G37*
G36*
G01X314797Y1603882D02*
X318197D01*
G02Y1600878I0J-1502D01*
G01X314797D01*
G02Y1603882I0J1502D01*
G37*
G36*
G01X1576135D02*
X1579535D01*
G02Y1600878I0J-1502D01*
G01X1576135D01*
G02Y1603882I0J1502D01*
G37*
G36*
G01X261257Y1591596D02*
X264657D01*
G02Y1588592I0J-1502D01*
G01X261257D01*
G02Y1591596I0J1502D01*
G37*
G36*
G01X357737Y1579684D02*
X361137D01*
G02Y1576680I0J-1502D01*
G01X357737D01*
G02Y1579684I0J1502D01*
G37*
G36*
G01X1546715Y1591596D02*
X1550115D01*
G02Y1588592I0J-1502D01*
G01X1546715D01*
G02Y1591596I0J1502D01*
G37*
G36*
G01Y1579684D02*
X1550115D01*
G02Y1576680I0J-1502D01*
G01X1546715D01*
G02Y1579684I0J1502D01*
G37*
G36*
G01X326857Y1615794D02*
X330257D01*
G02Y1612790I0J-1502D01*
G01X326857D01*
G02Y1615794I0J1502D01*
G37*
G36*
G01X249197Y1591596D02*
X252597D01*
G02Y1588592I0J-1502D01*
G01X249197D01*
G02Y1591596I0J1502D01*
G37*
G36*
G01X309497D02*
X312897D01*
G02Y1588592I0J-1502D01*
G01X309497D01*
G02Y1591596I0J1502D01*
G37*
G36*
G01X1564075Y1603882D02*
X1567475D01*
G02Y1600878I0J-1502D01*
G01X1564075D01*
G02Y1603882I0J1502D01*
G37*
G36*
G01Y1615794D02*
X1567475D01*
G02Y1612790I0J-1502D01*
G01X1564075D01*
G02Y1615794I0J1502D01*
G37*
G36*
G01X1552015D02*
X1555415D01*
G02Y1612790I0J-1502D01*
G01X1552015D01*
G02Y1615794I0J1502D01*
G37*
G36*
G01X1503775D02*
X1507175D01*
G02Y1612790I0J-1502D01*
G01X1503775D01*
G02Y1615794I0J1502D01*
G37*
G36*
G01X1552015Y1603882D02*
X1555415D01*
G02Y1600878I0J-1502D01*
G01X1552015D01*
G02Y1603882I0J1502D01*
G37*
G36*
G01X629831Y1591596D02*
X633231D01*
G02Y1588592I0J-1502D01*
G01X629831D01*
G02Y1591596I0J1502D01*
G37*
G36*
G01X1377672Y1579684D02*
X1381072D01*
G02Y1576680I0J-1502D01*
G01X1377672D01*
G02Y1579684I0J1502D01*
G37*
G36*
G01X218317Y1603882D02*
X221717D01*
G02Y1600878I0J-1502D01*
G01X218317D01*
G02Y1603882I0J1502D01*
G37*
G36*
G01X206257D02*
X209657D01*
G02Y1600878I0J-1502D01*
G01X206257D01*
G02Y1603882I0J1502D01*
G37*
G36*
G01X1527895Y1615794D02*
X1531295D01*
G02Y1612790I0J-1502D01*
G01X1527895D01*
G02Y1615794I0J1502D01*
G37*
G36*
G01X200957Y1591596D02*
X204357D01*
G02Y1588592I0J-1502D01*
G01X200957D01*
G02Y1591596I0J1502D01*
G37*
G36*
G01X1631135D02*
X1634535D01*
G02Y1588592I0J-1502D01*
G01X1631135D01*
G02Y1591596I0J1502D01*
G37*
G36*
G01X1539955Y1615794D02*
X1543355D01*
G02Y1612790I0J-1502D01*
G01X1539955D01*
G02Y1615794I0J1502D01*
G37*
G36*
G01Y1603882D02*
X1543355D01*
G02Y1600878I0J-1502D01*
G01X1539955D01*
G02Y1603882I0J1502D01*
G37*
G36*
G01X1527895D02*
X1531295D01*
G02Y1600878I0J-1502D01*
G01X1527895D01*
G02Y1603882I0J1502D01*
G37*
G36*
G01X302737Y1615794D02*
X306137D01*
G02Y1612790I0J-1502D01*
G01X302737D01*
G02Y1615794I0J1502D01*
G37*
G36*
G01X1522595Y1579684D02*
X1525995D01*
G02Y1576680I0J-1502D01*
G01X1522595D01*
G02Y1579684I0J1502D01*
G37*
G36*
G01X1515835Y1615794D02*
X1519235D01*
G02Y1612790I0J-1502D01*
G01X1515835D01*
G02Y1615794I0J1502D01*
G37*
G36*
G01X1636435D02*
X1639835D01*
G02Y1612790I0J-1502D01*
G01X1636435D01*
G02Y1615794I0J1502D01*
G37*
G36*
G01X1498475Y1591596D02*
X1501875D01*
G02Y1588592I0J-1502D01*
G01X1498475D01*
G02Y1591596I0J1502D01*
G37*
G36*
G01X1643195D02*
X1646595D01*
G02Y1588592I0J-1502D01*
G01X1643195D01*
G02Y1591596I0J1502D01*
G37*
G36*
G01X1515835Y1603882D02*
X1519235D01*
G02Y1600878I0J-1502D01*
G01X1515835D01*
G02Y1603882I0J1502D01*
G37*
G36*
G01X357737Y1591596D02*
X361137D01*
G02Y1588592I0J-1502D01*
G01X357737D01*
G02Y1591596I0J1502D01*
G37*
G36*
G01X194197Y1615794D02*
X197597D01*
G02Y1612790I0J-1502D01*
G01X194197D01*
G02Y1615794I0J1502D01*
G37*
G36*
G01X1510535Y1579684D02*
X1513935D01*
G02Y1576680I0J-1502D01*
G01X1510535D01*
G02Y1579684I0J1502D01*
G37*
G36*
G01X1570835Y1591596D02*
X1574235D01*
G02Y1588592I0J-1502D01*
G01X1570835D01*
G02Y1591596I0J1502D01*
G37*
G36*
G01X273317D02*
X276717D01*
G02Y1588592I0J-1502D01*
G01X273317D01*
G02Y1591596I0J1502D01*
G37*
G36*
G01Y1579684D02*
X276717D01*
G02Y1576680I0J-1502D01*
G01X273317D01*
G02Y1579684I0J1502D01*
G37*
G36*
G01X1491715Y1603882D02*
X1495115D01*
G02Y1600878I0J-1502D01*
G01X1491715D01*
G02Y1603882I0J1502D01*
G37*
G36*
G01Y1615794D02*
X1495115D01*
G02Y1612790I0J-1502D01*
G01X1491715D01*
G02Y1615794I0J1502D01*
G37*
G36*
G01X1631135Y1579684D02*
X1634535D01*
G02Y1576680I0J-1502D01*
G01X1631135D01*
G02Y1579684I0J1502D01*
G37*
G36*
G01X213017Y1591596D02*
X216417D01*
G02Y1588592I0J-1502D01*
G01X213017D01*
G02Y1591596I0J1502D01*
G37*
G36*
G01X188897Y1579684D02*
X192297D01*
G02Y1576680I0J-1502D01*
G01X188897D01*
G02Y1579684I0J1502D01*
G37*
G36*
G01X1503775Y1603882D02*
X1507175D01*
G02Y1600878I0J-1502D01*
G01X1503775D01*
G02Y1603882I0J1502D01*
G37*
G36*
G01X200957Y1579684D02*
X204357D01*
G02Y1576680I0J-1502D01*
G01X200957D01*
G02Y1579684I0J1502D01*
G37*
G36*
G01X605711D02*
X609111D01*
G02Y1576680I0J-1502D01*
G01X605711D01*
G02Y1579684I0J1502D01*
G37*
G36*
G01X1479655Y1603882D02*
X1483055D01*
G02Y1600878I0J-1502D01*
G01X1479655D01*
G02Y1603882I0J1502D01*
G37*
G36*
G01Y1615794D02*
X1483055D01*
G02Y1612790I0J-1502D01*
G01X1479655D01*
G02Y1615794I0J1502D01*
G37*
G36*
G01X249197Y1579684D02*
X252597D01*
G02Y1576680I0J-1502D01*
G01X249197D01*
G02Y1579684I0J1502D01*
G37*
G36*
G01X1467595Y1615794D02*
X1470995D01*
G02Y1612790I0J-1502D01*
G01X1467595D01*
G02Y1615794I0J1502D01*
G37*
G36*
G01Y1603882D02*
X1470995D01*
G02Y1600878I0J-1502D01*
G01X1467595D01*
G02Y1603882I0J1502D01*
G37*
G36*
G01X1558775Y1591596D02*
X1562175D01*
G02Y1588592I0J-1502D01*
G01X1558775D01*
G02Y1591596I0J1502D01*
G37*
G36*
G01X1643195Y1579684D02*
X1646595D01*
G02Y1576680I0J-1502D01*
G01X1643195D01*
G02Y1579684I0J1502D01*
G37*
G36*
G01X188897Y1591596D02*
X192297D01*
G02Y1588592I0J-1502D01*
G01X188897D01*
G02Y1591596I0J1502D01*
G37*
G36*
G01X1607015D02*
X1610415D01*
G02Y1588592I0J-1502D01*
G01X1607015D01*
G02Y1591596I0J1502D01*
G37*
G36*
G01X1582895D02*
X1586295D01*
G02Y1588592I0J-1502D01*
G01X1582895D01*
G02Y1591596I0J1502D01*
G37*
G36*
G01X225077Y1579684D02*
X228477D01*
G02Y1576680I0J-1502D01*
G01X225077D01*
G02Y1579684I0J1502D01*
G37*
G36*
G01Y1591596D02*
X228477D01*
G02Y1588592I0J-1502D01*
G01X225077D01*
G02Y1591596I0J1502D01*
G37*
G36*
G01X218317Y1615794D02*
X221717D01*
G02Y1612790I0J-1502D01*
G01X218317D01*
G02Y1615794I0J1502D01*
G37*
G36*
G01X290677Y1603882D02*
X294077D01*
G02Y1600878I0J-1502D01*
G01X290677D01*
G02Y1603882I0J1502D01*
G37*
G36*
G01Y1615794D02*
X294077D01*
G02Y1612790I0J-1502D01*
G01X290677D01*
G02Y1615794I0J1502D01*
G37*
G36*
G01X237137Y1579684D02*
X240537D01*
G02Y1576680I0J-1502D01*
G01X237137D01*
G02Y1579684I0J1502D01*
G37*
G36*
G01X213017D02*
X216417D01*
G02Y1576680I0J-1502D01*
G01X213017D01*
G02Y1579684I0J1502D01*
G37*
G36*
G01X230377Y1603882D02*
X233777D01*
G02Y1600878I0J-1502D01*
G01X230377D01*
G02Y1603882I0J1502D01*
G37*
G36*
G01X1619075Y1591596D02*
X1622475D01*
G02Y1588592I0J-1502D01*
G01X1619075D01*
G02Y1591596I0J1502D01*
G37*
G36*
G01X242437Y1615794D02*
X245837D01*
G02Y1612790I0J-1502D01*
G01X242437D01*
G02Y1615794I0J1502D01*
G37*
G36*
G01X369797Y1579684D02*
X373197D01*
G02Y1576680I0J-1502D01*
G01X369797D01*
G02Y1579684I0J1502D01*
G37*
G36*
G01X473051Y1591596D02*
X476451D01*
G02Y1588592I0J-1502D01*
G01X473051D01*
G02Y1591596I0J1502D01*
G37*
G36*
G01Y1579684D02*
X476451D01*
G02Y1576680I0J-1502D01*
G01X473051D01*
G02Y1579684I0J1502D01*
G37*
G36*
G01X1588195Y1603882D02*
X1591595D01*
G02Y1600878I0J-1502D01*
G01X1588195D01*
G02Y1603882I0J1502D01*
G37*
G36*
G01Y1615794D02*
X1591595D01*
G02Y1612790I0J-1502D01*
G01X1588195D01*
G02Y1615794I0J1502D01*
G37*
G36*
G01X61470Y86124D02*
X64870D01*
G02Y83120I0J-1502D01*
G01X61470D01*
G02Y86124I0J1502D01*
G37*
G36*
G01X297437Y1579684D02*
X300837D01*
G02Y1576680I0J-1502D01*
G01X297437D01*
G02Y1579684I0J1502D01*
G37*
G36*
G01X350977Y1615794D02*
X354377D01*
G02Y1612790I0J-1502D01*
G01X350977D01*
G02Y1615794I0J1502D01*
G37*
G36*
G01X375097Y1603882D02*
X378497D01*
G02Y1600878I0J-1502D01*
G01X375097D01*
G02Y1603882I0J1502D01*
G37*
G36*
G01Y1615794D02*
X378497D01*
G02Y1612790I0J-1502D01*
G01X375097D01*
G02Y1615794I0J1502D01*
G37*
G36*
G01X363037Y1603882D02*
X366437D01*
G02Y1600878I0J-1502D01*
G01X363037D01*
G02Y1603882I0J1502D01*
G37*
G36*
G01X1320456Y1124651D02*
G02X1323050I1297J0D01*
G02X1322978Y1124223I-1298J-2D01*
G01X1322948Y1124137D01*
X1323755Y1122739D01*
X1323845Y1122722D01*
G02X1324900Y1121447I-243J-1275D01*
G02X1322306I-1297J0D01*
G02X1322378Y1121875I1298J2D01*
G01X1322408Y1121961D01*
X1321601Y1123359D01*
X1321511Y1123376D01*
G02X1320456Y1124651I243J1275D01*
G37*
G36*
G01X1340806Y1108630D02*
G02X1343400I1297J0D01*
G02X1342345Y1107355I-1298J0D01*
G01X1342255Y1107338D01*
X1341448Y1105941D01*
X1341478Y1105855D01*
G02X1341551Y1105426I-1224J-429D01*
G01Y1105424D01*
G02X1340254Y1104128I-1297J1D01*
G02X1338956Y1105426I0J1298D01*
G02X1340011Y1106701I1298J0D01*
G01X1340101Y1106718D01*
X1340908Y1108116D01*
X1340878Y1108202D01*
G02X1340806Y1108630I1226J426D01*
G37*
G36*
G01X1505022Y873810D02*
G02X1507618I1298J0D01*
G01Y873808D01*
G02X1507545Y873381I-1298J2D01*
G01X1507515Y873295D01*
X1508321Y871898D01*
X1508411Y871881D01*
G02X1509468Y870606I-240J-1275D01*
G02X1506874I-1297J0D01*
G01Y870607D01*
G02X1506945Y871032I1297J2D01*
G01X1506975Y871118D01*
X1506168Y872518D01*
X1506078Y872535D01*
G02X1505022Y873810I242J1275D01*
G37*
G36*
G01X366080Y886625D02*
Y886627D01*
G02X368676I1298J0D01*
G02X367620Y885352I-1298J0D01*
G01X367530Y885335D01*
X366724Y883938D01*
X366754Y883852D01*
G02X366826Y883425I-1226J-426D01*
G01Y883423D01*
G02X364232I-1297J0D01*
G02X365287Y884698I1298J0D01*
G01X365377Y884715D01*
X366183Y886112D01*
X366153Y886198D01*
G02X366080Y886625I1225J429D01*
G37*
G36*
G01X1313541Y1122224D02*
X1315165D01*
G02X1316203Y1122744I1038J-776D01*
G02Y1120150I0J-1297D01*
G02X1315165Y1120670I0J1296D01*
G01X1313541D01*
G02X1312503Y1120150I-1038J776D01*
G02Y1122744I0J1297D01*
G02X1313541Y1122224I0J-1296D01*
G37*
G36*
G01X1505024Y886625D02*
Y886627D01*
G02X1507618I1297J0D01*
G02X1506563Y885352I-1298J0D01*
G01X1506473Y885335D01*
X1505666Y883937D01*
X1505696Y883851D01*
G02X1505768Y883423I-1226J-426D01*
G02X1503174I-1297J0D01*
G02X1504230Y884698I1298J0D01*
G01X1504320Y884715D01*
X1505126Y886112D01*
X1505096Y886198D01*
G02X1505024Y886625I1226J426D01*
G37*
G36*
G01X528880Y873810D02*
G02X531476I1298J0D01*
G01Y873808D01*
G02X531403Y873381I-1298J2D01*
G01X531373Y873295D01*
X532179Y871898D01*
X532269Y871881D01*
G02X533326Y870606I-240J-1275D01*
G02X530732I-1297J0D01*
G01Y870607D01*
G02X530803Y871032I1297J2D01*
G01X530833Y871118D01*
X530026Y872518D01*
X529936Y872535D01*
G02X528880Y873810I242J1275D01*
G37*
G36*
G01X349864Y1108630D02*
G02X352460I1298J0D01*
G01Y1108628D01*
G02X352387Y1108201I-1298J2D01*
G01X352357Y1108115D01*
X353164Y1106718D01*
X353254Y1106701D01*
G02X354308Y1105426I-244J-1275D01*
G01Y1105424D01*
G02X353011Y1104128I-1297J1D01*
G02X351714Y1105426I1J1298D01*
G02X351787Y1105855I1297J0D01*
G01X351817Y1105941D01*
X351010Y1107338D01*
X350920Y1107355D01*
G02X349864Y1108630I242J1275D01*
G37*
G36*
G01X1326492Y1112612D02*
X1328116D01*
G02X1329154Y1113132I1038J-776D01*
G02Y1110536I0J-1298D01*
G02X1328116Y1111056I0J1296D01*
G01X1326492D01*
G02X1325454Y1110536I-1038J776D01*
G02Y1113132I0J1298D01*
G02X1326492Y1112612I0J-1296D01*
G37*
G36*
G01X1316756Y1111834D02*
G02X1319352I1298J0D01*
G02X1319279Y1111406I-1299J1D01*
G01X1319249Y1111320D01*
X1320056Y1109922D01*
X1320146Y1109905D01*
G02X1321202Y1108630I-242J-1275D01*
G02X1318606I-1298J0D01*
G02X1318679Y1109058I1299J-1D01*
G01X1318709Y1109144D01*
X1317902Y1110542D01*
X1317812Y1110559D01*
G02X1316756Y1111834I242J1275D01*
G37*
G36*
G01X337399Y1122224D02*
X339023D01*
G02X340061Y1122744I1038J-776D01*
G02Y1120150I0J-1297D01*
G02X339023Y1120670I0J1296D01*
G01X337399D01*
G02X336361Y1120150I-1038J776D01*
G02Y1122744I0J1297D01*
G02X337399Y1122224I0J-1296D01*
G37*
G36*
G01X344799Y1128634D02*
X346423D01*
G02X347461Y1129154I1038J-776D01*
G02Y1126558I0J-1298D01*
G02X346423Y1127078I0J1296D01*
G01X344799D01*
G02X343761Y1126558I-1038J776D01*
G02Y1129154I0J1298D01*
G02X344799Y1128634I0J-1296D01*
G37*
G36*
G01X515932Y883423D02*
G02X518526I1297J0D01*
G01Y883421D01*
G02X518454Y882994I-1298J-1D01*
G01X518424Y882908D01*
X519230Y881511D01*
X519320Y881494D01*
G02X520376Y880219I-242J-1275D01*
G02X517780I-1298J0D01*
G02X517853Y880647I1299J-1D01*
G01X517883Y880733D01*
X517077Y882131D01*
X516987Y882148D01*
G02X515932Y883423I243J1275D01*
G37*
G36*
G01X523332D02*
G02X525926I1297J0D01*
G01Y883421D01*
G02X525854Y882994I-1298J-1D01*
G01X525824Y882908D01*
X526630Y881511D01*
X526720Y881494D01*
G02X527776Y880219I-242J-1275D01*
G02X525182I-1297J0D01*
G01Y880221D01*
G02X525254Y880646I1297J-1D01*
G01X525284Y880732D01*
X524477Y882131D01*
X524387Y882148D01*
G02X523332Y883423I243J1275D01*
G37*
G36*
G01X1333406Y1115039D02*
G02X1336000I1297J0D01*
G01Y1115037D01*
G02X1335928Y1114610I-1298J-1D01*
G01X1335898Y1114524D01*
X1336705Y1113126D01*
X1336795Y1113109D01*
G02X1337852Y1111834I-240J-1275D01*
G02X1335256I-1298J0D01*
G02X1335329Y1112262I1299J-1D01*
G01X1335359Y1112348D01*
X1334551Y1113747D01*
X1334461Y1113764D01*
G02X1333406Y1115039I243J1275D01*
G37*
G36*
G01X350350Y1112612D02*
X351974D01*
G02X353012Y1113132I1038J-776D01*
G02Y1110536I0J-1298D01*
G02X351974Y1111056I0J1296D01*
G01X350350D01*
G02X349312Y1110536I-1038J776D01*
G02Y1113132I0J1298D01*
G02X350350Y1112612I0J-1296D01*
G37*
G36*
G01X360532Y883423D02*
G02X363126I1297J0D01*
G01Y883421D01*
G02X363054Y882994I-1298J-1D01*
G01X363024Y882908D01*
X363830Y881511D01*
X363920Y881494D01*
G02X364976Y880219I-242J-1275D01*
G02X362380I-1298J0D01*
G02X362453Y880647I1299J-1D01*
G01X362483Y880733D01*
X361677Y882131D01*
X361587Y882148D01*
G02X360532Y883423I243J1275D01*
G37*
G36*
G01X1319091Y1106204D02*
X1320715D01*
G02X1321753Y1106724I1038J-776D01*
G02Y1104128I0J-1298D01*
G02X1320715Y1104648I0J1296D01*
G01X1319091D01*
G02X1318053Y1104128I-1038J776D01*
G02Y1106724I0J1298D01*
G02X1319091Y1106204I0J-1296D01*
G37*
G36*
G01X358680Y886625D02*
Y886627D01*
G02X361276I1298J0D01*
G02X360220Y885352I-1298J0D01*
G01X360130Y885335D01*
X359324Y883938D01*
X359354Y883852D01*
G02X359426Y883425I-1226J-426D01*
G01Y883423D01*
G02X356832I-1297J0D01*
G02X357887Y884698I1298J0D01*
G01X357977Y884715D01*
X358783Y886112D01*
X358753Y886198D01*
G02X358680Y886625I1225J429D01*
G37*
G36*
G01X1342222D02*
Y886627D01*
G02X1344818I1298J0D01*
G02X1343762Y885352I-1298J0D01*
G01X1343672Y885335D01*
X1342866Y883938D01*
X1342896Y883852D01*
G02X1342968Y883425I-1226J-426D01*
G01Y883423D01*
G02X1340374I-1297J0D01*
G02X1341429Y884698I1298J0D01*
G01X1341519Y884715D01*
X1342325Y886112D01*
X1342295Y886198D01*
G02X1342222Y886625I1225J429D01*
G37*
G36*
G01X353132Y883423D02*
G02X355726I1297J0D01*
G01Y883421D01*
G02X355654Y882994I-1298J-1D01*
G01X355624Y882908D01*
X356430Y881511D01*
X356520Y881494D01*
G02X357576Y880219I-242J-1275D01*
G02X354980I-1298J0D01*
G02X355053Y880647I1299J-1D01*
G01X355083Y880733D01*
X354277Y882131D01*
X354187Y882148D01*
G02X353132Y883423I243J1275D01*
G37*
G36*
G01X342949Y1106204D02*
X344573D01*
G02X345611Y1106724I1038J-776D01*
G02Y1104128I0J-1298D01*
G02X344573Y1104648I0J1296D01*
G01X342949D01*
G02X341911Y1104128I-1038J776D01*
G02Y1106724I0J1298D01*
G02X342949Y1106204I0J-1296D01*
G37*
G36*
G01X1334822Y886625D02*
Y886627D01*
G02X1337418I1298J0D01*
G02X1336362Y885352I-1298J0D01*
G01X1336272Y885335D01*
X1335466Y883938D01*
X1335496Y883852D01*
G02X1335568Y883425I-1226J-426D01*
G01Y883423D01*
G02X1332974I-1297J0D01*
G02X1334029Y884698I1298J0D01*
G01X1334119Y884715D01*
X1334925Y886112D01*
X1334895Y886198D01*
G02X1334822Y886625I1225J429D01*
G37*
G36*
G01X528882D02*
Y886627D01*
G02X531476I1297J0D01*
G02X530421Y885352I-1298J0D01*
G01X530331Y885335D01*
X529524Y883937D01*
X529554Y883851D01*
G02X529626Y883423I-1226J-426D01*
G02X527032I-1297J0D01*
G02X528088Y884698I1298J0D01*
G01X528178Y884715D01*
X528984Y886112D01*
X528954Y886198D01*
G02X528882Y886625I1226J426D01*
G37*
G36*
G01X357264Y1115039D02*
G02X359858I1297J0D01*
G01Y1115037D01*
G02X359786Y1114610I-1298J-1D01*
G01X359756Y1114524D01*
X360563Y1113126D01*
X360653Y1113109D01*
G02X361710Y1111834I-240J-1275D01*
G02X359114I-1298J0D01*
G02X359187Y1112262I1299J-1D01*
G01X359217Y1112348D01*
X358409Y1113747D01*
X358319Y1113764D01*
G02X357264Y1115039I243J1275D01*
G37*
G36*
G01X1499474Y883423D02*
G02X1502068I1297J0D01*
G01Y883421D01*
G02X1501996Y882994I-1298J-1D01*
G01X1501966Y882908D01*
X1502772Y881511D01*
X1502862Y881494D01*
G02X1503918Y880219I-242J-1275D01*
G02X1501324I-1297J0D01*
G01Y880221D01*
G02X1501396Y880646I1297J-1D01*
G01X1501426Y880732D01*
X1500619Y882131D01*
X1500529Y882148D01*
G02X1499474Y883423I243J1275D01*
G37*
G36*
G01X340614Y1111834D02*
G02X343210I1298J0D01*
G02X343137Y1111406I-1299J1D01*
G01X343107Y1111320D01*
X343914Y1109922D01*
X344004Y1109905D01*
G02X345060Y1108630I-242J-1275D01*
G02X342464I-1298J0D01*
G02X342537Y1109058I1299J-1D01*
G01X342567Y1109144D01*
X341760Y1110542D01*
X341670Y1110559D01*
G02X340614Y1111834I242J1275D01*
G37*
G36*
G01X364664Y1108630D02*
G02X367258I1297J0D01*
G02X366203Y1107355I-1298J0D01*
G01X366113Y1107338D01*
X365306Y1105941D01*
X365336Y1105855D01*
G02X365409Y1105426I-1224J-429D01*
G01Y1105424D01*
G02X364112Y1104128I-1297J1D01*
G02X362814Y1105426I0J1298D01*
G02X363869Y1106701I1298J0D01*
G01X363959Y1106718D01*
X364766Y1108116D01*
X364736Y1108202D01*
G02X364664Y1108630I1226J426D01*
G37*
G36*
G01X1320941Y1128634D02*
X1322565D01*
G02X1323603Y1129154I1038J-776D01*
G02Y1126558I0J-1298D01*
G02X1322565Y1127078I0J1296D01*
G01X1320941D01*
G02X1319903Y1126558I-1038J776D01*
G02Y1129154I0J1298D01*
G02X1320941Y1128634I0J-1296D01*
G37*
G36*
G01X1336674Y883423D02*
G02X1339268I1297J0D01*
G01Y883421D01*
G02X1339196Y882994I-1298J-1D01*
G01X1339166Y882908D01*
X1339972Y881511D01*
X1340062Y881494D01*
G02X1341118Y880219I-242J-1275D01*
G02X1338522I-1298J0D01*
G02X1338595Y880647I1299J-1D01*
G01X1338625Y880733D01*
X1337819Y882131D01*
X1337729Y882148D01*
G02X1336674Y883423I243J1275D01*
G37*
G36*
G01X1330101Y541552D02*
X1333143D01*
G02Y538546I0J-1503D01*
G01X1330101D01*
G02Y541552I0J1503D01*
G37*
G36*
G01X521480Y873810D02*
G02X524076I1298J0D01*
G01Y873808D01*
G02X524003Y873381I-1298J2D01*
G01X523973Y873295D01*
X524779Y871898D01*
X524869Y871881D01*
G02X525926Y870606I-240J-1275D01*
G02X523332I-1297J0D01*
G01Y870607D01*
G02X523403Y871032I1297J2D01*
G01X523433Y871118D01*
X522626Y872518D01*
X522536Y872535D01*
G02X521480Y873810I242J1275D01*
G37*
G36*
G01X1492074Y883423D02*
G02X1494668I1297J0D01*
G01Y883421D01*
G02X1494596Y882994I-1298J-1D01*
G01X1494566Y882908D01*
X1495372Y881511D01*
X1495462Y881494D01*
G02X1496518Y880219I-242J-1275D01*
G02X1493922I-1298J0D01*
G02X1493995Y880647I1299J-1D01*
G01X1494025Y880733D01*
X1493219Y882131D01*
X1493129Y882148D01*
G02X1492074Y883423I243J1275D01*
G37*
G36*
G01X344314Y1124651D02*
G02X346908I1297J0D01*
G02X346836Y1124223I-1298J-2D01*
G01X346806Y1124137D01*
X347613Y1122739D01*
X347703Y1122722D01*
G02X348758Y1121447I-243J-1275D01*
G02X346164I-1297J0D01*
G02X346236Y1121875I1298J2D01*
G01X346266Y1121961D01*
X345459Y1123359D01*
X345369Y1123376D01*
G02X344314Y1124651I243J1275D01*
G37*
G36*
G01X1497622Y873810D02*
G02X1500218I1298J0D01*
G01Y873808D01*
G02X1500145Y873381I-1298J2D01*
G01X1500115Y873295D01*
X1500921Y871898D01*
X1501011Y871881D01*
G02X1502068Y870606I-240J-1275D01*
G02X1499474I-1297J0D01*
G01Y870607D01*
G02X1499545Y871032I1297J2D01*
G01X1499575Y871118D01*
X1498768Y872518D01*
X1498678Y872535D01*
G02X1497622Y873810I242J1275D01*
G37*
G36*
G01X1326006Y1108630D02*
G02X1328602I1298J0D01*
G01Y1108628D01*
G02X1328529Y1108201I-1298J2D01*
G01X1328499Y1108115D01*
X1329306Y1106718D01*
X1329396Y1106701D01*
G02X1330450Y1105426I-244J-1275D01*
G01Y1105424D01*
G02X1329153Y1104128I-1297J1D01*
G02X1327856Y1105426I1J1298D01*
G02X1327929Y1105855I1297J0D01*
G01X1327959Y1105941D01*
X1327152Y1107338D01*
X1327062Y1107355D01*
G02X1326006Y1108630I242J1275D01*
G37*
G36*
G01X1358624Y283142D02*
X1355224D01*
G02Y286146I0J1502D01*
G01X1358624D01*
G02Y283142I0J-1502D01*
G37*
G36*
G01X1348084Y278756D02*
X1344684D01*
G02Y281762I0J1503D01*
G01X1348084D01*
G02Y278756I0J-1503D01*
G37*
G36*
G01X1368524Y281242D02*
X1365124D01*
G02Y284246I0J1502D01*
G01X1368524D01*
G02Y281242I0J-1502D01*
G37*
G36*
G01X1328480Y322400D02*
X1325080D01*
G02Y325404I0J1502D01*
G01X1328480D01*
G02Y322400I0J-1502D01*
G37*
G36*
G01X613970Y190254D02*
X617370D01*
G02Y187250I0J-1502D01*
G01X613970D01*
G02Y190254I0J1502D01*
G37*
G36*
G01X64571Y427304D02*
X61171D01*
G02Y430308I0J1502D01*
G01X64571D01*
G02Y427304I0J-1502D01*
G37*
G36*
G01X626640Y190254D02*
X630040D01*
G02Y187250I0J-1502D01*
G01X626640D01*
G02Y190254I0J1502D01*
G37*
G36*
G01X423180Y1601300D02*
X419780D01*
G02Y1604304I0J1502D01*
G01X423180D01*
G02Y1601300I0J-1502D01*
G37*
G36*
G01X49360Y427304D02*
X45960D01*
G02Y430308I0J1502D01*
G01X49360D01*
G02Y427304I0J-1502D01*
G37*
G36*
G01X1400985Y242432D02*
X1404385D01*
G02Y239426I0J-1503D01*
G01X1400985D01*
G02Y242432I0J1503D01*
G37*
G36*
G01X930731Y531982D02*
X933773D01*
G02Y528976I0J-1503D01*
G01X930731D01*
G02Y531982I0J1503D01*
G37*
G36*
G01X285377Y1591596D02*
X288777D01*
G02Y1588592I0J-1502D01*
G01X285377D01*
G02Y1591596I0J1502D01*
G37*
G36*
G01X229131Y49144D02*
X225731D01*
G02Y52148I0J1502D01*
G01X229131D01*
G02Y49144I0J-1502D01*
G37*
G36*
G01X284230D02*
X280830D01*
G02Y52148I0J1502D01*
G01X284230D01*
G02Y49144I0J-1502D01*
G37*
G36*
G01X1755272Y27934D02*
X1758672D01*
G02Y24928I0J-1503D01*
G01X1755272D01*
G02Y27934I0J1503D01*
G37*
G36*
G01X1530660Y101664D02*
X1534060D01*
G02Y98660I0J-1502D01*
G01X1530660D01*
G02Y101664I0J1502D01*
G37*
G36*
G01X1549308Y27934D02*
X1552708D01*
G02Y24928I0J-1503D01*
G01X1549308D01*
G02Y27934I0J1503D01*
G37*
G36*
G01X1556413Y20998D02*
X1559813D01*
G02Y17992I0J-1503D01*
G01X1556413D01*
G02Y20998I0J1503D01*
G37*
G36*
G01X1563481Y27934D02*
X1566881D01*
G02Y24928I0J-1503D01*
G01X1563481D01*
G02Y27934I0J1503D01*
G37*
G36*
G01X1570586Y20998D02*
X1573986D01*
G02Y17992I0J-1503D01*
G01X1570586D01*
G02Y20998I0J1503D01*
G37*
G36*
G01X1577654Y27934D02*
X1581054D01*
G02Y24928I0J-1503D01*
G01X1577654D01*
G02Y27934I0J1503D01*
G37*
G36*
G01X1584759Y20998D02*
X1588159D01*
G02Y17992I0J-1503D01*
G01X1584759D01*
G02Y20998I0J1503D01*
G37*
G36*
G01X1591828Y27934D02*
X1595228D01*
G02Y24928I0J-1503D01*
G01X1591828D01*
G02Y27934I0J1503D01*
G37*
G36*
G01X1598933Y20998D02*
X1602333D01*
G02Y17992I0J-1503D01*
G01X1598933D01*
G02Y20998I0J1503D01*
G37*
G36*
G01X1627694Y27934D02*
X1631094D01*
G02Y24928I0J-1503D01*
G01X1627694D01*
G02Y27934I0J1503D01*
G37*
G36*
G01X1634799Y20998D02*
X1638199D01*
G02Y17992I0J-1503D01*
G01X1634799D01*
G02Y20998I0J1503D01*
G37*
G36*
G01X218667Y21040D02*
X222067D01*
G02Y18036I0J-1502D01*
G01X218667D01*
G02Y21040I0J1502D01*
G37*
G36*
G01X211562Y27976D02*
X214962D01*
G02Y24972I0J-1502D01*
G01X211562D01*
G02Y27976I0J1502D01*
G37*
G36*
G01X204494Y21040D02*
X207894D01*
G02Y18036I0J-1502D01*
G01X204494D01*
G02Y21040I0J1502D01*
G37*
G36*
G01X197389Y27976D02*
X200789D01*
G02Y24972I0J-1502D01*
G01X197389D01*
G02Y27976I0J1502D01*
G37*
G36*
G01X167428D02*
X170828D01*
G02Y24972I0J-1502D01*
G01X167428D01*
G02Y27976I0J1502D01*
G37*
G36*
G01X174533Y21040D02*
X177933D01*
G02Y18036I0J-1502D01*
G01X174533D01*
G02Y21040I0J1502D01*
G37*
G36*
G01X153255Y27976D02*
X156655D01*
G02Y24972I0J-1502D01*
G01X153255D01*
G02Y27976I0J1502D01*
G37*
G36*
G01X160360Y21040D02*
X163760D01*
G02Y18036I0J-1502D01*
G01X160360D01*
G02Y21040I0J1502D01*
G37*
G36*
G01X124494D02*
X127894D01*
G02Y18036I0J-1502D01*
G01X124494D01*
G02Y21040I0J1502D01*
G37*
G36*
G01X117389Y27976D02*
X120789D01*
G02Y24972I0J-1502D01*
G01X117389D01*
G02Y27976I0J1502D01*
G37*
G36*
G01X103215D02*
X106615D01*
G02Y24972I0J-1502D01*
G01X103215D01*
G02Y27976I0J1502D01*
G37*
G36*
G01X110320Y21040D02*
X113720D01*
G02Y18036I0J-1502D01*
G01X110320D01*
G02Y21040I0J1502D01*
G37*
G36*
G01X89042Y27976D02*
X92442D01*
G02Y24972I0J-1502D01*
G01X89042D01*
G02Y27976I0J1502D01*
G37*
G36*
G01X96147Y21040D02*
X99547D01*
G02Y18036I0J-1502D01*
G01X96147D01*
G02Y21040I0J1502D01*
G37*
G36*
G01X74869Y27976D02*
X78269D01*
G02Y24972I0J-1502D01*
G01X74869D01*
G02Y27976I0J1502D01*
G37*
G36*
G01X81974Y21040D02*
X85374D01*
G02Y18036I0J-1502D01*
G01X81974D01*
G02Y21040I0J1502D01*
G37*
G36*
G01X1641867Y27934D02*
X1645267D01*
G02Y24928I0J-1503D01*
G01X1641867D01*
G02Y27934I0J1503D01*
G37*
G36*
G01X1648972Y20998D02*
X1652372D01*
G02Y17992I0J-1503D01*
G01X1648972D01*
G02Y20998I0J1503D01*
G37*
G36*
G01X1671828Y27934D02*
X1675228D01*
G02Y24928I0J-1503D01*
G01X1671828D01*
G02Y27934I0J1503D01*
G37*
G36*
G01X1678933Y20998D02*
X1682333D01*
G02Y17992I0J-1503D01*
G01X1678933D01*
G02Y20998I0J1503D01*
G37*
G36*
G01X1686001Y27934D02*
X1689401D01*
G02Y24928I0J-1503D01*
G01X1686001D01*
G02Y27934I0J1503D01*
G37*
G36*
G01X1693106Y20998D02*
X1696506D01*
G02Y17992I0J-1503D01*
G01X1693106D01*
G02Y20998I0J1503D01*
G37*
G36*
G01X1700217Y27962D02*
X1703617D01*
G02Y24956I0J-1503D01*
G01X1700217D01*
G02Y27962I0J1503D01*
G37*
G36*
G01X1700170Y52152D02*
X1703570D01*
G02Y49146I0J-1503D01*
G01X1700170D01*
G02Y52152I0J1503D01*
G37*
G36*
G01X670612Y48766D02*
X674012D01*
G02Y45762I0J-1502D01*
G01X670612D01*
G02Y48766I0J1502D01*
G37*
G36*
G01X284233Y24972D02*
X280833D01*
G02Y27976I0J1502D01*
G01X284233D01*
G02Y24972I0J-1502D01*
G37*
G36*
G01X1307442Y305496D02*
X1304042D01*
G02Y308500I0J1502D01*
G01X1307442D01*
G02Y305496I0J-1502D01*
G37*
G36*
G01X1382972Y1603882D02*
X1386372D01*
G02Y1600878I0J-1502D01*
G01X1382972D01*
G02Y1603882I0J1502D01*
G37*
G36*
G01Y1615794D02*
X1386372D01*
G02Y1612790I0J-1502D01*
G01X1382972D01*
G02Y1615794I0J1502D01*
G37*
G36*
G01X229135Y24972D02*
X225735D01*
G02Y27976I0J1502D01*
G01X229135D01*
G02Y24972I0J-1502D01*
G37*
G36*
G01X350977Y1603882D02*
X354377D01*
G02Y1600878I0J-1502D01*
G01X350977D01*
G02Y1603882I0J1502D01*
G37*
G36*
G01X1307042Y291134D02*
X1303642D01*
G02Y294138I0J1502D01*
G01X1307042D01*
G02Y291134I0J-1502D01*
G37*
G36*
G01X405990Y1617450D02*
X402590D01*
G02Y1620454I0J1502D01*
G01X405990D01*
G02Y1617450I0J-1502D01*
G37*
G36*
G01X441740Y1650764D02*
X438340D01*
G02Y1653768I0J1502D01*
G01X441740D01*
G02Y1650764I0J-1502D01*
G37*
G36*
G01X49212Y450100D02*
X45812D01*
G02Y453104I0J1502D01*
G01X49212D01*
G02Y450100I0J-1502D01*
G37*
G36*
G01X1418630Y221520D02*
X1422030D01*
G02Y218516I0J-1502D01*
G01X1418630D01*
G02Y221520I0J1502D01*
G37*
G36*
G01X1407420D02*
X1410820D01*
G02Y218516I0J-1502D01*
G01X1407420D01*
G02Y221520I0J1502D01*
G37*
G36*
G01X1432660D02*
X1436060D01*
G02Y218516I0J-1502D01*
G01X1432660D01*
G02Y221520I0J1502D01*
G37*
G36*
G01X862930Y71574D02*
X866330D01*
G02Y68570I0J-1502D01*
G01X862930D01*
G02Y71574I0J1502D01*
G37*
G36*
G01X1348824Y327478D02*
X1345424D01*
G02Y330484I0J1503D01*
G01X1348824D01*
G02Y327478I0J-1503D01*
G37*
G36*
G01X1341431Y321190D02*
X1338031D01*
G02Y324196I0J1503D01*
G01X1341431D01*
G02Y321190I0J-1503D01*
G37*
G36*
G01X1335145Y331114D02*
X1331745D01*
G02Y334118I0J1502D01*
G01X1335145D01*
G02Y331114I0J-1502D01*
G37*
G36*
G01X1319618Y316570D02*
X1316218D01*
G02Y319576I0J1503D01*
G01X1319618D01*
G02Y316570I0J-1503D01*
G37*
G36*
G01X1311077Y321494D02*
X1307677D01*
G02Y324498I0J1502D01*
G01X1311077D01*
G02Y321494I0J-1502D01*
G37*
G36*
G01X1380602Y199170D02*
X1384002D01*
G02Y196166I0J-1502D01*
G01X1380602D01*
G02Y199170I0J1502D01*
G37*
G36*
G01X1398006D02*
X1401406D01*
G02Y196166I0J-1502D01*
G01X1398006D01*
G02Y199170I0J1502D01*
G37*
G36*
G01X1373591Y177932D02*
X1376991D01*
G02Y174928I0J-1502D01*
G01X1373591D01*
G02Y177932I0J1502D01*
G37*
G36*
G01X1169820Y637554D02*
X1173220D01*
G02Y634550I0J-1502D01*
G01X1169820D01*
G02Y637554I0J1502D01*
G37*
G36*
G01X519764Y41830D02*
X523164D01*
G02Y38826I0J-1502D01*
G01X519764D01*
G02Y41830I0J1502D01*
G37*
G36*
G01X732793Y72938D02*
X736193D01*
G02Y69934I0J-1502D01*
G01X732793D01*
G02Y72938I0J1502D01*
G37*
G36*
G01X1161860Y643614D02*
X1165260D01*
G02Y640610I0J-1502D01*
G01X1161860D01*
G02Y643614I0J1502D01*
G37*
G36*
G01X663543Y44830D02*
X666943D01*
G02Y41826I0J-1502D01*
G01X663543D01*
G02Y44830I0J1502D01*
G37*
G36*
G01X656439Y48766D02*
X659839D01*
G02Y45762I0J-1502D01*
G01X656439D01*
G02Y48766I0J1502D01*
G37*
G36*
G01X562771Y1603882D02*
X566171D01*
G02Y1600878I0J-1502D01*
G01X562771D01*
G02Y1603882I0J1502D01*
G37*
G36*
G01X538651D02*
X542051D01*
G02Y1600878I0J-1502D01*
G01X538651D01*
G02Y1603882I0J1502D01*
G37*
G36*
G01X1406970Y140244D02*
X1410370D01*
G02Y137240I0J-1502D01*
G01X1406970D01*
G02Y140244I0J1502D01*
G37*
G36*
G01X1323303Y297674D02*
X1319903D01*
G02Y300678I0J1502D01*
G01X1323303D01*
G02Y297674I0J-1502D01*
G37*
G36*
G01X1361771Y330772D02*
X1358371D01*
G02Y333778I0J1503D01*
G01X1361771D01*
G02Y330772I0J-1503D01*
G37*
G36*
G01X555175Y72938D02*
X558575D01*
G02Y69934I0J-1502D01*
G01X555175D01*
G02Y72938I0J1502D01*
G37*
G36*
G01X541002D02*
X544402D01*
G02Y69934I0J-1502D01*
G01X541002D01*
G02Y72938I0J1502D01*
G37*
G36*
G01X519742D02*
X523142D01*
G02Y69934I0J-1502D01*
G01X519742D01*
G02Y72938I0J1502D01*
G37*
G36*
G01X533915Y61324D02*
X537315D01*
G02Y58320I0J-1502D01*
G01X533915D01*
G02Y61324I0J1502D01*
G37*
G36*
G01X1294500Y298190D02*
X1291100D01*
G02Y301194I0J1502D01*
G01X1294500D01*
G02Y298190I0J-1502D01*
G37*
G36*
G01X1404829Y185766D02*
X1408229D01*
G02Y182760I0J-1503D01*
G01X1404829D01*
G02Y185766I0J1503D01*
G37*
G36*
G01X538651Y1615794D02*
X542051D01*
G02Y1612790I0J-1502D01*
G01X538651D01*
G02Y1615794I0J1502D01*
G37*
G36*
G01X526591Y1603882D02*
X529991D01*
G02Y1600878I0J-1502D01*
G01X526591D01*
G02Y1603882I0J1502D01*
G37*
G36*
G01X514531D02*
X517931D01*
G02Y1600878I0J-1502D01*
G01X514531D01*
G02Y1603882I0J1502D01*
G37*
G36*
G01X526591Y1615794D02*
X529991D01*
G02Y1612790I0J-1502D01*
G01X526591D01*
G02Y1615794I0J1502D01*
G37*
G36*
G01X514531D02*
X517931D01*
G02Y1612790I0J-1502D01*
G01X514531D01*
G02Y1615794I0J1502D01*
G37*
G36*
G01X490411Y1603882D02*
X493811D01*
G02Y1600878I0J-1502D01*
G01X490411D01*
G02Y1603882I0J1502D01*
G37*
G36*
G01X478351Y1615794D02*
X481751D01*
G02Y1612790I0J-1502D01*
G01X478351D01*
G02Y1615794I0J1502D01*
G37*
G36*
G01X502471D02*
X505871D01*
G02Y1612790I0J-1502D01*
G01X502471D01*
G02Y1615794I0J1502D01*
G37*
G36*
G01X478351Y1603882D02*
X481751D01*
G02Y1600878I0J-1502D01*
G01X478351D01*
G02Y1603882I0J1502D01*
G37*
G36*
G01X1412284Y173198D02*
X1415684D01*
G02Y170194I0J-1502D01*
G01X1412284D01*
G02Y173198I0J1502D01*
G37*
G36*
G01X598951Y1603882D02*
X602351D01*
G02Y1600878I0J-1502D01*
G01X598951D01*
G02Y1603882I0J1502D01*
G37*
G36*
G01Y1615794D02*
X602351D01*
G02Y1612790I0J-1502D01*
G01X598951D01*
G02Y1615794I0J1502D01*
G37*
G36*
G01X586891Y1603882D02*
X590291D01*
G02Y1600878I0J-1502D01*
G01X586891D01*
G02Y1603882I0J1502D01*
G37*
G36*
G01X647191D02*
X650591D01*
G02Y1600878I0J-1502D01*
G01X647191D01*
G02Y1603882I0J1502D01*
G37*
G36*
G01X635131Y1615794D02*
X638531D01*
G02Y1612790I0J-1502D01*
G01X635131D01*
G02Y1615794I0J1502D01*
G37*
G36*
G01X647191D02*
X650591D01*
G02Y1612790I0J-1502D01*
G01X647191D01*
G02Y1615794I0J1502D01*
G37*
G36*
G01X623071D02*
X626471D01*
G02Y1612790I0J-1502D01*
G01X623071D01*
G02Y1615794I0J1502D01*
G37*
G36*
G01X1355200Y336340D02*
X1351800D01*
G02Y339346I0J1503D01*
G01X1355200D01*
G02Y336340I0J-1503D01*
G37*
G36*
G01X1328814Y292054D02*
X1325414D01*
G02Y295058I0J1502D01*
G01X1328814D01*
G02Y292054I0J-1502D01*
G37*
G36*
G01X1340161Y291902D02*
X1336761D01*
G02Y294906I0J1502D01*
G01X1340161D01*
G02Y291902I0J-1502D01*
G37*
G36*
G01X1413950Y185766D02*
X1417350D01*
G02Y182760I0J-1503D01*
G01X1413950D01*
G02Y185766I0J1503D01*
G37*
G36*
G01X1423110D02*
X1426510D01*
G02Y182760I0J-1503D01*
G01X1423110D01*
G02Y185766I0J1503D01*
G37*
G36*
G01X1401341Y178662D02*
X1404741D01*
G02Y175656I0J-1503D01*
G01X1401341D01*
G02Y178662I0J1503D01*
G37*
G36*
G01X1403778Y173186D02*
X1407178D01*
G02Y170182I0J-1502D01*
G01X1403778D01*
G02Y173186I0J1502D01*
G37*
G36*
G01X1389256Y199170D02*
X1392656D01*
G02Y196166I0J-1502D01*
G01X1389256D01*
G02Y199170I0J1502D01*
G37*
G36*
G01X550711Y1603882D02*
X554111D01*
G02Y1600878I0J-1502D01*
G01X550711D01*
G02Y1603882I0J1502D01*
G37*
G36*
G01X502471D02*
X505871D01*
G02Y1600878I0J-1502D01*
G01X502471D01*
G02Y1603882I0J1502D01*
G37*
G36*
G01X490411Y1615794D02*
X493811D01*
G02Y1612790I0J-1502D01*
G01X490411D01*
G02Y1615794I0J1502D01*
G37*
G36*
G01X987440Y432696D02*
X990840D01*
G02Y429690I0J-1503D01*
G01X987440D01*
G02Y432696I0J1503D01*
G37*
G36*
G01X1471460Y631900D02*
X1468060D01*
G02Y634904I0J1502D01*
G01X1471460D01*
G02Y631900I0J-1502D01*
G37*
G36*
G01X934047Y459364D02*
X937447D01*
G02Y456360I0J-1502D01*
G01X934047D01*
G02Y459364I0J1502D01*
G37*
G36*
G01X942047Y464514D02*
X945447D01*
G02Y461510I0J-1502D01*
G01X942047D01*
G02Y464514I0J1502D01*
G37*
G36*
G01X550711Y1615794D02*
X554111D01*
G02Y1612790I0J-1502D01*
G01X550711D01*
G02Y1615794I0J1502D01*
G37*
G36*
G01X635131Y1603882D02*
X638531D01*
G02Y1600878I0J-1502D01*
G01X635131D01*
G02Y1603882I0J1502D01*
G37*
G36*
G01X909584Y459638D02*
X912984D01*
G02Y456632I0J-1503D01*
G01X909584D01*
G02Y459638I0J1503D01*
G37*
G36*
G01X913394Y523164D02*
X916794D01*
G02Y520160I0J-1502D01*
G01X913394D01*
G02Y523164I0J1502D01*
G37*
G36*
G01X574831Y1603882D02*
X578231D01*
G02Y1600878I0J-1502D01*
G01X574831D01*
G02Y1603882I0J1502D01*
G37*
G36*
G01X659251D02*
X662651D01*
G02Y1600878I0J-1502D01*
G01X659251D01*
G02Y1603882I0J1502D01*
G37*
G36*
G01X1153370Y639694D02*
X1156770D01*
G02Y636690I0J-1502D01*
G01X1153370D01*
G02Y639694I0J1502D01*
G37*
G36*
G01X1406786Y199170D02*
X1410186D01*
G02Y196166I0J-1502D01*
G01X1406786D01*
G02Y199170I0J1502D01*
G37*
G36*
G01X611011Y1615794D02*
X614411D01*
G02Y1612790I0J-1502D01*
G01X611011D01*
G02Y1615794I0J1502D01*
G37*
G36*
G01X1312136Y283446D02*
X1308736D01*
G02Y286450I0J1502D01*
G01X1312136D01*
G02Y283446I0J-1502D01*
G37*
G36*
G01X611011Y1603882D02*
X614411D01*
G02Y1600878I0J-1502D01*
G01X611011D01*
G02Y1603882I0J1502D01*
G37*
G36*
G01X586891Y1615794D02*
X590291D01*
G02Y1612790I0J-1502D01*
G01X586891D01*
G02Y1615794I0J1502D01*
G37*
G36*
G01X659251D02*
X662651D01*
G02Y1612790I0J-1502D01*
G01X659251D01*
G02Y1615794I0J1502D01*
G37*
G36*
G01X574831D02*
X578231D01*
G02Y1612790I0J-1502D01*
G01X574831D01*
G02Y1615794I0J1502D01*
G37*
G36*
G01X1183360Y643564D02*
X1186760D01*
G02Y640560I0J-1502D01*
G01X1183360D01*
G02Y643564I0J1502D01*
G37*
G36*
G01X562771Y1615794D02*
X566171D01*
G02Y1612790I0J-1502D01*
G01X562771D01*
G02Y1615794I0J1502D01*
G37*
G36*
G01X901230Y533114D02*
X904630D01*
G02Y530110I0J-1502D01*
G01X901230D01*
G02Y533114I0J1502D01*
G37*
G36*
G01X954390Y529098D02*
X957790D01*
G02Y526094I0J-1502D01*
G01X954390D01*
G02Y529098I0J1502D01*
G37*
G36*
G01X963930Y534864D02*
X967330D01*
G02Y531860I0J-1502D01*
G01X963930D01*
G02Y534864I0J1502D01*
G37*
G36*
G01X548070Y80874D02*
X551470D01*
G02Y77870I0J-1502D01*
G01X548070D01*
G02Y80874I0J1502D01*
G37*
G36*
G01X623071Y1603882D02*
X626471D01*
G02Y1600878I0J-1502D01*
G01X623071D01*
G02Y1603882I0J1502D01*
G37*
G36*
G01X888130Y534114D02*
X891530D01*
G02Y531110I0J-1502D01*
G01X888130D01*
G02Y534114I0J1502D01*
G37*
G36*
G01X297437Y1591596D02*
X300837D01*
G02Y1588592I0J-1502D01*
G01X297437D01*
G02Y1591596I0J1502D01*
G37*
G36*
G01X237137D02*
X240537D01*
G02Y1588592I0J-1502D01*
G01X237137D01*
G02Y1591596I0J1502D01*
G37*
G36*
G01X1329274Y883423D02*
G02X1331868I1297J0D01*
G01Y883421D01*
G02X1331796Y882994I-1298J-1D01*
G01X1331766Y882908D01*
X1332572Y881511D01*
X1332662Y881494D01*
G02X1333718Y880219I-242J-1275D01*
G02X1331122I-1298J0D01*
G02X1331195Y880647I1299J-1D01*
G01X1331225Y880733D01*
X1330419Y882131D01*
X1330329Y882148D01*
G02X1329274Y883423I243J1275D01*
G37*
G36*
G01X937340Y309612D02*
X920138D01*
G02X937340I8601J12041D01*
G37*
G36*
G01X921047Y464514D02*
X924447D01*
G02Y461510I0J-1502D01*
G01X921047D01*
G02Y464514I0J1502D01*
G37*
G36*
G01X371587Y173422D02*
X365287D01*
G02Y197050I0J11814D01*
G01X371587D01*
G02Y173422I0J-11814D01*
G37*
G36*
G01X253477D02*
X247176D01*
G02X247175Y197050I0J11814D01*
G01X253476D01*
G02X253477Y173422I0J-11814D01*
G37*
G36*
G01X1012861Y434390D02*
X1016261D01*
G02Y431386I0J-1502D01*
G01X1012861D01*
G02Y434390I0J1502D01*
G37*
G36*
G01X50772Y120610D02*
X55372Y124913D01*
G02X66448Y113076I5538J-5919D01*
G01X61848Y108773D01*
G02X50772Y120610I-5538J5918D01*
G37*
G36*
G01X62587Y23395D02*
G02X58024Y17311I-2280J-3043D01*
G02X62587Y23395I2279J3044D01*
G37*
G36*
G01X443227Y845968D02*
G02X444266Y845448I0J-1298D01*
G01X445888D01*
G02X446927Y845968I1039J-778D01*
G02Y843374I0J-1297D01*
G02X445888Y843894I0J1298D01*
G01X444266D01*
G02X443227Y843374I-1039J778D01*
G02Y845968I0J1297D01*
G37*
G36*
G01X356830Y844971D02*
G02X359424I1297J0D01*
G02X358362Y843695I-1298J0D01*
G01X358267Y843677D01*
X357426Y842082D01*
X357465Y841994D01*
G02X357576Y841467I-1186J-525D01*
G02X354982I-1297J0D01*
G02X356044Y842743I1298J0D01*
G01X356139Y842761D01*
X356980Y844356D01*
X356941Y844444D01*
G02X356830Y844971I1186J525D01*
G37*
G36*
G01X364230D02*
G02X366824I1297J0D01*
G02X365762Y843695I-1298J0D01*
G01X365667Y843677D01*
X364826Y842082D01*
X364865Y841994D01*
G02X364976Y841467I-1186J-525D01*
G02X362382I-1297J0D01*
G02X363444Y842743I1298J0D01*
G01X363539Y842761D01*
X364380Y844356D01*
X364341Y844444D01*
G02X364230Y844971I1186J525D01*
G37*
G36*
G01X371630D02*
G02X374224I1297J0D01*
G02X373162Y843695I-1298J0D01*
G01X373067Y843677D01*
X372226Y842082D01*
X372265Y841994D01*
G02X372376Y841467I-1186J-525D01*
G02X369782I-1297J0D01*
G02X370844Y842743I1298J0D01*
G01X370939Y842761D01*
X371780Y844356D01*
X371741Y844444D01*
G02X371630Y844971I1186J525D01*
G37*
G36*
G01X379030D02*
G02X381624I1297J0D01*
G02X380562Y843695I-1298J0D01*
G01X380467Y843677D01*
X379626Y842082D01*
X379665Y841994D01*
G02X379776Y841467I-1186J-525D01*
G02X377182I-1297J0D01*
G02X378244Y842743I1298J0D01*
G01X378339Y842761D01*
X379180Y844356D01*
X379141Y844444D01*
G02X379030Y844971I1186J525D01*
G37*
G36*
G01X386430D02*
G02X389024I1297J0D01*
G02X387962Y843695I-1298J0D01*
G01X387867Y843677D01*
X387026Y842082D01*
X387065Y841994D01*
G02X387176Y841467I-1186J-525D01*
G02X384582I-1297J0D01*
G02X385644Y842743I1298J0D01*
G01X385739Y842761D01*
X386580Y844356D01*
X386541Y844444D01*
G02X386430Y844971I1186J525D01*
G37*
G36*
G01X393830D02*
G02X396424I1297J0D01*
G02X395362Y843695I-1298J0D01*
G01X395267Y843677D01*
X394426Y842082D01*
X394465Y841994D01*
G02X394576Y841467I-1186J-525D01*
G02X391982I-1297J0D01*
G02X393044Y842743I1298J0D01*
G01X393139Y842761D01*
X393980Y844356D01*
X393941Y844444D01*
G02X393830Y844971I1186J525D01*
G37*
G36*
G01X401230D02*
G02X403824I1297J0D01*
G02X402762Y843695I-1298J0D01*
G01X402667Y843677D01*
X401826Y842082D01*
X401865Y841994D01*
G02X401976Y841467I-1186J-525D01*
G02X399382I-1297J0D01*
G02X400444Y842743I1298J0D01*
G01X400539Y842761D01*
X401380Y844356D01*
X401341Y844444D01*
G02X401230Y844971I1186J525D01*
G37*
G36*
G01X408630D02*
G02X411224I1297J0D01*
G02X410162Y843695I-1298J0D01*
G01X410067Y843677D01*
X409226Y842082D01*
X409265Y841994D01*
G02X409376Y841467I-1186J-525D01*
G02X406782I-1297J0D01*
G02X407844Y842743I1298J0D01*
G01X407939Y842761D01*
X408780Y844356D01*
X408741Y844444D01*
G02X408630Y844971I1186J525D01*
G37*
G36*
G01X416030D02*
G02X418624I1297J0D01*
G02X417562Y843695I-1298J0D01*
G01X417467Y843677D01*
X416626Y842082D01*
X416665Y841994D01*
G02X416776Y841467I-1186J-525D01*
G02X414182I-1297J0D01*
G02X415244Y842743I1298J0D01*
G01X415339Y842761D01*
X416180Y844356D01*
X416141Y844444D01*
G02X416030Y844971I1186J525D01*
G37*
G36*
G01X423430D02*
G02X426024I1297J0D01*
G02X424962Y843695I-1298J0D01*
G01X424867Y843677D01*
X424026Y842082D01*
X424065Y841994D01*
G02X424176Y841467I-1186J-525D01*
G02X421582I-1297J0D01*
G02X422644Y842743I1298J0D01*
G01X422739Y842761D01*
X423580Y844356D01*
X423541Y844444D01*
G02X423430Y844971I1186J525D01*
G37*
G36*
G01X453030D02*
G02X455624I1297J0D01*
G02X454562Y843695I-1298J0D01*
G01X454467Y843677D01*
X453626Y842082D01*
X453665Y841994D01*
G02X453776Y841467I-1186J-525D01*
G02X451182I-1297J0D01*
G02X452244Y842743I1298J0D01*
G01X452339Y842761D01*
X453180Y844356D01*
X453141Y844444D01*
G02X453030Y844971I1186J525D01*
G37*
G36*
G01X460430D02*
G02X463024I1297J0D01*
G02X461962Y843695I-1298J0D01*
G01X461867Y843677D01*
X461026Y842082D01*
X461065Y841994D01*
G02X461176Y841467I-1186J-525D01*
G02X458582I-1297J0D01*
G02X459644Y842743I1298J0D01*
G01X459739Y842761D01*
X460580Y844356D01*
X460541Y844444D01*
G02X460430Y844971I1186J525D01*
G37*
G36*
G01X467830D02*
G02X470424I1297J0D01*
G02X469362Y843695I-1298J0D01*
G01X469267Y843677D01*
X468426Y842082D01*
X468465Y841994D01*
G02X468576Y841467I-1186J-525D01*
G02X465982I-1297J0D01*
G02X467044Y842743I1298J0D01*
G01X467139Y842761D01*
X467980Y844356D01*
X467941Y844444D01*
G02X467830Y844971I1186J525D01*
G37*
G36*
G01X475230D02*
G02X477824I1297J0D01*
G02X476762Y843695I-1298J0D01*
G01X476667Y843677D01*
X475826Y842082D01*
X475865Y841994D01*
G02X475976Y841467I-1186J-525D01*
G02X473382I-1297J0D01*
G02X474444Y842743I1298J0D01*
G01X474539Y842761D01*
X475380Y844356D01*
X475341Y844444D01*
G02X475230Y844971I1186J525D01*
G37*
G36*
G01X482630D02*
G02X485224I1297J0D01*
G02X484162Y843695I-1298J0D01*
G01X484067Y843677D01*
X483226Y842082D01*
X483265Y841994D01*
G02X483376Y841467I-1186J-525D01*
G02X480782I-1297J0D01*
G02X481844Y842743I1298J0D01*
G01X481939Y842761D01*
X482780Y844356D01*
X482741Y844444D01*
G02X482630Y844971I1186J525D01*
G37*
G36*
G01X490030D02*
G02X492624I1297J0D01*
G02X491519Y843688I-1297J0D01*
G01X491418Y843673D01*
X490608Y842112D01*
X490651Y842023D01*
G02X490776Y841467I-1174J-556D01*
G02X488180I-1298J0D01*
G02X489315Y842754I1297J0D01*
G01X489420Y842767D01*
X490213Y844297D01*
X490168Y844389D01*
G02X490030Y844971I1158J582D01*
G37*
G36*
G01X497430D02*
G02X500024I1297J0D01*
G02X498962Y843695I-1298J0D01*
G01X498867Y843677D01*
X498025Y842081D01*
X498064Y841993D01*
G02X498176Y841467I-1186J-527D01*
G02X495580I-1298J0D01*
G02X496644Y842743I1297J0D01*
G01X496739Y842761D01*
X497580Y844356D01*
X497541Y844444D01*
G02X497430Y844971I1186J525D01*
G37*
G36*
G01X504830D02*
G02X507424I1297J0D01*
G02X506362Y843695I-1298J0D01*
G01X506267Y843677D01*
X505426Y842082D01*
X505465Y841994D01*
G02X505576Y841467I-1186J-525D01*
G02X502982I-1297J0D01*
G02X504044Y842743I1298J0D01*
G01X504139Y842761D01*
X504980Y844356D01*
X504941Y844444D01*
G02X504830Y844971I1186J525D01*
G37*
G36*
G01X512230D02*
G02X514824I1297J0D01*
G02X513762Y843695I-1298J0D01*
G01X513667Y843677D01*
X512826Y842082D01*
X512865Y841994D01*
G02X512976Y841467I-1186J-525D01*
G02X510382I-1297J0D01*
G02X511444Y842743I1298J0D01*
G01X511539Y842761D01*
X512380Y844356D01*
X512341Y844444D01*
G02X512230Y844971I1186J525D01*
G37*
G36*
G01X519630D02*
G02X522224I1297J0D01*
G02X521162Y843695I-1298J0D01*
G01X521067Y843677D01*
X520226Y842082D01*
X520265Y841994D01*
G02X520376Y841467I-1186J-525D01*
G02X517782I-1297J0D01*
G02X518844Y842743I1298J0D01*
G01X518939Y842761D01*
X519780Y844356D01*
X519741Y844444D01*
G02X519630Y844971I1186J525D01*
G37*
G36*
G01X1332972D02*
G02X1335566I1297J0D01*
G02X1334504Y843695I-1298J0D01*
G01X1334409Y843677D01*
X1333568Y842082D01*
X1333607Y841994D01*
G02X1333718Y841467I-1186J-525D01*
G02X1331124I-1297J0D01*
G02X1332186Y842743I1298J0D01*
G01X1332281Y842761D01*
X1333122Y844356D01*
X1333083Y844444D01*
G02X1332972Y844971I1186J525D01*
G37*
G36*
G01X1340372D02*
G02X1342966I1297J0D01*
G02X1341904Y843695I-1298J0D01*
G01X1341809Y843677D01*
X1340968Y842082D01*
X1341007Y841994D01*
G02X1341118Y841467I-1186J-525D01*
G02X1338524I-1297J0D01*
G02X1339586Y842743I1298J0D01*
G01X1339681Y842761D01*
X1340522Y844356D01*
X1340483Y844444D01*
G02X1340372Y844971I1186J525D01*
G37*
G36*
G01X1347772D02*
G02X1350366I1297J0D01*
G02X1349304Y843695I-1298J0D01*
G01X1349209Y843677D01*
X1348368Y842082D01*
X1348407Y841994D01*
G02X1348518Y841467I-1186J-525D01*
G02X1345924I-1297J0D01*
G02X1346986Y842743I1298J0D01*
G01X1347081Y842761D01*
X1347922Y844356D01*
X1347883Y844444D01*
G02X1347772Y844971I1186J525D01*
G37*
G36*
G01X1355172D02*
G02X1357766I1297J0D01*
G02X1356704Y843695I-1298J0D01*
G01X1356609Y843677D01*
X1355768Y842082D01*
X1355807Y841994D01*
G02X1355918Y841467I-1186J-525D01*
G02X1353324I-1297J0D01*
G02X1354386Y842743I1298J0D01*
G01X1354481Y842761D01*
X1355322Y844356D01*
X1355283Y844444D01*
G02X1355172Y844971I1186J525D01*
G37*
G36*
G01X1362572D02*
G02X1365166I1297J0D01*
G02X1364104Y843695I-1298J0D01*
G01X1364009Y843677D01*
X1363168Y842082D01*
X1363207Y841994D01*
G02X1363318Y841467I-1186J-525D01*
G02X1360724I-1297J0D01*
G02X1361786Y842743I1298J0D01*
G01X1361881Y842761D01*
X1362722Y844356D01*
X1362683Y844444D01*
G02X1362572Y844971I1186J525D01*
G37*
G36*
G01X1369972D02*
G02X1372566I1297J0D01*
G02X1371504Y843695I-1298J0D01*
G01X1371409Y843677D01*
X1370568Y842082D01*
X1370607Y841994D01*
G02X1370718Y841467I-1186J-525D01*
G02X1368124I-1297J0D01*
G02X1369186Y842743I1298J0D01*
G01X1369281Y842761D01*
X1370122Y844356D01*
X1370083Y844444D01*
G02X1369972Y844971I1186J525D01*
G37*
G36*
G01X1377372D02*
G02X1379966I1297J0D01*
G02X1378904Y843695I-1298J0D01*
G01X1378809Y843677D01*
X1377968Y842082D01*
X1378007Y841994D01*
G02X1378118Y841467I-1186J-525D01*
G02X1375524I-1297J0D01*
G02X1376586Y842743I1298J0D01*
G01X1376681Y842761D01*
X1377522Y844356D01*
X1377483Y844444D01*
G02X1377372Y844971I1186J525D01*
G37*
G36*
G01X1384772D02*
G02X1387366I1297J0D01*
G02X1386304Y843695I-1298J0D01*
G01X1386209Y843677D01*
X1385368Y842082D01*
X1385407Y841994D01*
G02X1385518Y841467I-1186J-525D01*
G02X1382924I-1297J0D01*
G02X1383986Y842743I1298J0D01*
G01X1384081Y842761D01*
X1384922Y844356D01*
X1384883Y844444D01*
G02X1384772Y844971I1186J525D01*
G37*
G36*
G01X1392172D02*
G02X1394766I1297J0D01*
G02X1393704Y843695I-1298J0D01*
G01X1393609Y843677D01*
X1392768Y842082D01*
X1392807Y841994D01*
G02X1392918Y841467I-1186J-525D01*
G02X1390324I-1297J0D01*
G02X1391386Y842743I1298J0D01*
G01X1391481Y842761D01*
X1392322Y844356D01*
X1392283Y844444D01*
G02X1392172Y844971I1186J525D01*
G37*
G36*
G01X1399572D02*
G02X1402166I1297J0D01*
G02X1401104Y843695I-1298J0D01*
G01X1401009Y843677D01*
X1400168Y842082D01*
X1400207Y841994D01*
G02X1400318Y841467I-1186J-525D01*
G02X1397724I-1297J0D01*
G02X1398786Y842743I1298J0D01*
G01X1398881Y842761D01*
X1399722Y844356D01*
X1399683Y844444D01*
G02X1399572Y844971I1186J525D01*
G37*
G36*
G01X351280Y848176D02*
G02X353876I1298J0D01*
G02X353803Y847747I-1297J0D01*
G01X353772Y847661D01*
X354579Y846263D01*
X354669Y846246D01*
G02X355724Y844971I-243J-1275D01*
G02X353130I-1297J0D01*
G02X353202Y845400I1297J3D01*
G01X353233Y845486D01*
X352426Y846884D01*
X352336Y846901D01*
G02X351280Y848176I242J1275D01*
G37*
G36*
G01X358680D02*
G02X361276I1298J0D01*
G02X361203Y847747I-1297J0D01*
G01X361172Y847661D01*
X361979Y846263D01*
X362069Y846246D01*
G02X363124Y844971I-243J-1275D01*
G02X360530I-1297J0D01*
G02X360602Y845400I1297J3D01*
G01X360633Y845486D01*
X359826Y846884D01*
X359736Y846901D01*
G02X358680Y848176I242J1275D01*
G37*
G36*
G01X366080D02*
G02X368676I1298J0D01*
G02X368603Y847747I-1297J0D01*
G01X368572Y847661D01*
X369379Y846263D01*
X369469Y846246D01*
G02X370524Y844971I-243J-1275D01*
G02X367930I-1297J0D01*
G02X368002Y845400I1297J3D01*
G01X368033Y845486D01*
X367226Y846884D01*
X367136Y846901D01*
G02X366080Y848176I242J1275D01*
G37*
G36*
G01X373480D02*
G02X376076I1298J0D01*
G02X376003Y847747I-1297J0D01*
G01X375972Y847661D01*
X376779Y846263D01*
X376869Y846246D01*
G02X377924Y844971I-243J-1275D01*
G02X375330I-1297J0D01*
G02X375402Y845400I1297J3D01*
G01X375433Y845486D01*
X374626Y846884D01*
X374536Y846901D01*
G02X373480Y848176I242J1275D01*
G37*
G36*
G01X380880D02*
G02X383476I1298J0D01*
G02X383403Y847747I-1297J0D01*
G01X383372Y847661D01*
X384179Y846263D01*
X384269Y846246D01*
G02X385324Y844971I-243J-1275D01*
G02X382730I-1297J0D01*
G02X382802Y845400I1297J3D01*
G01X382833Y845486D01*
X382026Y846884D01*
X381936Y846901D01*
G02X380880Y848176I242J1275D01*
G37*
G36*
G01X388280D02*
G02X390876I1298J0D01*
G02X390803Y847747I-1297J0D01*
G01X390772Y847661D01*
X391579Y846263D01*
X391669Y846246D01*
G02X392724Y844971I-243J-1275D01*
G02X390130I-1297J0D01*
G02X390202Y845400I1297J3D01*
G01X390233Y845486D01*
X389426Y846884D01*
X389336Y846901D01*
G02X388280Y848176I242J1275D01*
G37*
G36*
G01X395680D02*
G02X398276I1298J0D01*
G02X398203Y847747I-1297J0D01*
G01X398172Y847661D01*
X398979Y846263D01*
X399069Y846246D01*
G02X400124Y844971I-243J-1275D01*
G02X397530I-1297J0D01*
G02X397602Y845400I1297J3D01*
G01X397633Y845486D01*
X396826Y846884D01*
X396736Y846901D01*
G02X395680Y848176I242J1275D01*
G37*
G36*
G01X403080D02*
G02X405676I1298J0D01*
G02X405603Y847747I-1297J0D01*
G01X405572Y847661D01*
X406379Y846263D01*
X406469Y846246D01*
G02X407524Y844971I-243J-1275D01*
G02X404930I-1297J0D01*
G02X405002Y845400I1297J3D01*
G01X405033Y845486D01*
X404226Y846884D01*
X404136Y846901D01*
G02X403080Y848176I242J1275D01*
G37*
G36*
G01X410480D02*
G02X413076I1298J0D01*
G02X413003Y847747I-1297J0D01*
G01X412972Y847661D01*
X413779Y846263D01*
X413869Y846246D01*
G02X414924Y844971I-243J-1275D01*
G02X412330I-1297J0D01*
G02X412402Y845400I1297J3D01*
G01X412433Y845486D01*
X411626Y846884D01*
X411536Y846901D01*
G02X410480Y848176I242J1275D01*
G37*
G36*
G01X417880D02*
G02X420476I1298J0D01*
G02X420403Y847747I-1297J0D01*
G01X420372Y847661D01*
X421179Y846263D01*
X421269Y846246D01*
G02X422324Y844971I-243J-1275D01*
G02X419730I-1297J0D01*
G02X419802Y845400I1297J3D01*
G01X419833Y845486D01*
X419026Y846884D01*
X418936Y846901D01*
G02X417880Y848176I242J1275D01*
G37*
G36*
G01X425280D02*
G02X427876I1298J0D01*
G02X427803Y847747I-1297J0D01*
G01X427772Y847661D01*
X428579Y846263D01*
X428669Y846246D01*
G02X429724Y844971I-243J-1275D01*
G02X427130I-1297J0D01*
G02X427202Y845400I1297J3D01*
G01X427233Y845486D01*
X426426Y846884D01*
X426336Y846901D01*
G02X425280Y848176I242J1275D01*
G37*
G36*
G01X430278Y849474D02*
G02X431317Y848954I0J-1298D01*
G01X432939D01*
G02X433978Y849474I1039J-778D01*
G02Y846878I0J-1298D01*
G02X432939Y847398I0J1298D01*
G01X431317D01*
G02X430278Y846878I-1039J778D01*
G02Y849474I0J1298D01*
G37*
G36*
G01X436380Y848176D02*
G02X438976I1298J0D01*
G02X437913Y846900I-1297J0D01*
G01X437818Y846882D01*
X436976Y845286D01*
X437015Y845197D01*
G02X437126Y844673I-1186J-525D01*
G01Y844671D01*
G02X434532I-1297J0D01*
G02X435594Y845947I1298J0D01*
G01X435689Y845965D01*
X436531Y847561D01*
X436492Y847650D01*
G02X436380Y848176I1186J527D01*
G37*
G36*
G01X447480D02*
G02X450076I1298J0D01*
G02X450003Y847748I-1298J1D01*
G01X449972Y847661D01*
X450780Y846263D01*
X450870Y846246D01*
G02X451926Y844971I-242J-1275D01*
G02X449330I-1298J0D01*
G02X449403Y845399I1298J-1D01*
G01X449434Y845486D01*
X448626Y846884D01*
X448536Y846901D01*
G02X447480Y848176I242J1275D01*
G37*
G36*
G01X454880D02*
G02X457476I1298J0D01*
G02X457403Y847747I-1297J0D01*
G01X457372Y847661D01*
X458179Y846263D01*
X458269Y846246D01*
G02X459324Y844971I-243J-1275D01*
G02X456730I-1297J0D01*
G02X456802Y845400I1297J3D01*
G01X456833Y845486D01*
X456026Y846884D01*
X455936Y846901D01*
G02X454880Y848176I242J1275D01*
G37*
G36*
G01X462280D02*
G02X464876I1298J0D01*
G02X464803Y847747I-1297J0D01*
G01X464772Y847661D01*
X465579Y846263D01*
X465669Y846246D01*
G02X466724Y844971I-243J-1275D01*
G02X464130I-1297J0D01*
G02X464202Y845400I1297J3D01*
G01X464233Y845486D01*
X463426Y846884D01*
X463336Y846901D01*
G02X462280Y848176I242J1275D01*
G37*
G36*
G01X469680D02*
G02X472276I1298J0D01*
G02X472203Y847747I-1297J0D01*
G01X472172Y847661D01*
X472979Y846263D01*
X473069Y846246D01*
G02X474124Y844971I-243J-1275D01*
G02X471530I-1297J0D01*
G02X471602Y845400I1297J3D01*
G01X471633Y845486D01*
X470826Y846884D01*
X470736Y846901D01*
G02X469680Y848176I242J1275D01*
G37*
G36*
G01X477080D02*
G02X479676I1298J0D01*
G02X479603Y847747I-1297J0D01*
G01X479572Y847661D01*
X480379Y846263D01*
X480469Y846246D01*
G02X481524Y844971I-243J-1275D01*
G02X478930I-1297J0D01*
G02X479002Y845400I1297J3D01*
G01X479033Y845486D01*
X478226Y846884D01*
X478136Y846901D01*
G02X477080Y848176I242J1275D01*
G37*
G36*
G01X484480D02*
G02X487076I1298J0D01*
G02X487003Y847747I-1297J0D01*
G01X486972Y847661D01*
X487779Y846263D01*
X487869Y846246D01*
G02X488924Y844971I-243J-1275D01*
G02X486330I-1297J0D01*
G02X486402Y845400I1297J3D01*
G01X486433Y845486D01*
X485626Y846884D01*
X485536Y846901D01*
G02X484480Y848176I242J1275D01*
G37*
G36*
G01X491880D02*
G02X494476I1298J0D01*
G02X494403Y847747I-1297J0D01*
G01X494372Y847661D01*
X495179Y846263D01*
X495269Y846246D01*
G02X496324Y844971I-243J-1275D01*
G02X493730I-1297J0D01*
G02X493802Y845400I1297J3D01*
G01X493833Y845486D01*
X493026Y846884D01*
X492936Y846901D01*
G02X491880Y848176I242J1275D01*
G37*
G36*
G01X499280D02*
G02X501876I1298J0D01*
G02X501803Y847747I-1297J0D01*
G01X501772Y847661D01*
X502579Y846263D01*
X502669Y846246D01*
G02X503724Y844971I-243J-1275D01*
G02X501130I-1297J0D01*
G02X501202Y845400I1297J3D01*
G01X501233Y845486D01*
X500426Y846884D01*
X500336Y846901D01*
G02X499280Y848176I242J1275D01*
G37*
G36*
G01X506680D02*
G02X509276I1298J0D01*
G02X509203Y847747I-1297J0D01*
G01X509172Y847661D01*
X509979Y846263D01*
X510069Y846246D01*
G02X511124Y844971I-243J-1275D01*
G02X508530I-1297J0D01*
G02X508602Y845400I1297J3D01*
G01X508633Y845486D01*
X507826Y846884D01*
X507736Y846901D01*
G02X506680Y848176I242J1275D01*
G37*
G36*
G01X514080D02*
G02X516676I1298J0D01*
G02X516603Y847747I-1297J0D01*
G01X516572Y847661D01*
X517379Y846263D01*
X517469Y846246D01*
G02X518524Y844971I-243J-1275D01*
G02X515930I-1297J0D01*
G02X516002Y845400I1297J3D01*
G01X516033Y845486D01*
X515226Y846884D01*
X515136Y846901D01*
G02X514080Y848176I242J1275D01*
G37*
G36*
G01X521480D02*
G02X524076I1298J0D01*
G02X524003Y847747I-1297J0D01*
G01X523972Y847661D01*
X524779Y846263D01*
X524869Y846246D01*
G02X525924Y844971I-243J-1275D01*
G02X523330I-1297J0D01*
G02X523402Y845400I1297J3D01*
G01X523433Y845486D01*
X522626Y846884D01*
X522536Y846901D01*
G02X521480Y848176I242J1275D01*
G37*
G36*
G01X526478Y849474D02*
G02X527517Y848954I0J-1298D01*
G01X529139D01*
G02X530178Y849474I1039J-778D01*
G02Y846878I0J-1298D01*
G02X529139Y847398I0J1298D01*
G01X527517D01*
G02X526478Y846878I-1039J778D01*
G02Y849474I0J1298D01*
G37*
G36*
G01X532580Y848176D02*
G02X535176I1298J0D01*
G02X534168Y846911I-1298J0D01*
G01X534079Y846891D01*
X533202Y845231D01*
X533236Y845145D01*
G02X533326Y844671I-1208J-475D01*
G02X530730I-1298J0D01*
G02X531738Y845936I1298J0D01*
G01X531827Y845956D01*
X532704Y847616D01*
X532670Y847702D01*
G02X532580Y848176I1208J475D01*
G37*
G36*
G01X1327422D02*
G02X1330018I1298J0D01*
G02X1329945Y847747I-1297J0D01*
G01X1329914Y847661D01*
X1330721Y846263D01*
X1330811Y846246D01*
G02X1331866Y844971I-243J-1275D01*
G02X1329272I-1297J0D01*
G02X1329344Y845400I1297J3D01*
G01X1329375Y845486D01*
X1328568Y846884D01*
X1328478Y846901D01*
G02X1327422Y848176I242J1275D01*
G37*
G36*
G01X1334822D02*
G02X1337418I1298J0D01*
G02X1337345Y847747I-1297J0D01*
G01X1337314Y847661D01*
X1338121Y846263D01*
X1338211Y846246D01*
G02X1339266Y844971I-243J-1275D01*
G02X1336672I-1297J0D01*
G02X1336744Y845400I1297J3D01*
G01X1336775Y845486D01*
X1335968Y846884D01*
X1335878Y846901D01*
G02X1334822Y848176I242J1275D01*
G37*
G36*
G01X1342222D02*
G02X1344818I1298J0D01*
G02X1344745Y847747I-1297J0D01*
G01X1344714Y847661D01*
X1345521Y846263D01*
X1345611Y846246D01*
G02X1346666Y844971I-243J-1275D01*
G02X1344072I-1297J0D01*
G02X1344144Y845400I1297J3D01*
G01X1344175Y845486D01*
X1343368Y846884D01*
X1343278Y846901D01*
G02X1342222Y848176I242J1275D01*
G37*
G36*
G01X1349622D02*
G02X1352218I1298J0D01*
G02X1352145Y847747I-1297J0D01*
G01X1352114Y847661D01*
X1352921Y846263D01*
X1353011Y846246D01*
G02X1354066Y844971I-243J-1275D01*
G02X1351472I-1297J0D01*
G02X1351544Y845400I1297J3D01*
G01X1351575Y845486D01*
X1350768Y846884D01*
X1350678Y846901D01*
G02X1349622Y848176I242J1275D01*
G37*
G36*
G01X1357022D02*
G02X1359618I1298J0D01*
G02X1359545Y847747I-1297J0D01*
G01X1359514Y847661D01*
X1360321Y846263D01*
X1360411Y846246D01*
G02X1361466Y844971I-243J-1275D01*
G02X1358872I-1297J0D01*
G02X1358944Y845400I1297J3D01*
G01X1358975Y845486D01*
X1358168Y846884D01*
X1358078Y846901D01*
G02X1357022Y848176I242J1275D01*
G37*
G36*
G01X1364422D02*
G02X1367018I1298J0D01*
G02X1366945Y847747I-1297J0D01*
G01X1366914Y847661D01*
X1367721Y846263D01*
X1367811Y846246D01*
G02X1368866Y844971I-243J-1275D01*
G02X1366272I-1297J0D01*
G02X1366344Y845400I1297J3D01*
G01X1366375Y845486D01*
X1365568Y846884D01*
X1365478Y846901D01*
G02X1364422Y848176I242J1275D01*
G37*
G36*
G01X1371822D02*
G02X1374418I1298J0D01*
G02X1374345Y847747I-1297J0D01*
G01X1374314Y847661D01*
X1375121Y846263D01*
X1375211Y846246D01*
G02X1376266Y844971I-243J-1275D01*
G02X1373672I-1297J0D01*
G02X1373744Y845400I1297J3D01*
G01X1373775Y845486D01*
X1372968Y846884D01*
X1372878Y846901D01*
G02X1371822Y848176I242J1275D01*
G37*
G36*
G01X1379222D02*
G02X1381818I1298J0D01*
G02X1381745Y847747I-1297J0D01*
G01X1381714Y847661D01*
X1382521Y846263D01*
X1382611Y846246D01*
G02X1383666Y844971I-243J-1275D01*
G02X1381072I-1297J0D01*
G02X1381144Y845400I1297J3D01*
G01X1381175Y845486D01*
X1380368Y846884D01*
X1380278Y846901D01*
G02X1379222Y848176I242J1275D01*
G37*
G36*
G01X1386622D02*
G02X1389218I1298J0D01*
G02X1389145Y847747I-1297J0D01*
G01X1389114Y847661D01*
X1389921Y846263D01*
X1390011Y846246D01*
G02X1391066Y844971I-243J-1275D01*
G02X1388472I-1297J0D01*
G02X1388544Y845400I1297J3D01*
G01X1388575Y845486D01*
X1387768Y846884D01*
X1387678Y846901D01*
G02X1386622Y848176I242J1275D01*
G37*
G36*
G01X1394022D02*
G02X1396618I1298J0D01*
G02X1396545Y847747I-1297J0D01*
G01X1396514Y847661D01*
X1397321Y846263D01*
X1397411Y846246D01*
G02X1398466Y844971I-243J-1275D01*
G02X1395872I-1297J0D01*
G02X1395944Y845400I1297J3D01*
G01X1395975Y845486D01*
X1395168Y846884D01*
X1395078Y846901D01*
G02X1394022Y848176I242J1275D01*
G37*
G36*
G01X1401422D02*
G02X1404018I1298J0D01*
G02X1403945Y847747I-1297J0D01*
G01X1403914Y847661D01*
X1404721Y846263D01*
X1404811Y846246D01*
G02X1405866Y844971I-243J-1275D01*
G02X1403272I-1297J0D01*
G02X1403344Y845400I1297J3D01*
G01X1403375Y845486D01*
X1402568Y846884D01*
X1402478Y846901D01*
G02X1401422Y848176I242J1275D01*
G37*
G36*
G01X1406420Y849474D02*
G02X1407459Y848954I0J-1298D01*
G01X1409081D01*
G02X1410120Y849474I1039J-778D01*
G02Y846878I0J-1298D01*
G02X1409081Y847398I0J1298D01*
G01X1407459D01*
G02X1406420Y846878I-1039J778D01*
G02Y849474I0J1298D01*
G37*
G36*
G01X1412522Y848176D02*
G02X1415118I1298J0D01*
G02X1414062Y846901I-1298J0D01*
G01X1413972Y846884D01*
X1413164Y845485D01*
X1413194Y845398D01*
G02X1413266Y844973I-1225J-426D01*
G01Y844971D01*
G02X1410672I-1297J0D01*
G02X1411728Y846246I1298J0D01*
G01X1411818Y846263D01*
X1412625Y847662D01*
X1412595Y847748D01*
G02X1412522Y848176I1225J429D01*
G37*
G36*
G01X349430Y851380D02*
G02X352024I1297J0D01*
G02X350969Y850105I-1298J0D01*
G01X350879Y850088D01*
X350072Y848691D01*
X350103Y848604D01*
G02X350176Y848176I-1225J-429D01*
G02X347580I-1298J0D01*
G02X348636Y849451I1298J0D01*
G01X348726Y849468D01*
X349533Y850865D01*
X349502Y850952D01*
G02X349430Y851380I1225J426D01*
G37*
G36*
G01X1325572D02*
G02X1328166I1297J0D01*
G02X1327111Y850105I-1298J0D01*
G01X1327021Y850088D01*
X1326214Y848691D01*
X1326245Y848604D01*
G02X1326318Y848176I-1225J-429D01*
G02X1323722I-1298J0D01*
G02X1324778Y849451I1298J0D01*
G01X1324868Y849468D01*
X1325675Y850865D01*
X1325644Y850952D01*
G02X1325572Y851380I1225J426D01*
G37*
G36*
G01X353132Y857789D02*
G02X355726I1297J0D01*
G02X355654Y857360I-1297J-3D01*
G01X355623Y857274D01*
X356430Y855876D01*
X356520Y855859D01*
G02X357576Y854584I-242J-1275D01*
G02X354980I-1298J0D01*
G02X355053Y855013I1297J0D01*
G01X355084Y855099D01*
X354277Y856497D01*
X354187Y856514D01*
G02X353132Y857789I243J1275D01*
G37*
G36*
G01X360532D02*
G02X363126I1297J0D01*
G02X363054Y857360I-1297J-3D01*
G01X363023Y857274D01*
X363830Y855876D01*
X363920Y855859D01*
G02X364976Y854584I-242J-1275D01*
G02X362380I-1298J0D01*
G02X362453Y855013I1297J0D01*
G01X362484Y855099D01*
X361677Y856497D01*
X361587Y856514D01*
G02X360532Y857789I243J1275D01*
G37*
G36*
G01X367932D02*
G02X370526I1297J0D01*
G02X370454Y857360I-1297J-3D01*
G01X370423Y857274D01*
X371230Y855876D01*
X371320Y855859D01*
G02X372376Y854584I-242J-1275D01*
G02X369780I-1298J0D01*
G02X369853Y855013I1297J0D01*
G01X369884Y855099D01*
X369077Y856497D01*
X368987Y856514D01*
G02X367932Y857789I243J1275D01*
G37*
G36*
G01X375332D02*
G02X377926I1297J0D01*
G02X377854Y857360I-1297J-3D01*
G01X377823Y857274D01*
X378630Y855876D01*
X378720Y855859D01*
G02X379776Y854584I-242J-1275D01*
G02X377180I-1298J0D01*
G02X377253Y855013I1297J0D01*
G01X377284Y855099D01*
X376477Y856497D01*
X376387Y856514D01*
G02X375332Y857789I243J1275D01*
G37*
G36*
G01X382732D02*
G02X385326I1297J0D01*
G02X385254Y857360I-1297J-3D01*
G01X385223Y857274D01*
X386030Y855876D01*
X386120Y855859D01*
G02X387176Y854584I-242J-1275D01*
G02X384580I-1298J0D01*
G02X384653Y855013I1297J0D01*
G01X384684Y855099D01*
X383877Y856497D01*
X383787Y856514D01*
G02X382732Y857789I243J1275D01*
G37*
G36*
G01X390132D02*
G02X392726I1297J0D01*
G02X392654Y857360I-1297J-3D01*
G01X392623Y857274D01*
X393430Y855876D01*
X393520Y855859D01*
G02X394576Y854584I-242J-1275D01*
G02X391980I-1298J0D01*
G02X392053Y855013I1297J0D01*
G01X392084Y855099D01*
X391277Y856497D01*
X391187Y856514D01*
G02X390132Y857789I243J1275D01*
G37*
G36*
G01X397532D02*
G02X400126I1297J0D01*
G02X400054Y857360I-1297J-3D01*
G01X400023Y857274D01*
X400830Y855876D01*
X400920Y855859D01*
G02X401976Y854584I-242J-1275D01*
G02X399380I-1298J0D01*
G02X399453Y855013I1297J0D01*
G01X399484Y855099D01*
X398677Y856497D01*
X398587Y856514D01*
G02X397532Y857789I243J1275D01*
G37*
G36*
G01X404932D02*
G02X407526I1297J0D01*
G02X407454Y857360I-1297J-3D01*
G01X407423Y857274D01*
X408230Y855876D01*
X408320Y855859D01*
G02X409376Y854584I-242J-1275D01*
G02X406780I-1298J0D01*
G02X406853Y855013I1297J0D01*
G01X406884Y855099D01*
X406077Y856497D01*
X405987Y856514D01*
G02X404932Y857789I243J1275D01*
G37*
G36*
G01X412332D02*
G02X414926I1297J0D01*
G02X414854Y857360I-1297J-3D01*
G01X414823Y857274D01*
X415630Y855876D01*
X415720Y855859D01*
G02X416776Y854584I-242J-1275D01*
G02X414180I-1298J0D01*
G02X414253Y855013I1297J0D01*
G01X414284Y855099D01*
X413477Y856497D01*
X413387Y856514D01*
G02X412332Y857789I243J1275D01*
G37*
G36*
G01X419732D02*
G02X422326I1297J0D01*
G02X422254Y857360I-1297J-3D01*
G01X422223Y857274D01*
X423030Y855876D01*
X423120Y855859D01*
G02X424176Y854584I-242J-1275D01*
G02X421580I-1298J0D01*
G02X421653Y855013I1297J0D01*
G01X421684Y855099D01*
X420877Y856497D01*
X420787Y856514D01*
G02X419732Y857789I243J1275D01*
G37*
G36*
G01X427132D02*
G02X429726I1297J0D01*
G02X429654Y857360I-1297J-3D01*
G01X429623Y857274D01*
X430430Y855876D01*
X430520Y855859D01*
G02X431576Y854584I-242J-1275D01*
G02X428980I-1298J0D01*
G02X429053Y855013I1297J0D01*
G01X429084Y855099D01*
X428277Y856497D01*
X428187Y856514D01*
G02X427132Y857789I243J1275D01*
G37*
G36*
G01X434532D02*
G02X437126I1297J0D01*
G02X437054Y857360I-1297J-3D01*
G01X437023Y857274D01*
X437830Y855876D01*
X437920Y855859D01*
G02X438976Y854584I-242J-1275D01*
G02X436382I-1297J0D01*
G02X436454Y855012I1297J2D01*
G01X436484Y855098D01*
X435677Y856497D01*
X435587Y856514D01*
G02X434532Y857789I243J1275D01*
G37*
G36*
G01X445632D02*
G02X448226I1297J0D01*
G02X447171Y856514I-1298J0D01*
G01X447081Y856497D01*
X446273Y855098D01*
X446303Y855011D01*
G02X446376Y854584I-1225J-429D01*
G02X443780I-1298J0D01*
G02X444838Y855859I1297J0D01*
G01X444928Y855876D01*
X445735Y857274D01*
X445704Y857361D01*
G02X445632Y857789I1225J426D01*
G37*
G36*
G01X453032D02*
G02X455626I1297J0D01*
G02X454571Y856514I-1298J0D01*
G01X454481Y856497D01*
X453673Y855098D01*
X453703Y855011D01*
G02X453776Y854584I-1225J-429D01*
G02X451180I-1298J0D01*
G02X452238Y855859I1297J0D01*
G01X452328Y855876D01*
X453135Y857274D01*
X453104Y857361D01*
G02X453032Y857789I1225J426D01*
G37*
G36*
G01X460432D02*
G02X463026I1297J0D01*
G02X461971Y856514I-1298J0D01*
G01X461881Y856497D01*
X461073Y855098D01*
X461103Y855011D01*
G02X461176Y854584I-1225J-429D01*
G02X458580I-1298J0D01*
G02X459638Y855859I1297J0D01*
G01X459728Y855876D01*
X460535Y857274D01*
X460504Y857361D01*
G02X460432Y857789I1225J426D01*
G37*
G36*
G01X467832D02*
G02X470426I1297J0D01*
G02X469371Y856514I-1298J0D01*
G01X469281Y856497D01*
X468473Y855098D01*
X468503Y855011D01*
G02X468576Y854584I-1225J-429D01*
G02X465980I-1298J0D01*
G02X467038Y855859I1297J0D01*
G01X467128Y855876D01*
X467935Y857274D01*
X467904Y857361D01*
G02X467832Y857789I1225J426D01*
G37*
G36*
G01X475232D02*
G02X477826I1297J0D01*
G02X476771Y856514I-1298J0D01*
G01X476681Y856497D01*
X475873Y855098D01*
X475903Y855011D01*
G02X475976Y854584I-1225J-429D01*
G02X473380I-1298J0D01*
G02X474438Y855859I1297J0D01*
G01X474528Y855876D01*
X475335Y857274D01*
X475304Y857361D01*
G02X475232Y857789I1225J426D01*
G37*
G36*
G01X482632D02*
G02X485226I1297J0D01*
G02X484171Y856514I-1298J0D01*
G01X484081Y856497D01*
X483273Y855098D01*
X483303Y855011D01*
G02X483376Y854584I-1225J-429D01*
G02X480780I-1298J0D01*
G02X481838Y855859I1297J0D01*
G01X481928Y855876D01*
X482735Y857274D01*
X482704Y857361D01*
G02X482632Y857789I1225J426D01*
G37*
G36*
G01X490032D02*
G02X492626I1297J0D01*
G02X491571Y856514I-1298J0D01*
G01X491481Y856497D01*
X490673Y855098D01*
X490703Y855011D01*
G02X490776Y854584I-1225J-429D01*
G02X488180I-1298J0D01*
G02X489238Y855859I1297J0D01*
G01X489328Y855876D01*
X490135Y857274D01*
X490104Y857361D01*
G02X490032Y857789I1225J426D01*
G37*
G36*
G01X497432D02*
G02X500026I1297J0D01*
G02X498971Y856514I-1298J0D01*
G01X498881Y856497D01*
X498073Y855098D01*
X498103Y855011D01*
G02X498176Y854584I-1225J-429D01*
G02X495580I-1298J0D01*
G02X496638Y855859I1297J0D01*
G01X496728Y855876D01*
X497535Y857274D01*
X497504Y857361D01*
G02X497432Y857789I1225J426D01*
G37*
G36*
G01X504832D02*
G02X507426I1297J0D01*
G02X506371Y856514I-1298J0D01*
G01X506281Y856497D01*
X505473Y855098D01*
X505503Y855011D01*
G02X505576Y854584I-1225J-429D01*
G02X502980I-1298J0D01*
G02X504038Y855859I1297J0D01*
G01X504128Y855876D01*
X504935Y857274D01*
X504904Y857361D01*
G02X504832Y857789I1225J426D01*
G37*
G36*
G01X512232D02*
G02X514826I1297J0D01*
G02X513771Y856514I-1298J0D01*
G01X513681Y856497D01*
X512873Y855098D01*
X512903Y855011D01*
G02X512976Y854584I-1225J-429D01*
G02X510380I-1298J0D01*
G02X511438Y855859I1297J0D01*
G01X511528Y855876D01*
X512335Y857274D01*
X512304Y857361D01*
G02X512232Y857789I1225J426D01*
G37*
G36*
G01X519632D02*
G02X522226I1297J0D01*
G02X521171Y856514I-1298J0D01*
G01X521081Y856497D01*
X520273Y855098D01*
X520303Y855011D01*
G02X520376Y854584I-1225J-429D01*
G02X517780I-1298J0D01*
G02X518838Y855859I1297J0D01*
G01X518928Y855876D01*
X519735Y857274D01*
X519704Y857361D01*
G02X519632Y857789I1225J426D01*
G37*
G36*
G01X527032D02*
G02X529626I1297J0D01*
G02X528571Y856514I-1298J0D01*
G01X528481Y856497D01*
X527673Y855098D01*
X527703Y855011D01*
G02X527776Y854584I-1225J-429D01*
G02X525180I-1298J0D01*
G02X526238Y855859I1297J0D01*
G01X526328Y855876D01*
X527135Y857274D01*
X527104Y857361D01*
G02X527032Y857789I1225J426D01*
G37*
G36*
G01X1329274D02*
G02X1331868I1297J0D01*
G02X1331796Y857360I-1297J-3D01*
G01X1331765Y857274D01*
X1332572Y855876D01*
X1332662Y855859D01*
G02X1333718Y854584I-242J-1275D01*
G02X1331122I-1298J0D01*
G02X1331195Y855013I1297J0D01*
G01X1331226Y855099D01*
X1330419Y856497D01*
X1330329Y856514D01*
G02X1329274Y857789I243J1275D01*
G37*
G36*
G01X1336674D02*
G02X1339268I1297J0D01*
G02X1339196Y857360I-1297J-3D01*
G01X1339165Y857274D01*
X1339972Y855876D01*
X1340062Y855859D01*
G02X1341118Y854584I-242J-1275D01*
G02X1338522I-1298J0D01*
G02X1338595Y855013I1297J0D01*
G01X1338626Y855099D01*
X1337819Y856497D01*
X1337729Y856514D01*
G02X1336674Y857789I243J1275D01*
G37*
G36*
G01X1344074D02*
G02X1346668I1297J0D01*
G02X1346596Y857360I-1297J-3D01*
G01X1346565Y857274D01*
X1347372Y855876D01*
X1347462Y855859D01*
G02X1348518Y854584I-242J-1275D01*
G02X1345922I-1298J0D01*
G02X1345995Y855013I1297J0D01*
G01X1346026Y855099D01*
X1345219Y856497D01*
X1345129Y856514D01*
G02X1344074Y857789I243J1275D01*
G37*
G36*
G01X1351474D02*
G02X1354068I1297J0D01*
G02X1353996Y857360I-1297J-3D01*
G01X1353965Y857274D01*
X1354772Y855876D01*
X1354862Y855859D01*
G02X1355918Y854584I-242J-1275D01*
G02X1353322I-1298J0D01*
G02X1353395Y855013I1297J0D01*
G01X1353426Y855099D01*
X1352619Y856497D01*
X1352529Y856514D01*
G02X1351474Y857789I243J1275D01*
G37*
G36*
G01X1358874D02*
G02X1361468I1297J0D01*
G02X1361396Y857360I-1297J-3D01*
G01X1361365Y857274D01*
X1362172Y855876D01*
X1362262Y855859D01*
G02X1363318Y854584I-242J-1275D01*
G02X1360722I-1298J0D01*
G02X1360795Y855013I1297J0D01*
G01X1360826Y855099D01*
X1360019Y856497D01*
X1359929Y856514D01*
G02X1358874Y857789I243J1275D01*
G37*
G36*
G01X1366274D02*
G02X1368868I1297J0D01*
G02X1368796Y857360I-1297J-3D01*
G01X1368765Y857274D01*
X1369572Y855876D01*
X1369662Y855859D01*
G02X1370718Y854584I-242J-1275D01*
G02X1368122I-1298J0D01*
G02X1368195Y855013I1297J0D01*
G01X1368226Y855099D01*
X1367419Y856497D01*
X1367329Y856514D01*
G02X1366274Y857789I243J1275D01*
G37*
G36*
G01X1373674D02*
G02X1376268I1297J0D01*
G02X1376196Y857360I-1297J-3D01*
G01X1376165Y857274D01*
X1376972Y855876D01*
X1377062Y855859D01*
G02X1378118Y854584I-242J-1275D01*
G02X1375522I-1298J0D01*
G02X1375595Y855013I1297J0D01*
G01X1375626Y855099D01*
X1374819Y856497D01*
X1374729Y856514D01*
G02X1373674Y857789I243J1275D01*
G37*
G36*
G01X1381074D02*
G02X1383668I1297J0D01*
G02X1383596Y857360I-1297J-3D01*
G01X1383565Y857274D01*
X1384372Y855876D01*
X1384462Y855859D01*
G02X1385518Y854584I-242J-1275D01*
G02X1382922I-1298J0D01*
G02X1382995Y855013I1297J0D01*
G01X1383026Y855099D01*
X1382219Y856497D01*
X1382129Y856514D01*
G02X1381074Y857789I243J1275D01*
G37*
G36*
G01X1388474D02*
G02X1391068I1297J0D01*
G02X1390996Y857360I-1297J-3D01*
G01X1390965Y857274D01*
X1391772Y855876D01*
X1391862Y855859D01*
G02X1392918Y854584I-242J-1275D01*
G02X1390322I-1298J0D01*
G02X1390395Y855013I1297J0D01*
G01X1390426Y855099D01*
X1389619Y856497D01*
X1389529Y856514D01*
G02X1388474Y857789I243J1275D01*
G37*
G36*
G01X1395874D02*
G02X1398468I1297J0D01*
G02X1398396Y857360I-1297J-3D01*
G01X1398365Y857274D01*
X1399172Y855876D01*
X1399262Y855859D01*
G02X1400318Y854584I-242J-1275D01*
G02X1397722I-1298J0D01*
G02X1397795Y855013I1297J0D01*
G01X1397826Y855099D01*
X1397019Y856497D01*
X1396929Y856514D01*
G02X1395874Y857789I243J1275D01*
G37*
G36*
G01X1403274D02*
G02X1405868I1297J0D01*
G02X1405796Y857360I-1297J-3D01*
G01X1405765Y857274D01*
X1406572Y855876D01*
X1406662Y855859D01*
G02X1407718Y854584I-242J-1275D01*
G02X1405122I-1298J0D01*
G02X1405195Y855013I1297J0D01*
G01X1405226Y855099D01*
X1404419Y856497D01*
X1404329Y856514D01*
G02X1403274Y857789I243J1275D01*
G37*
G36*
G01X1410674D02*
G02X1413268I1297J0D01*
G02X1413196Y857360I-1297J-3D01*
G01X1413165Y857274D01*
X1413972Y855876D01*
X1414062Y855859D01*
G02X1415118Y854584I-242J-1275D01*
G02X1412524I-1297J0D01*
G02X1412596Y855012I1297J2D01*
G01X1412626Y855098D01*
X1411819Y856497D01*
X1411729Y856514D01*
G02X1410674Y857789I243J1275D01*
G37*
G36*
G01X1421774D02*
G02X1424368I1297J0D01*
G02X1423313Y856514I-1298J0D01*
G01X1423223Y856497D01*
X1422415Y855098D01*
X1422445Y855011D01*
G02X1422518Y854584I-1225J-429D01*
G02X1419922I-1298J0D01*
G02X1420980Y855859I1297J0D01*
G01X1421070Y855876D01*
X1421877Y857274D01*
X1421846Y857361D01*
G02X1421774Y857789I1225J426D01*
G37*
G36*
G01X1429174D02*
G02X1431768I1297J0D01*
G02X1430713Y856514I-1298J0D01*
G01X1430623Y856497D01*
X1429815Y855098D01*
X1429845Y855011D01*
G02X1429918Y854584I-1225J-429D01*
G02X1427322I-1298J0D01*
G02X1428380Y855859I1297J0D01*
G01X1428470Y855876D01*
X1429277Y857274D01*
X1429246Y857361D01*
G02X1429174Y857789I1225J426D01*
G37*
G36*
G01X1436574D02*
G02X1439168I1297J0D01*
G02X1438113Y856514I-1298J0D01*
G01X1438023Y856497D01*
X1437215Y855098D01*
X1437245Y855011D01*
G02X1437318Y854584I-1225J-429D01*
G02X1434722I-1298J0D01*
G02X1435780Y855859I1297J0D01*
G01X1435870Y855876D01*
X1436677Y857274D01*
X1436646Y857361D01*
G02X1436574Y857789I1225J426D01*
G37*
G36*
G01X1443974D02*
G02X1446568I1297J0D01*
G02X1445513Y856514I-1298J0D01*
G01X1445423Y856497D01*
X1444615Y855098D01*
X1444645Y855011D01*
G02X1444718Y854584I-1225J-429D01*
G02X1442122I-1298J0D01*
G02X1443180Y855859I1297J0D01*
G01X1443270Y855876D01*
X1444077Y857274D01*
X1444046Y857361D01*
G02X1443974Y857789I1225J426D01*
G37*
G36*
G01X1451374D02*
G02X1453968I1297J0D01*
G02X1452913Y856514I-1298J0D01*
G01X1452823Y856497D01*
X1452015Y855098D01*
X1452045Y855011D01*
G02X1452118Y854584I-1225J-429D01*
G02X1449522I-1298J0D01*
G02X1450580Y855859I1297J0D01*
G01X1450670Y855876D01*
X1451477Y857274D01*
X1451446Y857361D01*
G02X1451374Y857789I1225J426D01*
G37*
G36*
G01X1458774D02*
G02X1461368I1297J0D01*
G02X1460313Y856514I-1298J0D01*
G01X1460223Y856497D01*
X1459415Y855098D01*
X1459445Y855011D01*
G02X1459518Y854584I-1225J-429D01*
G02X1456922I-1298J0D01*
G02X1457980Y855859I1297J0D01*
G01X1458070Y855876D01*
X1458877Y857274D01*
X1458846Y857361D01*
G02X1458774Y857789I1225J426D01*
G37*
G36*
G01X1466174D02*
G02X1468768I1297J0D01*
G02X1467713Y856514I-1298J0D01*
G01X1467623Y856497D01*
X1466815Y855098D01*
X1466845Y855011D01*
G02X1466918Y854584I-1225J-429D01*
G02X1464322I-1298J0D01*
G02X1465380Y855859I1297J0D01*
G01X1465470Y855876D01*
X1466277Y857274D01*
X1466246Y857361D01*
G02X1466174Y857789I1225J426D01*
G37*
G36*
G01X1473574D02*
G02X1476168I1297J0D01*
G02X1475113Y856514I-1298J0D01*
G01X1475023Y856497D01*
X1474215Y855098D01*
X1474245Y855011D01*
G02X1474318Y854584I-1225J-429D01*
G02X1471722I-1298J0D01*
G02X1472780Y855859I1297J0D01*
G01X1472870Y855876D01*
X1473677Y857274D01*
X1473646Y857361D01*
G02X1473574Y857789I1225J426D01*
G37*
G36*
G01X1480974D02*
G02X1483568I1297J0D01*
G02X1482513Y856514I-1298J0D01*
G01X1482423Y856497D01*
X1481615Y855098D01*
X1481645Y855011D01*
G02X1481718Y854584I-1225J-429D01*
G02X1479122I-1298J0D01*
G02X1480180Y855859I1297J0D01*
G01X1480270Y855876D01*
X1481077Y857274D01*
X1481046Y857361D01*
G02X1480974Y857789I1225J426D01*
G37*
G36*
G01X1488374D02*
G02X1490968I1297J0D01*
G02X1489913Y856514I-1298J0D01*
G01X1489823Y856497D01*
X1489015Y855098D01*
X1489045Y855011D01*
G02X1489118Y854584I-1225J-429D01*
G02X1486522I-1298J0D01*
G02X1487580Y855859I1297J0D01*
G01X1487670Y855876D01*
X1488477Y857274D01*
X1488446Y857361D01*
G02X1488374Y857789I1225J426D01*
G37*
G36*
G01X1495774D02*
G02X1498368I1297J0D01*
G02X1497313Y856514I-1298J0D01*
G01X1497223Y856497D01*
X1496415Y855098D01*
X1496445Y855011D01*
G02X1496518Y854584I-1225J-429D01*
G02X1493922I-1298J0D01*
G02X1494980Y855859I1297J0D01*
G01X1495070Y855876D01*
X1495877Y857274D01*
X1495846Y857361D01*
G02X1495774Y857789I1225J426D01*
G37*
G36*
G01X1503174D02*
G02X1505768I1297J0D01*
G02X1504713Y856514I-1298J0D01*
G01X1504623Y856497D01*
X1503815Y855098D01*
X1503845Y855011D01*
G02X1503918Y854584I-1225J-429D01*
G02X1501322I-1298J0D01*
G02X1502380Y855859I1297J0D01*
G01X1502470Y855876D01*
X1503277Y857274D01*
X1503246Y857361D01*
G02X1503174Y857789I1225J426D01*
G37*
G36*
G01X351280Y860993D02*
G02X353876I1298J0D01*
G02X352820Y859718I-1298J0D01*
G01X352730Y859701D01*
X351923Y858304D01*
X351954Y858217D01*
G02X352026Y857789I-1225J-426D01*
G02X349432I-1297J0D01*
G02X350487Y859064I1298J0D01*
G01X350577Y859081D01*
X351384Y860478D01*
X351353Y860565D01*
G02X351280Y860993I1225J429D01*
G37*
G36*
G01X358680D02*
G02X361276I1298J0D01*
G02X360220Y859718I-1298J0D01*
G01X360130Y859701D01*
X359323Y858304D01*
X359354Y858217D01*
G02X359426Y857789I-1225J-426D01*
G02X356832I-1297J0D01*
G02X357887Y859064I1298J0D01*
G01X357977Y859081D01*
X358784Y860478D01*
X358753Y860565D01*
G02X358680Y860993I1225J429D01*
G37*
G36*
G01X366080D02*
G02X368676I1298J0D01*
G02X367620Y859718I-1298J0D01*
G01X367530Y859701D01*
X366723Y858304D01*
X366754Y858217D01*
G02X366826Y857789I-1225J-426D01*
G02X364232I-1297J0D01*
G02X365287Y859064I1298J0D01*
G01X365377Y859081D01*
X366184Y860478D01*
X366153Y860565D01*
G02X366080Y860993I1225J429D01*
G37*
G36*
G01X373480D02*
G02X376076I1298J0D01*
G02X375020Y859718I-1298J0D01*
G01X374930Y859701D01*
X374123Y858304D01*
X374154Y858217D01*
G02X374226Y857789I-1225J-426D01*
G02X371632I-1297J0D01*
G02X372687Y859064I1298J0D01*
G01X372777Y859081D01*
X373584Y860478D01*
X373553Y860565D01*
G02X373480Y860993I1225J429D01*
G37*
G36*
G01X380880D02*
G02X383476I1298J0D01*
G02X382420Y859718I-1298J0D01*
G01X382330Y859701D01*
X381523Y858304D01*
X381554Y858217D01*
G02X381626Y857789I-1225J-426D01*
G02X379032I-1297J0D01*
G02X380087Y859064I1298J0D01*
G01X380177Y859081D01*
X380984Y860478D01*
X380953Y860565D01*
G02X380880Y860993I1225J429D01*
G37*
G36*
G01X388280D02*
G02X390876I1298J0D01*
G02X389820Y859718I-1298J0D01*
G01X389730Y859701D01*
X388923Y858304D01*
X388954Y858217D01*
G02X389026Y857789I-1225J-426D01*
G02X386432I-1297J0D01*
G02X387487Y859064I1298J0D01*
G01X387577Y859081D01*
X388384Y860478D01*
X388353Y860565D01*
G02X388280Y860993I1225J429D01*
G37*
G36*
G01X395680D02*
G02X398276I1298J0D01*
G02X397220Y859718I-1298J0D01*
G01X397130Y859701D01*
X396323Y858304D01*
X396354Y858217D01*
G02X396426Y857789I-1225J-426D01*
G02X393832I-1297J0D01*
G02X394887Y859064I1298J0D01*
G01X394977Y859081D01*
X395784Y860478D01*
X395753Y860565D01*
G02X395680Y860993I1225J429D01*
G37*
G36*
G01X403080D02*
G02X405676I1298J0D01*
G02X404620Y859718I-1298J0D01*
G01X404530Y859701D01*
X403723Y858304D01*
X403754Y858217D01*
G02X403826Y857789I-1225J-426D01*
G02X401232I-1297J0D01*
G02X402287Y859064I1298J0D01*
G01X402377Y859081D01*
X403184Y860478D01*
X403153Y860565D01*
G02X403080Y860993I1225J429D01*
G37*
G36*
G01X410480D02*
G02X413076I1298J0D01*
G02X412020Y859718I-1298J0D01*
G01X411930Y859701D01*
X411123Y858304D01*
X411154Y858217D01*
G02X411226Y857789I-1225J-426D01*
G02X408632I-1297J0D01*
G02X409687Y859064I1298J0D01*
G01X409777Y859081D01*
X410584Y860478D01*
X410553Y860565D01*
G02X410480Y860993I1225J429D01*
G37*
G36*
G01X417880D02*
G02X420476I1298J0D01*
G02X419420Y859718I-1298J0D01*
G01X419330Y859701D01*
X418523Y858304D01*
X418554Y858217D01*
G02X418626Y857789I-1225J-426D01*
G02X416032I-1297J0D01*
G02X417087Y859064I1298J0D01*
G01X417177Y859081D01*
X417984Y860478D01*
X417953Y860565D01*
G02X417880Y860993I1225J429D01*
G37*
G36*
G01X425280D02*
G02X427876I1298J0D01*
G02X426820Y859718I-1298J0D01*
G01X426730Y859701D01*
X425923Y858304D01*
X425954Y858217D01*
G02X426026Y857789I-1225J-426D01*
G02X423432I-1297J0D01*
G02X424487Y859064I1298J0D01*
G01X424577Y859081D01*
X425384Y860478D01*
X425353Y860565D01*
G02X425280Y860993I1225J429D01*
G37*
G36*
G01X432682D02*
G02X435276I1297J0D01*
G02X434221Y859718I-1298J0D01*
G01X434131Y859701D01*
X433324Y858303D01*
X433354Y858217D01*
G02X433426Y857789I-1225J-426D01*
G02X430832I-1297J0D01*
G02X431888Y859064I1298J0D01*
G01X431978Y859081D01*
X432785Y860478D01*
X432754Y860565D01*
G02X432682Y860993I1225J426D01*
G37*
G36*
G01X440080D02*
G02X442676I1298J0D01*
G02X442603Y860564I-1297J0D01*
G01X442572Y860478D01*
X443378Y859081D01*
X443468Y859064D01*
G02X444526Y857789I-239J-1275D01*
G02X441932I-1297J0D01*
G02X442003Y858215I1297J3D01*
G01X442034Y858302D01*
X441226Y859701D01*
X441136Y859718D01*
G02X440080Y860993I242J1275D01*
G37*
G36*
G01X447482D02*
G02X450076I1297J0D01*
G02X450004Y860564I-1297J-3D01*
G01X449973Y860478D01*
X450779Y859081D01*
X450869Y859064D01*
G02X451926Y857789I-240J-1275D01*
G02X449332I-1297J0D01*
G01Y857791D01*
G02X449404Y858216I1297J-1D01*
G01X449434Y858303D01*
X448627Y859701D01*
X448537Y859718D01*
G02X447482Y860993I243J1275D01*
G37*
G36*
G01X454880D02*
G02X457476I1298J0D01*
G02X457403Y860564I-1297J0D01*
G01X457372Y860478D01*
X458178Y859081D01*
X458268Y859064D01*
G02X459326Y857789I-239J-1275D01*
G02X456732I-1297J0D01*
G02X456803Y858215I1297J3D01*
G01X456834Y858302D01*
X456026Y859701D01*
X455936Y859718D01*
G02X454880Y860993I242J1275D01*
G37*
G36*
G01X462280D02*
G02X464876I1298J0D01*
G02X464803Y860564I-1297J0D01*
G01X464772Y860478D01*
X465578Y859081D01*
X465668Y859064D01*
G02X466726Y857789I-239J-1275D01*
G02X464132I-1297J0D01*
G02X464203Y858215I1297J3D01*
G01X464234Y858302D01*
X463426Y859701D01*
X463336Y859718D01*
G02X462280Y860993I242J1275D01*
G37*
G36*
G01X469680D02*
G02X472276I1298J0D01*
G02X472203Y860564I-1297J0D01*
G01X472172Y860478D01*
X472978Y859081D01*
X473068Y859064D01*
G02X474126Y857789I-239J-1275D01*
G02X471532I-1297J0D01*
G02X471603Y858215I1297J3D01*
G01X471634Y858302D01*
X470826Y859701D01*
X470736Y859718D01*
G02X469680Y860993I242J1275D01*
G37*
G36*
G01X477080D02*
G02X479676I1298J0D01*
G02X479603Y860564I-1297J0D01*
G01X479572Y860478D01*
X480378Y859081D01*
X480468Y859064D01*
G02X481526Y857789I-239J-1275D01*
G02X478932I-1297J0D01*
G02X479003Y858215I1297J3D01*
G01X479034Y858302D01*
X478226Y859701D01*
X478136Y859718D01*
G02X477080Y860993I242J1275D01*
G37*
G36*
G01X484480D02*
G02X487076I1298J0D01*
G02X487003Y860564I-1297J0D01*
G01X486972Y860478D01*
X487778Y859081D01*
X487868Y859064D01*
G02X488926Y857789I-239J-1275D01*
G02X486332I-1297J0D01*
G02X486403Y858215I1297J3D01*
G01X486434Y858302D01*
X485626Y859701D01*
X485536Y859718D01*
G02X484480Y860993I242J1275D01*
G37*
G36*
G01X491880D02*
G02X494476I1298J0D01*
G02X494403Y860564I-1297J0D01*
G01X494372Y860478D01*
X495178Y859081D01*
X495268Y859064D01*
G02X496326Y857789I-239J-1275D01*
G02X493732I-1297J0D01*
G02X493803Y858215I1297J3D01*
G01X493834Y858302D01*
X493026Y859701D01*
X492936Y859718D01*
G02X491880Y860993I242J1275D01*
G37*
G36*
G01X499280D02*
G02X501876I1298J0D01*
G02X501803Y860564I-1297J0D01*
G01X501772Y860478D01*
X502578Y859081D01*
X502668Y859064D01*
G02X503726Y857789I-239J-1275D01*
G02X501132I-1297J0D01*
G02X501203Y858215I1297J3D01*
G01X501234Y858302D01*
X500426Y859701D01*
X500336Y859718D01*
G02X499280Y860993I242J1275D01*
G37*
G36*
G01X506680D02*
G02X509276I1298J0D01*
G02X509203Y860564I-1297J0D01*
G01X509172Y860478D01*
X509978Y859081D01*
X510068Y859064D01*
G02X511126Y857789I-239J-1275D01*
G02X508532I-1297J0D01*
G02X508603Y858215I1297J3D01*
G01X508634Y858302D01*
X507826Y859701D01*
X507736Y859718D01*
G02X506680Y860993I242J1275D01*
G37*
G36*
G01X514080D02*
G02X516676I1298J0D01*
G02X516603Y860564I-1297J0D01*
G01X516572Y860478D01*
X517378Y859081D01*
X517468Y859064D01*
G02X518526Y857789I-239J-1275D01*
G02X515932I-1297J0D01*
G02X516003Y858215I1297J3D01*
G01X516034Y858302D01*
X515226Y859701D01*
X515136Y859718D01*
G02X514080Y860993I242J1275D01*
G37*
G36*
G01X521480D02*
G02X524076I1298J0D01*
G02X524003Y860564I-1297J0D01*
G01X523972Y860478D01*
X524778Y859081D01*
X524868Y859064D01*
G02X525926Y857789I-239J-1275D01*
G02X523332I-1297J0D01*
G02X523403Y858215I1297J3D01*
G01X523434Y858302D01*
X522626Y859701D01*
X522536Y859718D01*
G02X521480Y860993I242J1275D01*
G37*
G36*
G01X1327422D02*
G02X1330018I1298J0D01*
G02X1328962Y859718I-1298J0D01*
G01X1328872Y859701D01*
X1328065Y858304D01*
X1328096Y858217D01*
G02X1328168Y857789I-1225J-426D01*
G02X1325574I-1297J0D01*
G02X1326629Y859064I1298J0D01*
G01X1326719Y859081D01*
X1327526Y860478D01*
X1327495Y860565D01*
G02X1327422Y860993I1225J429D01*
G37*
G36*
G01X1334822D02*
G02X1337418I1298J0D01*
G02X1336362Y859718I-1298J0D01*
G01X1336272Y859701D01*
X1335465Y858304D01*
X1335496Y858217D01*
G02X1335568Y857789I-1225J-426D01*
G02X1332974I-1297J0D01*
G02X1334029Y859064I1298J0D01*
G01X1334119Y859081D01*
X1334926Y860478D01*
X1334895Y860565D01*
G02X1334822Y860993I1225J429D01*
G37*
G36*
G01X1342222D02*
G02X1344818I1298J0D01*
G02X1343762Y859718I-1298J0D01*
G01X1343672Y859701D01*
X1342865Y858304D01*
X1342896Y858217D01*
G02X1342968Y857789I-1225J-426D01*
G02X1340374I-1297J0D01*
G02X1341429Y859064I1298J0D01*
G01X1341519Y859081D01*
X1342326Y860478D01*
X1342295Y860565D01*
G02X1342222Y860993I1225J429D01*
G37*
G36*
G01X1349622D02*
G02X1352218I1298J0D01*
G02X1351162Y859718I-1298J0D01*
G01X1351072Y859701D01*
X1350265Y858304D01*
X1350296Y858217D01*
G02X1350368Y857789I-1225J-426D01*
G02X1347774I-1297J0D01*
G02X1348829Y859064I1298J0D01*
G01X1348919Y859081D01*
X1349726Y860478D01*
X1349695Y860565D01*
G02X1349622Y860993I1225J429D01*
G37*
G36*
G01X1357022D02*
G02X1359618I1298J0D01*
G02X1358562Y859718I-1298J0D01*
G01X1358472Y859701D01*
X1357665Y858304D01*
X1357696Y858217D01*
G02X1357768Y857789I-1225J-426D01*
G02X1355174I-1297J0D01*
G02X1356229Y859064I1298J0D01*
G01X1356319Y859081D01*
X1357126Y860478D01*
X1357095Y860565D01*
G02X1357022Y860993I1225J429D01*
G37*
G36*
G01X1364422D02*
G02X1367018I1298J0D01*
G02X1365962Y859718I-1298J0D01*
G01X1365872Y859701D01*
X1365065Y858304D01*
X1365096Y858217D01*
G02X1365168Y857789I-1225J-426D01*
G02X1362574I-1297J0D01*
G02X1363629Y859064I1298J0D01*
G01X1363719Y859081D01*
X1364526Y860478D01*
X1364495Y860565D01*
G02X1364422Y860993I1225J429D01*
G37*
G36*
G01X1371822D02*
G02X1374418I1298J0D01*
G02X1373362Y859718I-1298J0D01*
G01X1373272Y859701D01*
X1372465Y858304D01*
X1372496Y858217D01*
G02X1372568Y857789I-1225J-426D01*
G02X1369974I-1297J0D01*
G02X1371029Y859064I1298J0D01*
G01X1371119Y859081D01*
X1371926Y860478D01*
X1371895Y860565D01*
G02X1371822Y860993I1225J429D01*
G37*
G36*
G01X1379222D02*
G02X1381818I1298J0D01*
G02X1380762Y859718I-1298J0D01*
G01X1380672Y859701D01*
X1379865Y858304D01*
X1379896Y858217D01*
G02X1379968Y857789I-1225J-426D01*
G02X1377374I-1297J0D01*
G02X1378429Y859064I1298J0D01*
G01X1378519Y859081D01*
X1379326Y860478D01*
X1379295Y860565D01*
G02X1379222Y860993I1225J429D01*
G37*
G36*
G01X1386622D02*
G02X1389218I1298J0D01*
G02X1388162Y859718I-1298J0D01*
G01X1388072Y859701D01*
X1387265Y858304D01*
X1387296Y858217D01*
G02X1387368Y857789I-1225J-426D01*
G02X1384774I-1297J0D01*
G02X1385829Y859064I1298J0D01*
G01X1385919Y859081D01*
X1386726Y860478D01*
X1386695Y860565D01*
G02X1386622Y860993I1225J429D01*
G37*
G36*
G01X1394022D02*
G02X1396618I1298J0D01*
G02X1395562Y859718I-1298J0D01*
G01X1395472Y859701D01*
X1394665Y858304D01*
X1394696Y858217D01*
G02X1394768Y857789I-1225J-426D01*
G02X1392174I-1297J0D01*
G02X1393229Y859064I1298J0D01*
G01X1393319Y859081D01*
X1394126Y860478D01*
X1394095Y860565D01*
G02X1394022Y860993I1225J429D01*
G37*
G36*
G01X1401422D02*
G02X1404018I1298J0D01*
G02X1402962Y859718I-1298J0D01*
G01X1402872Y859701D01*
X1402065Y858304D01*
X1402096Y858217D01*
G02X1402168Y857789I-1225J-426D01*
G02X1399574I-1297J0D01*
G02X1400629Y859064I1298J0D01*
G01X1400719Y859081D01*
X1401526Y860478D01*
X1401495Y860565D01*
G02X1401422Y860993I1225J429D01*
G37*
G36*
G01X1408824D02*
G02X1411418I1297J0D01*
G02X1410363Y859718I-1298J0D01*
G01X1410273Y859701D01*
X1409466Y858303D01*
X1409496Y858217D01*
G02X1409568Y857789I-1225J-426D01*
G02X1406974I-1297J0D01*
G02X1408030Y859064I1298J0D01*
G01X1408120Y859081D01*
X1408927Y860478D01*
X1408896Y860565D01*
G02X1408824Y860993I1225J426D01*
G37*
G36*
G01X1416222D02*
G02X1418818I1298J0D01*
G02X1418745Y860564I-1297J0D01*
G01X1418714Y860478D01*
X1419520Y859081D01*
X1419610Y859064D01*
G02X1420668Y857789I-239J-1275D01*
G02X1418074I-1297J0D01*
G02X1418145Y858215I1297J3D01*
G01X1418176Y858302D01*
X1417368Y859701D01*
X1417278Y859718D01*
G02X1416222Y860993I242J1275D01*
G37*
G36*
G01X1423624D02*
G02X1426218I1297J0D01*
G02X1426146Y860564I-1297J-3D01*
G01X1426115Y860478D01*
X1426921Y859081D01*
X1427011Y859064D01*
G02X1428068Y857789I-240J-1275D01*
G02X1425474I-1297J0D01*
G01Y857791D01*
G02X1425546Y858216I1297J-1D01*
G01X1425576Y858303D01*
X1424769Y859701D01*
X1424679Y859718D01*
G02X1423624Y860993I243J1275D01*
G37*
G36*
G01X1431022D02*
G02X1433618I1298J0D01*
G02X1433545Y860564I-1297J0D01*
G01X1433514Y860478D01*
X1434320Y859081D01*
X1434410Y859064D01*
G02X1435468Y857789I-239J-1275D01*
G02X1432874I-1297J0D01*
G02X1432945Y858215I1297J3D01*
G01X1432976Y858302D01*
X1432168Y859701D01*
X1432078Y859718D01*
G02X1431022Y860993I242J1275D01*
G37*
G36*
G01X1438422D02*
G02X1441018I1298J0D01*
G02X1440945Y860564I-1297J0D01*
G01X1440914Y860478D01*
X1441720Y859081D01*
X1441810Y859064D01*
G02X1442868Y857789I-239J-1275D01*
G02X1440274I-1297J0D01*
G02X1440345Y858215I1297J3D01*
G01X1440376Y858302D01*
X1439568Y859701D01*
X1439478Y859718D01*
G02X1438422Y860993I242J1275D01*
G37*
G36*
G01X1445822D02*
G02X1448418I1298J0D01*
G02X1448345Y860564I-1297J0D01*
G01X1448314Y860478D01*
X1449120Y859081D01*
X1449210Y859064D01*
G02X1450268Y857789I-239J-1275D01*
G02X1447674I-1297J0D01*
G02X1447745Y858215I1297J3D01*
G01X1447776Y858302D01*
X1446968Y859701D01*
X1446878Y859718D01*
G02X1445822Y860993I242J1275D01*
G37*
G36*
G01X1453222D02*
G02X1455818I1298J0D01*
G02X1455745Y860564I-1297J0D01*
G01X1455714Y860478D01*
X1456520Y859081D01*
X1456610Y859064D01*
G02X1457668Y857789I-239J-1275D01*
G02X1455074I-1297J0D01*
G02X1455145Y858215I1297J3D01*
G01X1455176Y858302D01*
X1454368Y859701D01*
X1454278Y859718D01*
G02X1453222Y860993I242J1275D01*
G37*
G36*
G01X1460622D02*
G02X1463218I1298J0D01*
G02X1463145Y860564I-1297J0D01*
G01X1463114Y860478D01*
X1463920Y859081D01*
X1464010Y859064D01*
G02X1465068Y857789I-239J-1275D01*
G02X1462474I-1297J0D01*
G02X1462545Y858215I1297J3D01*
G01X1462576Y858302D01*
X1461768Y859701D01*
X1461678Y859718D01*
G02X1460622Y860993I242J1275D01*
G37*
G36*
G01X1468022D02*
G02X1470618I1298J0D01*
G02X1470545Y860564I-1297J0D01*
G01X1470514Y860478D01*
X1471320Y859081D01*
X1471410Y859064D01*
G02X1472468Y857789I-239J-1275D01*
G02X1469874I-1297J0D01*
G02X1469945Y858215I1297J3D01*
G01X1469976Y858302D01*
X1469168Y859701D01*
X1469078Y859718D01*
G02X1468022Y860993I242J1275D01*
G37*
G36*
G01X1475422D02*
G02X1478018I1298J0D01*
G02X1477945Y860564I-1297J0D01*
G01X1477914Y860478D01*
X1478720Y859081D01*
X1478810Y859064D01*
G02X1479868Y857789I-239J-1275D01*
G02X1477274I-1297J0D01*
G02X1477345Y858215I1297J3D01*
G01X1477376Y858302D01*
X1476568Y859701D01*
X1476478Y859718D01*
G02X1475422Y860993I242J1275D01*
G37*
G36*
G01X1482822D02*
G02X1485418I1298J0D01*
G02X1485345Y860564I-1297J0D01*
G01X1485314Y860478D01*
X1486120Y859081D01*
X1486210Y859064D01*
G02X1487268Y857789I-239J-1275D01*
G02X1484674I-1297J0D01*
G02X1484745Y858215I1297J3D01*
G01X1484776Y858302D01*
X1483968Y859701D01*
X1483878Y859718D01*
G02X1482822Y860993I242J1275D01*
G37*
G36*
G01X1490222D02*
G02X1492818I1298J0D01*
G02X1492745Y860564I-1297J0D01*
G01X1492714Y860478D01*
X1493520Y859081D01*
X1493610Y859064D01*
G02X1494668Y857789I-239J-1275D01*
G02X1492074I-1297J0D01*
G02X1492145Y858215I1297J3D01*
G01X1492176Y858302D01*
X1491368Y859701D01*
X1491278Y859718D01*
G02X1490222Y860993I242J1275D01*
G37*
G36*
G01X1497622D02*
G02X1500218I1298J0D01*
G02X1500145Y860564I-1297J0D01*
G01X1500114Y860478D01*
X1500920Y859081D01*
X1501010Y859064D01*
G02X1502068Y857789I-239J-1275D01*
G02X1499474I-1297J0D01*
G02X1499545Y858215I1297J3D01*
G01X1499576Y858302D01*
X1498768Y859701D01*
X1498678Y859718D01*
G02X1497622Y860993I242J1275D01*
G37*
G36*
G01X353132Y870606D02*
G02X355726I1297J0D01*
G02X355654Y870177I-1297J-3D01*
G01X355623Y870091D01*
X356430Y868693D01*
X356520Y868676D01*
G02X357576Y867401I-242J-1275D01*
G02X354980I-1298J0D01*
G02X355053Y867830I1297J0D01*
G01X355084Y867916D01*
X354277Y869314D01*
X354187Y869331D01*
G02X353132Y870606I243J1275D01*
G37*
G36*
G01X360532D02*
G02X363126I1297J0D01*
G02X363054Y870177I-1297J-3D01*
G01X363023Y870091D01*
X363830Y868693D01*
X363920Y868676D01*
G02X364976Y867401I-242J-1275D01*
G02X362380I-1298J0D01*
G02X362453Y867830I1297J0D01*
G01X362484Y867916D01*
X361677Y869314D01*
X361587Y869331D01*
G02X360532Y870606I243J1275D01*
G37*
G36*
G01X367932D02*
G02X370526I1297J0D01*
G02X370454Y870177I-1297J-3D01*
G01X370423Y870091D01*
X371230Y868693D01*
X371320Y868676D01*
G02X372376Y867401I-242J-1275D01*
G02X369780I-1298J0D01*
G02X369853Y867830I1297J0D01*
G01X369884Y867916D01*
X369077Y869314D01*
X368987Y869331D01*
G02X367932Y870606I243J1275D01*
G37*
G36*
G01X375332D02*
G02X377926I1297J0D01*
G02X377854Y870177I-1297J-3D01*
G01X377823Y870091D01*
X378630Y868693D01*
X378720Y868676D01*
G02X379776Y867401I-242J-1275D01*
G02X377180I-1298J0D01*
G02X377253Y867830I1297J0D01*
G01X377284Y867916D01*
X376477Y869314D01*
X376387Y869331D01*
G02X375332Y870606I243J1275D01*
G37*
G36*
G01X382732D02*
G02X385326I1297J0D01*
G02X385254Y870177I-1297J-3D01*
G01X385223Y870091D01*
X386030Y868693D01*
X386120Y868676D01*
G02X387176Y867401I-242J-1275D01*
G02X384580I-1298J0D01*
G02X384653Y867830I1297J0D01*
G01X384684Y867916D01*
X383877Y869314D01*
X383787Y869331D01*
G02X382732Y870606I243J1275D01*
G37*
G36*
G01X390132D02*
G02X392726I1297J0D01*
G02X392654Y870177I-1297J-3D01*
G01X392623Y870091D01*
X393430Y868693D01*
X393520Y868676D01*
G02X394576Y867401I-242J-1275D01*
G02X391980I-1298J0D01*
G02X392053Y867830I1297J0D01*
G01X392084Y867916D01*
X391277Y869314D01*
X391187Y869331D01*
G02X390132Y870606I243J1275D01*
G37*
G36*
G01X397532D02*
G02X400126I1297J0D01*
G02X400054Y870177I-1297J-3D01*
G01X400023Y870091D01*
X400830Y868693D01*
X400920Y868676D01*
G02X401976Y867401I-242J-1275D01*
G02X399380I-1298J0D01*
G02X399453Y867830I1297J0D01*
G01X399484Y867916D01*
X398677Y869314D01*
X398587Y869331D01*
G02X397532Y870606I243J1275D01*
G37*
G36*
G01X404932D02*
G02X407526I1297J0D01*
G02X407454Y870177I-1297J-3D01*
G01X407423Y870091D01*
X408230Y868693D01*
X408320Y868676D01*
G02X409376Y867401I-242J-1275D01*
G02X406780I-1298J0D01*
G02X406853Y867830I1297J0D01*
G01X406884Y867916D01*
X406077Y869314D01*
X405987Y869331D01*
G02X404932Y870606I243J1275D01*
G37*
G36*
G01X416032D02*
G02X418626I1297J0D01*
G02X417571Y869331I-1298J0D01*
G01X417481Y869314D01*
X416673Y867915D01*
X416703Y867828D01*
G02X416776Y867401I-1225J-429D01*
G02X414180I-1298J0D01*
G02X415238Y868676I1297J0D01*
G01X415328Y868693D01*
X416135Y870091D01*
X416104Y870178D01*
G02X416032Y870606I1225J426D01*
G37*
G36*
G01X423432D02*
G02X426026I1297J0D01*
G02X424971Y869331I-1298J0D01*
G01X424881Y869314D01*
X424073Y867915D01*
X424103Y867828D01*
G02X424176Y867401I-1225J-429D01*
G02X421580I-1298J0D01*
G02X422638Y868676I1297J0D01*
G01X422728Y868693D01*
X423535Y870091D01*
X423504Y870178D01*
G02X423432Y870606I1225J426D01*
G37*
G36*
G01X430832D02*
G02X433426I1297J0D01*
G02X432371Y869331I-1298J0D01*
G01X432281Y869314D01*
X431473Y867915D01*
X431503Y867828D01*
G02X431576Y867401I-1225J-429D01*
G02X428980I-1298J0D01*
G02X430038Y868676I1297J0D01*
G01X430128Y868693D01*
X430935Y870091D01*
X430904Y870178D01*
G02X430832Y870606I1225J426D01*
G37*
G36*
G01X438232D02*
G02X440826I1297J0D01*
G02X439771Y869331I-1298J0D01*
G01X439681Y869314D01*
X438873Y867915D01*
X438903Y867828D01*
G02X438976Y867401I-1225J-429D01*
G02X436380I-1298J0D01*
G02X437438Y868676I1297J0D01*
G01X437528Y868693D01*
X438335Y870091D01*
X438304Y870178D01*
G02X438232Y870606I1225J426D01*
G37*
G36*
G01X445632D02*
G02X448226I1297J0D01*
G02X447171Y869331I-1298J0D01*
G01X447081Y869314D01*
X446273Y867915D01*
X446303Y867828D01*
G02X446376Y867401I-1225J-429D01*
G02X443780I-1298J0D01*
G02X444838Y868676I1297J0D01*
G01X444928Y868693D01*
X445735Y870091D01*
X445704Y870178D01*
G02X445632Y870606I1225J426D01*
G37*
G36*
G01X453032D02*
G02X455626I1297J0D01*
G02X454571Y869331I-1298J0D01*
G01X454481Y869314D01*
X453673Y867915D01*
X453703Y867828D01*
G02X453776Y867401I-1225J-429D01*
G02X451180I-1298J0D01*
G02X452238Y868676I1297J0D01*
G01X452328Y868693D01*
X453135Y870091D01*
X453104Y870178D01*
G02X453032Y870606I1225J426D01*
G37*
G36*
G01X460432D02*
G02X463026I1297J0D01*
G02X461971Y869331I-1298J0D01*
G01X461881Y869314D01*
X461073Y867915D01*
X461103Y867828D01*
G02X461176Y867401I-1225J-429D01*
G02X458580I-1298J0D01*
G02X459638Y868676I1297J0D01*
G01X459728Y868693D01*
X460535Y870091D01*
X460504Y870178D01*
G02X460432Y870606I1225J426D01*
G37*
G36*
G01X467832D02*
G02X470426I1297J0D01*
G02X469371Y869331I-1298J0D01*
G01X469281Y869314D01*
X468473Y867915D01*
X468503Y867828D01*
G02X468576Y867401I-1225J-429D01*
G02X465980I-1298J0D01*
G02X467038Y868676I1297J0D01*
G01X467128Y868693D01*
X467935Y870091D01*
X467904Y870178D01*
G02X467832Y870606I1225J426D01*
G37*
G36*
G01X475232D02*
G02X477826I1297J0D01*
G02X476771Y869331I-1298J0D01*
G01X476681Y869314D01*
X475873Y867915D01*
X475903Y867828D01*
G02X475976Y867401I-1225J-429D01*
G02X473380I-1298J0D01*
G02X474438Y868676I1297J0D01*
G01X474528Y868693D01*
X475335Y870091D01*
X475304Y870178D01*
G02X475232Y870606I1225J426D01*
G37*
G36*
G01X482632D02*
G02X485226I1297J0D01*
G02X484171Y869331I-1298J0D01*
G01X484081Y869314D01*
X483273Y867915D01*
X483303Y867828D01*
G02X483376Y867401I-1225J-429D01*
G02X480780I-1298J0D01*
G02X481838Y868676I1297J0D01*
G01X481928Y868693D01*
X482735Y870091D01*
X482704Y870178D01*
G02X482632Y870606I1225J426D01*
G37*
G36*
G01X490032D02*
G02X492626I1297J0D01*
G02X491571Y869331I-1298J0D01*
G01X491481Y869314D01*
X490673Y867915D01*
X490703Y867828D01*
G02X490776Y867401I-1225J-429D01*
G02X488180I-1298J0D01*
G02X489238Y868676I1297J0D01*
G01X489328Y868693D01*
X490135Y870091D01*
X490104Y870178D01*
G02X490032Y870606I1225J426D01*
G37*
G36*
G01X497432D02*
G02X500026I1297J0D01*
G02X498971Y869331I-1298J0D01*
G01X498881Y869314D01*
X498073Y867915D01*
X498103Y867828D01*
G02X498176Y867401I-1225J-429D01*
G02X495580I-1298J0D01*
G02X496638Y868676I1297J0D01*
G01X496728Y868693D01*
X497535Y870091D01*
X497504Y870178D01*
G02X497432Y870606I1225J426D01*
G37*
G36*
G01X504832D02*
G02X507426I1297J0D01*
G02X506371Y869331I-1298J0D01*
G01X506281Y869314D01*
X505473Y867915D01*
X505503Y867828D01*
G02X505576Y867401I-1225J-429D01*
G02X502980I-1298J0D01*
G02X504038Y868676I1297J0D01*
G01X504128Y868693D01*
X504935Y870091D01*
X504904Y870178D01*
G02X504832Y870606I1225J426D01*
G37*
G36*
G01X512232D02*
G02X514826I1297J0D01*
G02X513771Y869331I-1298J0D01*
G01X513681Y869314D01*
X512873Y867915D01*
X512903Y867828D01*
G02X512976Y867401I-1225J-429D01*
G02X510380I-1298J0D01*
G02X511438Y868676I1297J0D01*
G01X511528Y868693D01*
X512335Y870091D01*
X512304Y870178D01*
G02X512232Y870606I1225J426D01*
G37*
G36*
G01X519632D02*
G02X522226I1297J0D01*
G02X521171Y869331I-1298J0D01*
G01X521081Y869314D01*
X520273Y867915D01*
X520303Y867828D01*
G02X520376Y867401I-1225J-429D01*
G02X517780I-1298J0D01*
G02X518838Y868676I1297J0D01*
G01X518928Y868693D01*
X519735Y870091D01*
X519704Y870178D01*
G02X519632Y870606I1225J426D01*
G37*
G36*
G01X527032D02*
G02X529626I1297J0D01*
G02X528571Y869331I-1298J0D01*
G01X528481Y869314D01*
X527674Y867916D01*
X527704Y867829D01*
G02X527776Y867401I-1225J-426D01*
G02X525182I-1297J0D01*
G02X526238Y868676I1298J0D01*
G01X526328Y868693D01*
X527135Y870091D01*
X527104Y870178D01*
G02X527032Y870606I1225J426D01*
G37*
G36*
G01X1329274D02*
G02X1331868I1297J0D01*
G02X1331796Y870177I-1297J-3D01*
G01X1331765Y870091D01*
X1332572Y868693D01*
X1332662Y868676D01*
G02X1333718Y867401I-242J-1275D01*
G02X1331122I-1298J0D01*
G02X1331195Y867830I1297J0D01*
G01X1331226Y867916D01*
X1330419Y869314D01*
X1330329Y869331D01*
G02X1329274Y870606I243J1275D01*
G37*
G36*
G01X1336674D02*
G02X1339268I1297J0D01*
G02X1339196Y870177I-1297J-3D01*
G01X1339165Y870091D01*
X1339972Y868693D01*
X1340062Y868676D01*
G02X1341118Y867401I-242J-1275D01*
G02X1338522I-1298J0D01*
G02X1338595Y867830I1297J0D01*
G01X1338626Y867916D01*
X1337819Y869314D01*
X1337729Y869331D01*
G02X1336674Y870606I243J1275D01*
G37*
G36*
G01X1344074D02*
G02X1346668I1297J0D01*
G02X1346596Y870177I-1297J-3D01*
G01X1346565Y870091D01*
X1347372Y868693D01*
X1347462Y868676D01*
G02X1348518Y867401I-242J-1275D01*
G02X1345922I-1298J0D01*
G02X1345995Y867830I1297J0D01*
G01X1346026Y867916D01*
X1345219Y869314D01*
X1345129Y869331D01*
G02X1344074Y870606I243J1275D01*
G37*
G36*
G01X1351474D02*
G02X1354068I1297J0D01*
G02X1353996Y870177I-1297J-3D01*
G01X1353965Y870091D01*
X1354772Y868693D01*
X1354862Y868676D01*
G02X1355918Y867401I-242J-1275D01*
G02X1353322I-1298J0D01*
G02X1353395Y867830I1297J0D01*
G01X1353426Y867916D01*
X1352619Y869314D01*
X1352529Y869331D01*
G02X1351474Y870606I243J1275D01*
G37*
G36*
G01X1358874D02*
G02X1361468I1297J0D01*
G02X1361396Y870177I-1297J-3D01*
G01X1361365Y870091D01*
X1362172Y868693D01*
X1362262Y868676D01*
G02X1363318Y867401I-242J-1275D01*
G02X1360722I-1298J0D01*
G02X1360795Y867830I1297J0D01*
G01X1360826Y867916D01*
X1360019Y869314D01*
X1359929Y869331D01*
G02X1358874Y870606I243J1275D01*
G37*
G36*
G01X1366274D02*
G02X1368868I1297J0D01*
G02X1368796Y870177I-1297J-3D01*
G01X1368765Y870091D01*
X1369572Y868693D01*
X1369662Y868676D01*
G02X1370718Y867401I-242J-1275D01*
G02X1368122I-1298J0D01*
G02X1368195Y867830I1297J0D01*
G01X1368226Y867916D01*
X1367419Y869314D01*
X1367329Y869331D01*
G02X1366274Y870606I243J1275D01*
G37*
G36*
G01X1373674D02*
G02X1376268I1297J0D01*
G02X1376196Y870177I-1297J-3D01*
G01X1376165Y870091D01*
X1376972Y868693D01*
X1377062Y868676D01*
G02X1378118Y867401I-242J-1275D01*
G02X1375522I-1298J0D01*
G02X1375595Y867830I1297J0D01*
G01X1375626Y867916D01*
X1374819Y869314D01*
X1374729Y869331D01*
G02X1373674Y870606I243J1275D01*
G37*
G36*
G01X1381074D02*
G02X1383668I1297J0D01*
G02X1383596Y870177I-1297J-3D01*
G01X1383565Y870091D01*
X1384372Y868693D01*
X1384462Y868676D01*
G02X1385518Y867401I-242J-1275D01*
G02X1382922I-1298J0D01*
G02X1382995Y867830I1297J0D01*
G01X1383026Y867916D01*
X1382219Y869314D01*
X1382129Y869331D01*
G02X1381074Y870606I243J1275D01*
G37*
G36*
G01X1392174D02*
G02X1394768I1297J0D01*
G02X1393713Y869331I-1298J0D01*
G01X1393623Y869314D01*
X1392815Y867915D01*
X1392845Y867828D01*
G02X1392918Y867401I-1225J-429D01*
G02X1390322I-1298J0D01*
G02X1391380Y868676I1297J0D01*
G01X1391470Y868693D01*
X1392277Y870091D01*
X1392246Y870178D01*
G02X1392174Y870606I1225J426D01*
G37*
G36*
G01X1399574D02*
G02X1402168I1297J0D01*
G02X1401113Y869331I-1298J0D01*
G01X1401023Y869314D01*
X1400215Y867915D01*
X1400245Y867828D01*
G02X1400318Y867401I-1225J-429D01*
G02X1397722I-1298J0D01*
G02X1398780Y868676I1297J0D01*
G01X1398870Y868693D01*
X1399677Y870091D01*
X1399646Y870178D01*
G02X1399574Y870606I1225J426D01*
G37*
G36*
G01X1406974D02*
G02X1409568I1297J0D01*
G02X1408513Y869331I-1298J0D01*
G01X1408423Y869314D01*
X1407615Y867915D01*
X1407645Y867828D01*
G02X1407718Y867401I-1225J-429D01*
G02X1405122I-1298J0D01*
G02X1406180Y868676I1297J0D01*
G01X1406270Y868693D01*
X1407077Y870091D01*
X1407046Y870178D01*
G02X1406974Y870606I1225J426D01*
G37*
G36*
G01X1414374D02*
G02X1416968I1297J0D01*
G02X1415913Y869331I-1298J0D01*
G01X1415823Y869314D01*
X1415015Y867915D01*
X1415045Y867828D01*
G02X1415118Y867401I-1225J-429D01*
G02X1412522I-1298J0D01*
G02X1413580Y868676I1297J0D01*
G01X1413670Y868693D01*
X1414477Y870091D01*
X1414446Y870178D01*
G02X1414374Y870606I1225J426D01*
G37*
G36*
G01X1421774D02*
G02X1424368I1297J0D01*
G02X1423313Y869331I-1298J0D01*
G01X1423223Y869314D01*
X1422415Y867915D01*
X1422445Y867828D01*
G02X1422518Y867401I-1225J-429D01*
G02X1419922I-1298J0D01*
G02X1420980Y868676I1297J0D01*
G01X1421070Y868693D01*
X1421877Y870091D01*
X1421846Y870178D01*
G02X1421774Y870606I1225J426D01*
G37*
G36*
G01X1429174D02*
G02X1431768I1297J0D01*
G02X1430713Y869331I-1298J0D01*
G01X1430623Y869314D01*
X1429815Y867915D01*
X1429845Y867828D01*
G02X1429918Y867401I-1225J-429D01*
G02X1427322I-1298J0D01*
G02X1428380Y868676I1297J0D01*
G01X1428470Y868693D01*
X1429277Y870091D01*
X1429246Y870178D01*
G02X1429174Y870606I1225J426D01*
G37*
G36*
G01X1436574D02*
G02X1439168I1297J0D01*
G02X1438113Y869331I-1298J0D01*
G01X1438023Y869314D01*
X1437215Y867915D01*
X1437245Y867828D01*
G02X1437318Y867401I-1225J-429D01*
G02X1434722I-1298J0D01*
G02X1435780Y868676I1297J0D01*
G01X1435870Y868693D01*
X1436677Y870091D01*
X1436646Y870178D01*
G02X1436574Y870606I1225J426D01*
G37*
G36*
G01X1443974D02*
G02X1446568I1297J0D01*
G02X1445513Y869331I-1298J0D01*
G01X1445423Y869314D01*
X1444615Y867915D01*
X1444645Y867828D01*
G02X1444718Y867401I-1225J-429D01*
G02X1442122I-1298J0D01*
G02X1443180Y868676I1297J0D01*
G01X1443270Y868693D01*
X1444077Y870091D01*
X1444046Y870178D01*
G02X1443974Y870606I1225J426D01*
G37*
G36*
G01X1451374D02*
G02X1453968I1297J0D01*
G02X1452913Y869331I-1298J0D01*
G01X1452823Y869314D01*
X1452015Y867915D01*
X1452045Y867828D01*
G02X1452118Y867401I-1225J-429D01*
G02X1449522I-1298J0D01*
G02X1450580Y868676I1297J0D01*
G01X1450670Y868693D01*
X1451477Y870091D01*
X1451446Y870178D01*
G02X1451374Y870606I1225J426D01*
G37*
G36*
G01X1458774D02*
G02X1461368I1297J0D01*
G02X1460313Y869331I-1298J0D01*
G01X1460223Y869314D01*
X1459415Y867915D01*
X1459445Y867828D01*
G02X1459518Y867401I-1225J-429D01*
G02X1456922I-1298J0D01*
G02X1457980Y868676I1297J0D01*
G01X1458070Y868693D01*
X1458877Y870091D01*
X1458846Y870178D01*
G02X1458774Y870606I1225J426D01*
G37*
G36*
G01X1466174D02*
G02X1468768I1297J0D01*
G02X1467713Y869331I-1298J0D01*
G01X1467623Y869314D01*
X1466815Y867915D01*
X1466845Y867828D01*
G02X1466918Y867401I-1225J-429D01*
G02X1464322I-1298J0D01*
G02X1465380Y868676I1297J0D01*
G01X1465470Y868693D01*
X1466277Y870091D01*
X1466246Y870178D01*
G02X1466174Y870606I1225J426D01*
G37*
G36*
G01X1473574D02*
G02X1476168I1297J0D01*
G02X1475113Y869331I-1298J0D01*
G01X1475023Y869314D01*
X1474215Y867915D01*
X1474245Y867828D01*
G02X1474318Y867401I-1225J-429D01*
G02X1471722I-1298J0D01*
G02X1472780Y868676I1297J0D01*
G01X1472870Y868693D01*
X1473677Y870091D01*
X1473646Y870178D01*
G02X1473574Y870606I1225J426D01*
G37*
G36*
G01X1480974D02*
G02X1483568I1297J0D01*
G02X1482513Y869331I-1298J0D01*
G01X1482423Y869314D01*
X1481615Y867915D01*
X1481645Y867828D01*
G02X1481718Y867401I-1225J-429D01*
G02X1479122I-1298J0D01*
G02X1480180Y868676I1297J0D01*
G01X1480270Y868693D01*
X1481077Y870091D01*
X1481046Y870178D01*
G02X1480974Y870606I1225J426D01*
G37*
G36*
G01X1488374D02*
G02X1490968I1297J0D01*
G02X1489913Y869331I-1298J0D01*
G01X1489823Y869314D01*
X1489015Y867915D01*
X1489045Y867828D01*
G02X1489118Y867401I-1225J-429D01*
G02X1486522I-1298J0D01*
G02X1487580Y868676I1297J0D01*
G01X1487670Y868693D01*
X1488477Y870091D01*
X1488446Y870178D01*
G02X1488374Y870606I1225J426D01*
G37*
G36*
G01X1495774D02*
G02X1498368I1297J0D01*
G02X1497313Y869331I-1298J0D01*
G01X1497223Y869314D01*
X1496415Y867915D01*
X1496445Y867828D01*
G02X1496518Y867401I-1225J-429D01*
G02X1493922I-1298J0D01*
G02X1494980Y868676I1297J0D01*
G01X1495070Y868693D01*
X1495877Y870091D01*
X1495846Y870178D01*
G02X1495774Y870606I1225J426D01*
G37*
G36*
G01X1503174D02*
G02X1505768I1297J0D01*
G02X1504713Y869331I-1298J0D01*
G01X1504623Y869314D01*
X1503816Y867916D01*
X1503846Y867829D01*
G02X1503918Y867401I-1225J-426D01*
G02X1501324I-1297J0D01*
G02X1502380Y868676I1298J0D01*
G01X1502470Y868693D01*
X1503277Y870091D01*
X1503246Y870178D01*
G02X1503174Y870606I1225J426D01*
G37*
G36*
G01X351280Y873810D02*
G02X353876I1298J0D01*
G02X352820Y872535I-1298J0D01*
G01X352730Y872518D01*
X351923Y871121D01*
X351954Y871034D01*
G02X352026Y870606I-1225J-426D01*
G02X349432I-1297J0D01*
G02X350487Y871881I1298J0D01*
G01X350577Y871898D01*
X351384Y873295D01*
X351353Y873382D01*
G02X351280Y873810I1225J429D01*
G37*
G36*
G01X358680D02*
G02X361276I1298J0D01*
G02X360220Y872535I-1298J0D01*
G01X360130Y872518D01*
X359323Y871121D01*
X359354Y871034D01*
G02X359426Y870606I-1225J-426D01*
G02X356832I-1297J0D01*
G02X357887Y871881I1298J0D01*
G01X357977Y871898D01*
X358784Y873295D01*
X358753Y873382D01*
G02X358680Y873810I1225J429D01*
G37*
G36*
G01X366080D02*
G02X368676I1298J0D01*
G02X367620Y872535I-1298J0D01*
G01X367530Y872518D01*
X366723Y871121D01*
X366754Y871034D01*
G02X366826Y870606I-1225J-426D01*
G02X364232I-1297J0D01*
G02X365287Y871881I1298J0D01*
G01X365377Y871898D01*
X366184Y873295D01*
X366153Y873382D01*
G02X366080Y873810I1225J429D01*
G37*
G36*
G01X373480D02*
G02X376076I1298J0D01*
G02X375020Y872535I-1298J0D01*
G01X374930Y872518D01*
X374123Y871121D01*
X374154Y871034D01*
G02X374226Y870606I-1225J-426D01*
G02X371632I-1297J0D01*
G02X372687Y871881I1298J0D01*
G01X372777Y871898D01*
X373584Y873295D01*
X373553Y873382D01*
G02X373480Y873810I1225J429D01*
G37*
G36*
G01X380880D02*
G02X383476I1298J0D01*
G02X382420Y872535I-1298J0D01*
G01X382330Y872518D01*
X381523Y871121D01*
X381554Y871034D01*
G02X381626Y870606I-1225J-426D01*
G02X379032I-1297J0D01*
G02X380087Y871881I1298J0D01*
G01X380177Y871898D01*
X380984Y873295D01*
X380953Y873382D01*
G02X380880Y873810I1225J429D01*
G37*
G36*
G01X388280D02*
G02X390876I1298J0D01*
G02X389820Y872535I-1298J0D01*
G01X389730Y872518D01*
X388923Y871121D01*
X388954Y871034D01*
G02X389026Y870606I-1225J-426D01*
G02X386432I-1297J0D01*
G02X387487Y871881I1298J0D01*
G01X387577Y871898D01*
X388384Y873295D01*
X388353Y873382D01*
G02X388280Y873810I1225J429D01*
G37*
G36*
G01X395680D02*
G02X398276I1298J0D01*
G02X397220Y872535I-1298J0D01*
G01X397130Y872518D01*
X396323Y871121D01*
X396354Y871034D01*
G02X396426Y870606I-1225J-426D01*
G02X393832I-1297J0D01*
G02X394887Y871881I1298J0D01*
G01X394977Y871898D01*
X395784Y873295D01*
X395753Y873382D01*
G02X395680Y873810I1225J429D01*
G37*
G36*
G01X403080D02*
G02X405676I1298J0D01*
G02X404620Y872535I-1298J0D01*
G01X404530Y872518D01*
X403723Y871121D01*
X403754Y871034D01*
G02X403826Y870606I-1225J-426D01*
G02X401232I-1297J0D01*
G02X402287Y871881I1298J0D01*
G01X402377Y871898D01*
X403184Y873295D01*
X403153Y873382D01*
G02X403080Y873810I1225J429D01*
G37*
G36*
G01X410480D02*
G02X413076I1298J0D01*
G02X413003Y873381I-1297J0D01*
G01X412972Y873295D01*
X413778Y871898D01*
X413868Y871881D01*
G02X414926Y870606I-239J-1275D01*
G02X412332I-1297J0D01*
G02X412403Y871032I1297J3D01*
G01X412434Y871119D01*
X411626Y872518D01*
X411536Y872535D01*
G02X410480Y873810I242J1275D01*
G37*
G36*
G01X417880D02*
G02X420476I1298J0D01*
G02X420403Y873381I-1297J0D01*
G01X420372Y873295D01*
X421178Y871898D01*
X421268Y871881D01*
G02X422326Y870606I-239J-1275D01*
G02X419732I-1297J0D01*
G02X419803Y871032I1297J3D01*
G01X419834Y871119D01*
X419026Y872518D01*
X418936Y872535D01*
G02X417880Y873810I242J1275D01*
G37*
G36*
G01X425280D02*
G02X427876I1298J0D01*
G02X427803Y873381I-1297J0D01*
G01X427772Y873295D01*
X428578Y871898D01*
X428668Y871881D01*
G02X429726Y870606I-239J-1275D01*
G02X427132I-1297J0D01*
G02X427203Y871032I1297J3D01*
G01X427234Y871119D01*
X426426Y872518D01*
X426336Y872535D01*
G02X425280Y873810I242J1275D01*
G37*
G36*
G01X432682D02*
G02X435276I1297J0D01*
G02X435204Y873381I-1297J-3D01*
G01X435173Y873295D01*
X435979Y871898D01*
X436069Y871881D01*
G02X437126Y870606I-240J-1275D01*
G02X434532I-1297J0D01*
G01Y870608D01*
G02X434604Y871033I1297J-1D01*
G01X434634Y871120D01*
X433827Y872518D01*
X433737Y872535D01*
G02X432682Y873810I243J1275D01*
G37*
G36*
G01X440080D02*
G02X442676I1298J0D01*
G02X442603Y873381I-1297J0D01*
G01X442572Y873295D01*
X443378Y871898D01*
X443468Y871881D01*
G02X444526Y870606I-239J-1275D01*
G02X441932I-1297J0D01*
G02X442003Y871032I1297J3D01*
G01X442034Y871119D01*
X441226Y872518D01*
X441136Y872535D01*
G02X440080Y873810I242J1275D01*
G37*
G36*
G01X447482D02*
G02X450076I1297J0D01*
G02X450004Y873381I-1297J-3D01*
G01X449973Y873295D01*
X450779Y871898D01*
X450869Y871881D01*
G02X451926Y870606I-240J-1275D01*
G02X449332I-1297J0D01*
G01Y870608D01*
G02X449404Y871033I1297J-1D01*
G01X449434Y871120D01*
X448627Y872518D01*
X448537Y872535D01*
G02X447482Y873810I243J1275D01*
G37*
G36*
G01X454880D02*
G02X457476I1298J0D01*
G02X457403Y873381I-1297J0D01*
G01X457372Y873295D01*
X458178Y871898D01*
X458268Y871881D01*
G02X459326Y870606I-239J-1275D01*
G02X456732I-1297J0D01*
G02X456803Y871032I1297J3D01*
G01X456834Y871119D01*
X456026Y872518D01*
X455936Y872535D01*
G02X454880Y873810I242J1275D01*
G37*
G36*
G01X462280D02*
G02X464876I1298J0D01*
G02X464803Y873381I-1297J0D01*
G01X464772Y873295D01*
X465578Y871898D01*
X465668Y871881D01*
G02X466726Y870606I-239J-1275D01*
G02X464132I-1297J0D01*
G02X464203Y871032I1297J3D01*
G01X464234Y871119D01*
X463426Y872518D01*
X463336Y872535D01*
G02X462280Y873810I242J1275D01*
G37*
G36*
G01X477080D02*
G02X479676I1298J0D01*
G02X479603Y873381I-1297J0D01*
G01X479572Y873295D01*
X480378Y871898D01*
X480468Y871881D01*
G02X481526Y870606I-239J-1275D01*
G02X478932I-1297J0D01*
G02X479003Y871032I1297J3D01*
G01X479034Y871119D01*
X478226Y872518D01*
X478136Y872535D01*
G02X477080Y873810I242J1275D01*
G37*
G36*
G01X484480D02*
G02X487076I1298J0D01*
G02X487003Y873381I-1297J0D01*
G01X486972Y873295D01*
X487778Y871898D01*
X487868Y871881D01*
G02X488926Y870606I-239J-1275D01*
G02X486332I-1297J0D01*
G02X486403Y871032I1297J3D01*
G01X486434Y871119D01*
X485626Y872518D01*
X485536Y872535D01*
G02X484480Y873810I242J1275D01*
G37*
G36*
G01X491880D02*
G02X494476I1298J0D01*
G02X494403Y873381I-1297J0D01*
G01X494372Y873295D01*
X495178Y871898D01*
X495268Y871881D01*
G02X496326Y870606I-239J-1275D01*
G02X493732I-1297J0D01*
G02X493803Y871032I1297J3D01*
G01X493834Y871119D01*
X493026Y872518D01*
X492936Y872535D01*
G02X491880Y873810I242J1275D01*
G37*
G36*
G01X499280D02*
G02X501876I1298J0D01*
G02X501803Y873381I-1297J0D01*
G01X501772Y873295D01*
X502578Y871898D01*
X502668Y871881D01*
G02X503726Y870606I-239J-1275D01*
G02X501132I-1297J0D01*
G02X501203Y871032I1297J3D01*
G01X501234Y871119D01*
X500426Y872518D01*
X500336Y872535D01*
G02X499280Y873810I242J1275D01*
G37*
G36*
G01X506680D02*
G02X509276I1298J0D01*
G02X509203Y873381I-1297J0D01*
G01X509172Y873295D01*
X509978Y871898D01*
X510068Y871881D01*
G02X511126Y870606I-239J-1275D01*
G02X508532I-1297J0D01*
G02X508603Y871032I1297J3D01*
G01X508634Y871119D01*
X507826Y872518D01*
X507736Y872535D01*
G02X506680Y873810I242J1275D01*
G37*
G36*
G01X514080D02*
G02X516676I1298J0D01*
G02X516603Y873381I-1297J0D01*
G01X516572Y873295D01*
X517378Y871898D01*
X517468Y871881D01*
G02X518526Y870606I-239J-1275D01*
G02X515932I-1297J0D01*
G02X516003Y871032I1297J3D01*
G01X516034Y871119D01*
X515226Y872518D01*
X515136Y872535D01*
G02X514080Y873810I242J1275D01*
G37*
G36*
G01X1327422D02*
G02X1330018I1298J0D01*
G02X1328962Y872535I-1298J0D01*
G01X1328872Y872518D01*
X1328065Y871121D01*
X1328096Y871034D01*
G02X1328168Y870606I-1225J-426D01*
G02X1325574I-1297J0D01*
G02X1326629Y871881I1298J0D01*
G01X1326719Y871898D01*
X1327526Y873295D01*
X1327495Y873382D01*
G02X1327422Y873810I1225J429D01*
G37*
G36*
G01X1334822D02*
G02X1337418I1298J0D01*
G02X1336362Y872535I-1298J0D01*
G01X1336272Y872518D01*
X1335465Y871121D01*
X1335496Y871034D01*
G02X1335568Y870606I-1225J-426D01*
G02X1332974I-1297J0D01*
G02X1334029Y871881I1298J0D01*
G01X1334119Y871898D01*
X1334926Y873295D01*
X1334895Y873382D01*
G02X1334822Y873810I1225J429D01*
G37*
G36*
G01X1342222D02*
G02X1344818I1298J0D01*
G02X1343762Y872535I-1298J0D01*
G01X1343672Y872518D01*
X1342865Y871121D01*
X1342896Y871034D01*
G02X1342968Y870606I-1225J-426D01*
G02X1340374I-1297J0D01*
G02X1341429Y871881I1298J0D01*
G01X1341519Y871898D01*
X1342326Y873295D01*
X1342295Y873382D01*
G02X1342222Y873810I1225J429D01*
G37*
G36*
G01X1349622D02*
G02X1352218I1298J0D01*
G02X1351162Y872535I-1298J0D01*
G01X1351072Y872518D01*
X1350265Y871121D01*
X1350296Y871034D01*
G02X1350368Y870606I-1225J-426D01*
G02X1347774I-1297J0D01*
G02X1348829Y871881I1298J0D01*
G01X1348919Y871898D01*
X1349726Y873295D01*
X1349695Y873382D01*
G02X1349622Y873810I1225J429D01*
G37*
G36*
G01X1357022D02*
G02X1359618I1298J0D01*
G02X1358562Y872535I-1298J0D01*
G01X1358472Y872518D01*
X1357665Y871121D01*
X1357696Y871034D01*
G02X1357768Y870606I-1225J-426D01*
G02X1355174I-1297J0D01*
G02X1356229Y871881I1298J0D01*
G01X1356319Y871898D01*
X1357126Y873295D01*
X1357095Y873382D01*
G02X1357022Y873810I1225J429D01*
G37*
G36*
G01X1364422D02*
G02X1367018I1298J0D01*
G02X1365962Y872535I-1298J0D01*
G01X1365872Y872518D01*
X1365065Y871121D01*
X1365096Y871034D01*
G02X1365168Y870606I-1225J-426D01*
G02X1362574I-1297J0D01*
G02X1363629Y871881I1298J0D01*
G01X1363719Y871898D01*
X1364526Y873295D01*
X1364495Y873382D01*
G02X1364422Y873810I1225J429D01*
G37*
G36*
G01X1371822D02*
G02X1374418I1298J0D01*
G02X1373362Y872535I-1298J0D01*
G01X1373272Y872518D01*
X1372465Y871121D01*
X1372496Y871034D01*
G02X1372568Y870606I-1225J-426D01*
G02X1369974I-1297J0D01*
G02X1371029Y871881I1298J0D01*
G01X1371119Y871898D01*
X1371926Y873295D01*
X1371895Y873382D01*
G02X1371822Y873810I1225J429D01*
G37*
G36*
G01X1379222D02*
G02X1381818I1298J0D01*
G02X1380762Y872535I-1298J0D01*
G01X1380672Y872518D01*
X1379865Y871121D01*
X1379896Y871034D01*
G02X1379968Y870606I-1225J-426D01*
G02X1377374I-1297J0D01*
G02X1378429Y871881I1298J0D01*
G01X1378519Y871898D01*
X1379326Y873295D01*
X1379295Y873382D01*
G02X1379222Y873810I1225J429D01*
G37*
G36*
G01X1386622D02*
G02X1389218I1298J0D01*
G02X1389145Y873381I-1297J0D01*
G01X1389114Y873295D01*
X1389920Y871898D01*
X1390010Y871881D01*
G02X1391068Y870606I-239J-1275D01*
G02X1388474I-1297J0D01*
G02X1388545Y871032I1297J3D01*
G01X1388576Y871119D01*
X1387768Y872518D01*
X1387678Y872535D01*
G02X1386622Y873810I242J1275D01*
G37*
G36*
G01X1394022D02*
G02X1396618I1298J0D01*
G02X1396545Y873381I-1297J0D01*
G01X1396514Y873295D01*
X1397320Y871898D01*
X1397410Y871881D01*
G02X1398468Y870606I-239J-1275D01*
G02X1395874I-1297J0D01*
G02X1395945Y871032I1297J3D01*
G01X1395976Y871119D01*
X1395168Y872518D01*
X1395078Y872535D01*
G02X1394022Y873810I242J1275D01*
G37*
G36*
G01X1401422D02*
G02X1404018I1298J0D01*
G02X1403945Y873381I-1297J0D01*
G01X1403914Y873295D01*
X1404720Y871898D01*
X1404810Y871881D01*
G02X1405868Y870606I-239J-1275D01*
G02X1403274I-1297J0D01*
G02X1403345Y871032I1297J3D01*
G01X1403376Y871119D01*
X1402568Y872518D01*
X1402478Y872535D01*
G02X1401422Y873810I242J1275D01*
G37*
G36*
G01X1408824D02*
G02X1411418I1297J0D01*
G02X1411346Y873381I-1297J-3D01*
G01X1411315Y873295D01*
X1412121Y871898D01*
X1412211Y871881D01*
G02X1413268Y870606I-240J-1275D01*
G02X1410674I-1297J0D01*
G01Y870608D01*
G02X1410746Y871033I1297J-1D01*
G01X1410776Y871120D01*
X1409969Y872518D01*
X1409879Y872535D01*
G02X1408824Y873810I243J1275D01*
G37*
G36*
G01X1416222D02*
G02X1418818I1298J0D01*
G02X1418745Y873381I-1297J0D01*
G01X1418714Y873295D01*
X1419520Y871898D01*
X1419610Y871881D01*
G02X1420668Y870606I-239J-1275D01*
G02X1418074I-1297J0D01*
G02X1418145Y871032I1297J3D01*
G01X1418176Y871119D01*
X1417368Y872518D01*
X1417278Y872535D01*
G02X1416222Y873810I242J1275D01*
G37*
G36*
G01X1423624D02*
G02X1426218I1297J0D01*
G02X1426146Y873381I-1297J-3D01*
G01X1426115Y873295D01*
X1426921Y871898D01*
X1427011Y871881D01*
G02X1428068Y870606I-240J-1275D01*
G02X1425474I-1297J0D01*
G01Y870608D01*
G02X1425546Y871033I1297J-1D01*
G01X1425576Y871120D01*
X1424769Y872518D01*
X1424679Y872535D01*
G02X1423624Y873810I243J1275D01*
G37*
G36*
G01X1431022D02*
G02X1433618I1298J0D01*
G02X1433545Y873381I-1297J0D01*
G01X1433514Y873295D01*
X1434320Y871898D01*
X1434410Y871881D01*
G02X1435468Y870606I-239J-1275D01*
G02X1432874I-1297J0D01*
G02X1432945Y871032I1297J3D01*
G01X1432976Y871119D01*
X1432168Y872518D01*
X1432078Y872535D01*
G02X1431022Y873810I242J1275D01*
G37*
G36*
G01X1438422D02*
G02X1441018I1298J0D01*
G02X1440945Y873381I-1297J0D01*
G01X1440914Y873295D01*
X1441720Y871898D01*
X1441810Y871881D01*
G02X1442868Y870606I-239J-1275D01*
G02X1440274I-1297J0D01*
G02X1440345Y871032I1297J3D01*
G01X1440376Y871119D01*
X1439568Y872518D01*
X1439478Y872535D01*
G02X1438422Y873810I242J1275D01*
G37*
G36*
G01X1453222D02*
G02X1455818I1298J0D01*
G02X1455745Y873381I-1297J0D01*
G01X1455714Y873295D01*
X1456520Y871898D01*
X1456610Y871881D01*
G02X1457668Y870606I-239J-1275D01*
G02X1455074I-1297J0D01*
G02X1455145Y871032I1297J3D01*
G01X1455176Y871119D01*
X1454368Y872518D01*
X1454278Y872535D01*
G02X1453222Y873810I242J1275D01*
G37*
G36*
G01X1460622D02*
G02X1463218I1298J0D01*
G02X1463145Y873381I-1297J0D01*
G01X1463114Y873295D01*
X1463920Y871898D01*
X1464010Y871881D01*
G02X1465068Y870606I-239J-1275D01*
G02X1462474I-1297J0D01*
G02X1462545Y871032I1297J3D01*
G01X1462576Y871119D01*
X1461768Y872518D01*
X1461678Y872535D01*
G02X1460622Y873810I242J1275D01*
G37*
G36*
G01X1468022D02*
G02X1470618I1298J0D01*
G02X1470545Y873381I-1297J0D01*
G01X1470514Y873295D01*
X1471320Y871898D01*
X1471410Y871881D01*
G02X1472468Y870606I-239J-1275D01*
G02X1469874I-1297J0D01*
G02X1469945Y871032I1297J3D01*
G01X1469976Y871119D01*
X1469168Y872518D01*
X1469078Y872535D01*
G02X1468022Y873810I242J1275D01*
G37*
G36*
G01X1475422D02*
G02X1478018I1298J0D01*
G02X1477945Y873381I-1297J0D01*
G01X1477914Y873295D01*
X1478720Y871898D01*
X1478810Y871881D01*
G02X1479868Y870606I-239J-1275D01*
G02X1477274I-1297J0D01*
G02X1477345Y871032I1297J3D01*
G01X1477376Y871119D01*
X1476568Y872518D01*
X1476478Y872535D01*
G02X1475422Y873810I242J1275D01*
G37*
G36*
G01X1482822D02*
G02X1485418I1298J0D01*
G02X1485345Y873381I-1297J0D01*
G01X1485314Y873295D01*
X1486120Y871898D01*
X1486210Y871881D01*
G02X1487268Y870606I-239J-1275D01*
G02X1484674I-1297J0D01*
G02X1484745Y871032I1297J3D01*
G01X1484776Y871119D01*
X1483968Y872518D01*
X1483878Y872535D01*
G02X1482822Y873810I242J1275D01*
G37*
G36*
G01X1490222D02*
G02X1492818I1298J0D01*
G02X1492745Y873381I-1297J0D01*
G01X1492714Y873295D01*
X1493520Y871898D01*
X1493610Y871881D01*
G02X1494668Y870606I-239J-1275D01*
G02X1492074I-1297J0D01*
G02X1492145Y871032I1297J3D01*
G01X1492176Y871119D01*
X1491368Y872518D01*
X1491278Y872535D01*
G02X1490222Y873810I242J1275D01*
G37*
G36*
G01X367932Y883423D02*
G02X370526I1297J0D01*
G02X370454Y882994I-1297J-3D01*
G01X370423Y882908D01*
X371229Y881511D01*
X371319Y881494D01*
G02X372376Y880219I-240J-1275D01*
G02X369780I-1298J0D01*
G02X369853Y880647I1298J-1D01*
G01X369883Y880734D01*
X369077Y882131D01*
X368987Y882148D01*
G02X367932Y883423I243J1275D01*
G37*
G36*
G01X375332D02*
G02X377926I1297J0D01*
G02X377854Y882994I-1297J-3D01*
G01X377823Y882908D01*
X378629Y881511D01*
X378719Y881494D01*
G02X379776Y880219I-240J-1275D01*
G02X377180I-1298J0D01*
G02X377253Y880647I1298J-1D01*
G01X377283Y880734D01*
X376477Y882131D01*
X376387Y882148D01*
G02X375332Y883423I243J1275D01*
G37*
G36*
G01X382732D02*
G02X385326I1297J0D01*
G02X385254Y882994I-1297J-3D01*
G01X385223Y882908D01*
X386029Y881511D01*
X386119Y881494D01*
G02X387176Y880219I-240J-1275D01*
G02X384580I-1298J0D01*
G02X384653Y880647I1298J-1D01*
G01X384683Y880734D01*
X383877Y882131D01*
X383787Y882148D01*
G02X382732Y883423I243J1275D01*
G37*
G36*
G01X390132D02*
G02X392726I1297J0D01*
G02X392654Y882994I-1297J-3D01*
G01X392623Y882908D01*
X393429Y881511D01*
X393519Y881494D01*
G02X394576Y880219I-240J-1275D01*
G02X391980I-1298J0D01*
G02X392053Y880647I1298J-1D01*
G01X392083Y880734D01*
X391277Y882131D01*
X391187Y882148D01*
G02X390132Y883423I243J1275D01*
G37*
G36*
G01X397532D02*
G02X400126I1297J0D01*
G02X400054Y882994I-1297J-3D01*
G01X400023Y882908D01*
X400829Y881511D01*
X400919Y881494D01*
G02X401976Y880219I-240J-1275D01*
G02X399380I-1298J0D01*
G02X399453Y880647I1298J-1D01*
G01X399483Y880734D01*
X398677Y882131D01*
X398587Y882148D01*
G02X397532Y883423I243J1275D01*
G37*
G36*
G01X404932D02*
G02X407526I1297J0D01*
G02X407454Y882994I-1297J-3D01*
G01X407423Y882908D01*
X408229Y881511D01*
X408319Y881494D01*
G02X409376Y880219I-240J-1275D01*
G02X406780I-1298J0D01*
G02X406853Y880647I1298J-1D01*
G01X406883Y880734D01*
X406077Y882131D01*
X405987Y882148D01*
G02X404932Y883423I243J1275D01*
G37*
G36*
G01X412332D02*
G02X414926I1297J0D01*
G02X414854Y882994I-1297J-3D01*
G01X414823Y882908D01*
X415629Y881511D01*
X415719Y881494D01*
G02X416776Y880219I-240J-1275D01*
G02X414180I-1298J0D01*
G02X414253Y880647I1298J-1D01*
G01X414283Y880734D01*
X413477Y882131D01*
X413387Y882148D01*
G02X412332Y883423I243J1275D01*
G37*
G36*
G01X419732D02*
G02X422326I1297J0D01*
G02X422254Y882994I-1297J-3D01*
G01X422223Y882908D01*
X423029Y881511D01*
X423119Y881494D01*
G02X424176Y880219I-240J-1275D01*
G02X421580I-1298J0D01*
G02X421653Y880647I1298J-1D01*
G01X421683Y880734D01*
X420877Y882131D01*
X420787Y882148D01*
G02X419732Y883423I243J1275D01*
G37*
G36*
G01X427132D02*
G02X429726I1297J0D01*
G02X429654Y882994I-1297J-3D01*
G01X429623Y882908D01*
X430429Y881511D01*
X430519Y881494D01*
G02X431576Y880219I-240J-1275D01*
G02X428980I-1298J0D01*
G02X429053Y880647I1298J-1D01*
G01X429083Y880734D01*
X428277Y882131D01*
X428187Y882148D01*
G02X427132Y883423I243J1275D01*
G37*
G36*
G01X434532D02*
G02X437126I1297J0D01*
G02X437054Y882994I-1297J-3D01*
G01X437023Y882908D01*
X437829Y881511D01*
X437919Y881494D01*
G02X438976Y880219I-240J-1275D01*
G02X436380I-1298J0D01*
G02X436453Y880647I1298J-1D01*
G01X436483Y880734D01*
X435677Y882131D01*
X435587Y882148D01*
G02X434532Y883423I243J1275D01*
G37*
G36*
G01X441932D02*
G02X444526I1297J0D01*
G02X444454Y882994I-1297J-3D01*
G01X444423Y882908D01*
X445229Y881511D01*
X445319Y881494D01*
G02X446376Y880219I-240J-1275D01*
G02X443780I-1298J0D01*
G02X443853Y880647I1298J-1D01*
G01X443883Y880734D01*
X443077Y882131D01*
X442987Y882148D01*
G02X441932Y883423I243J1275D01*
G37*
G36*
G01X449332D02*
G02X451926I1297J0D01*
G02X451854Y882994I-1297J-3D01*
G01X451823Y882908D01*
X452629Y881511D01*
X452719Y881494D01*
G02X453776Y880219I-240J-1275D01*
G02X451182I-1297J0D01*
G01Y880221D01*
G02X451254Y880646I1297J-1D01*
G01X451284Y880733D01*
X450477Y882131D01*
X450387Y882148D01*
G02X449332Y883423I243J1275D01*
G37*
G36*
G01X456732D02*
G02X459326I1297J0D01*
G02X459254Y882994I-1297J-3D01*
G01X459223Y882908D01*
X460029Y881511D01*
X460119Y881494D01*
G02X461176Y880219I-240J-1275D01*
G02X458580I-1298J0D01*
G02X458653Y880647I1298J-1D01*
G01X458683Y880734D01*
X457877Y882131D01*
X457787Y882148D01*
G02X456732Y883423I243J1275D01*
G37*
G36*
G01X464132D02*
G02X466726I1297J0D01*
G02X466654Y882994I-1297J-3D01*
G01X466623Y882908D01*
X467429Y881511D01*
X467519Y881494D01*
G02X468576Y880219I-240J-1275D01*
G02X465980I-1298J0D01*
G02X466053Y880647I1298J-1D01*
G01X466083Y880734D01*
X465277Y882131D01*
X465187Y882148D01*
G02X464132Y883423I243J1275D01*
G37*
G36*
G01X471532D02*
G02X474126I1297J0D01*
G02X474054Y882994I-1297J-3D01*
G01X474023Y882908D01*
X474829Y881511D01*
X474919Y881494D01*
G02X475976Y880219I-240J-1275D01*
G02X473380I-1298J0D01*
G02X473453Y880647I1298J-1D01*
G01X473483Y880734D01*
X472677Y882131D01*
X472587Y882148D01*
G02X471532Y883423I243J1275D01*
G37*
G36*
G01X478932D02*
G02X481526I1297J0D01*
G02X481454Y882994I-1297J-3D01*
G01X481423Y882908D01*
X482229Y881511D01*
X482319Y881494D01*
G02X483376Y880219I-240J-1275D01*
G02X480780I-1298J0D01*
G02X480853Y880647I1298J-1D01*
G01X480883Y880734D01*
X480077Y882131D01*
X479987Y882148D01*
G02X478932Y883423I243J1275D01*
G37*
G36*
G01X486332D02*
G02X488926I1297J0D01*
G02X488854Y882994I-1297J-3D01*
G01X488823Y882908D01*
X489629Y881511D01*
X489719Y881494D01*
G02X490776Y880219I-240J-1275D01*
G02X488180I-1298J0D01*
G02X488253Y880647I1298J-1D01*
G01X488283Y880734D01*
X487477Y882131D01*
X487387Y882148D01*
G02X486332Y883423I243J1275D01*
G37*
G36*
G01X493732D02*
G02X496326I1297J0D01*
G02X496254Y882994I-1297J-3D01*
G01X496223Y882908D01*
X497029Y881511D01*
X497119Y881494D01*
G02X498176Y880219I-240J-1275D01*
G02X495580I-1298J0D01*
G02X495653Y880647I1298J-1D01*
G01X495683Y880734D01*
X494877Y882131D01*
X494787Y882148D01*
G02X493732Y883423I243J1275D01*
G37*
G36*
G01X501132D02*
G02X503726I1297J0D01*
G02X503654Y882994I-1297J-3D01*
G01X503623Y882908D01*
X504429Y881511D01*
X504519Y881494D01*
G02X505576Y880219I-240J-1275D01*
G02X502980I-1298J0D01*
G02X503053Y880647I1298J-1D01*
G01X503083Y880734D01*
X502277Y882131D01*
X502187Y882148D01*
G02X501132Y883423I243J1275D01*
G37*
G36*
G01X508532D02*
G02X511126I1297J0D01*
G02X511054Y882994I-1297J-3D01*
G01X511023Y882908D01*
X511829Y881511D01*
X511919Y881494D01*
G02X512976Y880219I-240J-1275D01*
G02X510380I-1298J0D01*
G02X510453Y880647I1298J-1D01*
G01X510483Y880734D01*
X509677Y882131D01*
X509587Y882148D01*
G02X508532Y883423I243J1275D01*
G37*
G36*
G01X1344074D02*
G02X1346668I1297J0D01*
G02X1346596Y882994I-1297J-3D01*
G01X1346565Y882908D01*
X1347371Y881511D01*
X1347461Y881494D01*
G02X1348518Y880219I-240J-1275D01*
G02X1345922I-1298J0D01*
G02X1345995Y880647I1298J-1D01*
G01X1346025Y880734D01*
X1345219Y882131D01*
X1345129Y882148D01*
G02X1344074Y883423I243J1275D01*
G37*
G36*
G01X1351474D02*
G02X1354068I1297J0D01*
G02X1353996Y882994I-1297J-3D01*
G01X1353965Y882908D01*
X1354771Y881511D01*
X1354861Y881494D01*
G02X1355918Y880219I-240J-1275D01*
G02X1353322I-1298J0D01*
G02X1353395Y880647I1298J-1D01*
G01X1353425Y880734D01*
X1352619Y882131D01*
X1352529Y882148D01*
G02X1351474Y883423I243J1275D01*
G37*
G36*
G01X1358874D02*
G02X1361468I1297J0D01*
G02X1361396Y882994I-1297J-3D01*
G01X1361365Y882908D01*
X1362171Y881511D01*
X1362261Y881494D01*
G02X1363318Y880219I-240J-1275D01*
G02X1360722I-1298J0D01*
G02X1360795Y880647I1298J-1D01*
G01X1360825Y880734D01*
X1360019Y882131D01*
X1359929Y882148D01*
G02X1358874Y883423I243J1275D01*
G37*
G36*
G01X1366274D02*
G02X1368868I1297J0D01*
G02X1368796Y882994I-1297J-3D01*
G01X1368765Y882908D01*
X1369571Y881511D01*
X1369661Y881494D01*
G02X1370718Y880219I-240J-1275D01*
G02X1368122I-1298J0D01*
G02X1368195Y880647I1298J-1D01*
G01X1368225Y880734D01*
X1367419Y882131D01*
X1367329Y882148D01*
G02X1366274Y883423I243J1275D01*
G37*
G36*
G01X1373674D02*
G02X1376268I1297J0D01*
G02X1376196Y882994I-1297J-3D01*
G01X1376165Y882908D01*
X1376971Y881511D01*
X1377061Y881494D01*
G02X1378118Y880219I-240J-1275D01*
G02X1375522I-1298J0D01*
G02X1375595Y880647I1298J-1D01*
G01X1375625Y880734D01*
X1374819Y882131D01*
X1374729Y882148D01*
G02X1373674Y883423I243J1275D01*
G37*
G36*
G01X1381074D02*
G02X1383668I1297J0D01*
G02X1383596Y882994I-1297J-3D01*
G01X1383565Y882908D01*
X1384371Y881511D01*
X1384461Y881494D01*
G02X1385518Y880219I-240J-1275D01*
G02X1382922I-1298J0D01*
G02X1382995Y880647I1298J-1D01*
G01X1383025Y880734D01*
X1382219Y882131D01*
X1382129Y882148D01*
G02X1381074Y883423I243J1275D01*
G37*
G36*
G01X1388474D02*
G02X1391068I1297J0D01*
G02X1390996Y882994I-1297J-3D01*
G01X1390965Y882908D01*
X1391771Y881511D01*
X1391861Y881494D01*
G02X1392918Y880219I-240J-1275D01*
G02X1390322I-1298J0D01*
G02X1390395Y880647I1298J-1D01*
G01X1390425Y880734D01*
X1389619Y882131D01*
X1389529Y882148D01*
G02X1388474Y883423I243J1275D01*
G37*
G36*
G01X1395874D02*
G02X1398468I1297J0D01*
G02X1398396Y882994I-1297J-3D01*
G01X1398365Y882908D01*
X1399171Y881511D01*
X1399261Y881494D01*
G02X1400318Y880219I-240J-1275D01*
G02X1397722I-1298J0D01*
G02X1397795Y880647I1298J-1D01*
G01X1397825Y880734D01*
X1397019Y882131D01*
X1396929Y882148D01*
G02X1395874Y883423I243J1275D01*
G37*
G36*
G01X1403274D02*
G02X1405868I1297J0D01*
G02X1405796Y882994I-1297J-3D01*
G01X1405765Y882908D01*
X1406571Y881511D01*
X1406661Y881494D01*
G02X1407718Y880219I-240J-1275D01*
G02X1405122I-1298J0D01*
G02X1405195Y880647I1298J-1D01*
G01X1405225Y880734D01*
X1404419Y882131D01*
X1404329Y882148D01*
G02X1403274Y883423I243J1275D01*
G37*
G36*
G01X1410674D02*
G02X1413268I1297J0D01*
G02X1413196Y882994I-1297J-3D01*
G01X1413165Y882908D01*
X1413971Y881511D01*
X1414061Y881494D01*
G02X1415118Y880219I-240J-1275D01*
G02X1412522I-1298J0D01*
G02X1412595Y880647I1298J-1D01*
G01X1412625Y880734D01*
X1411819Y882131D01*
X1411729Y882148D01*
G02X1410674Y883423I243J1275D01*
G37*
G36*
G01X1418074D02*
G02X1420668I1297J0D01*
G02X1420596Y882994I-1297J-3D01*
G01X1420565Y882908D01*
X1421371Y881511D01*
X1421461Y881494D01*
G02X1422518Y880219I-240J-1275D01*
G02X1419922I-1298J0D01*
G02X1419995Y880647I1298J-1D01*
G01X1420025Y880734D01*
X1419219Y882131D01*
X1419129Y882148D01*
G02X1418074Y883423I243J1275D01*
G37*
G36*
G01X1425474D02*
G02X1428068I1297J0D01*
G02X1427996Y882994I-1297J-3D01*
G01X1427965Y882908D01*
X1428771Y881511D01*
X1428861Y881494D01*
G02X1429918Y880219I-240J-1275D01*
G02X1427324I-1297J0D01*
G01Y880221D01*
G02X1427396Y880646I1297J-1D01*
G01X1427426Y880733D01*
X1426619Y882131D01*
X1426529Y882148D01*
G02X1425474Y883423I243J1275D01*
G37*
G36*
G01X1432874D02*
G02X1435468I1297J0D01*
G02X1435396Y882994I-1297J-3D01*
G01X1435365Y882908D01*
X1436171Y881511D01*
X1436261Y881494D01*
G02X1437318Y880219I-240J-1275D01*
G02X1434722I-1298J0D01*
G02X1434795Y880647I1298J-1D01*
G01X1434825Y880734D01*
X1434019Y882131D01*
X1433929Y882148D01*
G02X1432874Y883423I243J1275D01*
G37*
G36*
G01X1440274D02*
G02X1442868I1297J0D01*
G02X1442796Y882994I-1297J-3D01*
G01X1442765Y882908D01*
X1443571Y881511D01*
X1443661Y881494D01*
G02X1444718Y880219I-240J-1275D01*
G02X1442122I-1298J0D01*
G02X1442195Y880647I1298J-1D01*
G01X1442225Y880734D01*
X1441419Y882131D01*
X1441329Y882148D01*
G02X1440274Y883423I243J1275D01*
G37*
G36*
G01X1447674D02*
G02X1450268I1297J0D01*
G02X1450196Y882994I-1297J-3D01*
G01X1450165Y882908D01*
X1450971Y881511D01*
X1451061Y881494D01*
G02X1452118Y880219I-240J-1275D01*
G02X1449522I-1298J0D01*
G02X1449595Y880647I1298J-1D01*
G01X1449625Y880734D01*
X1448819Y882131D01*
X1448729Y882148D01*
G02X1447674Y883423I243J1275D01*
G37*
G36*
G01X1455074D02*
G02X1457668I1297J0D01*
G02X1457596Y882994I-1297J-3D01*
G01X1457565Y882908D01*
X1458371Y881511D01*
X1458461Y881494D01*
G02X1459518Y880219I-240J-1275D01*
G02X1456922I-1298J0D01*
G02X1456995Y880647I1298J-1D01*
G01X1457025Y880734D01*
X1456219Y882131D01*
X1456129Y882148D01*
G02X1455074Y883423I243J1275D01*
G37*
G36*
G01X1462474D02*
G02X1465068I1297J0D01*
G02X1464996Y882994I-1297J-3D01*
G01X1464965Y882908D01*
X1465771Y881511D01*
X1465861Y881494D01*
G02X1466918Y880219I-240J-1275D01*
G02X1464322I-1298J0D01*
G02X1464395Y880647I1298J-1D01*
G01X1464425Y880734D01*
X1463619Y882131D01*
X1463529Y882148D01*
G02X1462474Y883423I243J1275D01*
G37*
G36*
G01X1469874D02*
G02X1472468I1297J0D01*
G02X1472396Y882994I-1297J-3D01*
G01X1472365Y882908D01*
X1473171Y881511D01*
X1473261Y881494D01*
G02X1474318Y880219I-240J-1275D01*
G02X1471722I-1298J0D01*
G02X1471795Y880647I1298J-1D01*
G01X1471825Y880734D01*
X1471019Y882131D01*
X1470929Y882148D01*
G02X1469874Y883423I243J1275D01*
G37*
G36*
G01X1477274D02*
G02X1479868I1297J0D01*
G02X1479796Y882994I-1297J-3D01*
G01X1479765Y882908D01*
X1480571Y881511D01*
X1480661Y881494D01*
G02X1481718Y880219I-240J-1275D01*
G02X1479122I-1298J0D01*
G02X1479195Y880647I1298J-1D01*
G01X1479225Y880734D01*
X1478419Y882131D01*
X1478329Y882148D01*
G02X1477274Y883423I243J1275D01*
G37*
G36*
G01X1484674D02*
G02X1487268I1297J0D01*
G02X1487196Y882994I-1297J-3D01*
G01X1487165Y882908D01*
X1487971Y881511D01*
X1488061Y881494D01*
G02X1489118Y880219I-240J-1275D01*
G02X1486522I-1298J0D01*
G02X1486595Y880647I1298J-1D01*
G01X1486625Y880734D01*
X1485819Y882131D01*
X1485729Y882148D01*
G02X1484674Y883423I243J1275D01*
G37*
G36*
G01X373480Y886627D02*
G02X376076I1298J0D01*
G02X375020Y885352I-1298J0D01*
G01X374930Y885335D01*
X374123Y883938D01*
X374154Y883851D01*
G02X374226Y883423I-1225J-426D01*
G02X371632I-1297J0D01*
G02X372687Y884698I1298J0D01*
G01X372777Y884715D01*
X373584Y886112D01*
X373553Y886199D01*
G02X373480Y886627I1225J429D01*
G37*
G36*
G01X380880D02*
G02X383476I1298J0D01*
G02X382420Y885352I-1298J0D01*
G01X382330Y885335D01*
X381523Y883938D01*
X381554Y883851D01*
G02X381626Y883423I-1225J-426D01*
G02X379032I-1297J0D01*
G02X380087Y884698I1298J0D01*
G01X380177Y884715D01*
X380984Y886112D01*
X380953Y886199D01*
G02X380880Y886627I1225J429D01*
G37*
G36*
G01X388280D02*
G02X390876I1298J0D01*
G02X389820Y885352I-1298J0D01*
G01X389730Y885335D01*
X388923Y883938D01*
X388954Y883851D01*
G02X389026Y883423I-1225J-426D01*
G02X386432I-1297J0D01*
G02X387487Y884698I1298J0D01*
G01X387577Y884715D01*
X388384Y886112D01*
X388353Y886199D01*
G02X388280Y886627I1225J429D01*
G37*
G36*
G01X395680D02*
G02X398276I1298J0D01*
G02X397220Y885352I-1298J0D01*
G01X397130Y885335D01*
X396323Y883938D01*
X396354Y883851D01*
G02X396426Y883423I-1225J-426D01*
G02X393832I-1297J0D01*
G02X394887Y884698I1298J0D01*
G01X394977Y884715D01*
X395784Y886112D01*
X395753Y886199D01*
G02X395680Y886627I1225J429D01*
G37*
G36*
G01X403080D02*
G02X405676I1298J0D01*
G02X404620Y885352I-1298J0D01*
G01X404530Y885335D01*
X403723Y883938D01*
X403754Y883851D01*
G02X403826Y883423I-1225J-426D01*
G02X401232I-1297J0D01*
G02X402287Y884698I1298J0D01*
G01X402377Y884715D01*
X403184Y886112D01*
X403153Y886199D01*
G02X403080Y886627I1225J429D01*
G37*
G36*
G01X410480D02*
G02X413076I1298J0D01*
G02X412020Y885352I-1298J0D01*
G01X411930Y885335D01*
X411123Y883938D01*
X411154Y883851D01*
G02X411226Y883423I-1225J-426D01*
G02X408632I-1297J0D01*
G02X409687Y884698I1298J0D01*
G01X409777Y884715D01*
X410584Y886112D01*
X410553Y886199D01*
G02X410480Y886627I1225J429D01*
G37*
G36*
G01X417880D02*
G02X420476I1298J0D01*
G02X419420Y885352I-1298J0D01*
G01X419330Y885335D01*
X418523Y883938D01*
X418554Y883851D01*
G02X418626Y883423I-1225J-426D01*
G02X416032I-1297J0D01*
G02X417087Y884698I1298J0D01*
G01X417177Y884715D01*
X417984Y886112D01*
X417953Y886199D01*
G02X417880Y886627I1225J429D01*
G37*
G36*
G01X425280D02*
G02X427876I1298J0D01*
G02X426820Y885352I-1298J0D01*
G01X426730Y885335D01*
X425923Y883938D01*
X425954Y883851D01*
G02X426026Y883423I-1225J-426D01*
G02X423432I-1297J0D01*
G02X424487Y884698I1298J0D01*
G01X424577Y884715D01*
X425384Y886112D01*
X425353Y886199D01*
G02X425280Y886627I1225J429D01*
G37*
G36*
G01X432680D02*
G02X435276I1298J0D01*
G02X434220Y885352I-1298J0D01*
G01X434130Y885335D01*
X433323Y883938D01*
X433354Y883851D01*
G02X433426Y883423I-1225J-426D01*
G02X430832I-1297J0D01*
G02X431887Y884698I1298J0D01*
G01X431977Y884715D01*
X432784Y886112D01*
X432753Y886199D01*
G02X432680Y886627I1225J429D01*
G37*
G36*
G01X440080D02*
G02X442676I1298J0D01*
G02X441620Y885352I-1298J0D01*
G01X441530Y885335D01*
X440723Y883938D01*
X440754Y883851D01*
G02X440826Y883423I-1225J-426D01*
G02X438232I-1297J0D01*
G02X439287Y884698I1298J0D01*
G01X439377Y884715D01*
X440184Y886112D01*
X440153Y886199D01*
G02X440080Y886627I1225J429D01*
G37*
G36*
G01X447480D02*
G02X450076I1298J0D01*
G02X449020Y885352I-1298J0D01*
G01X448930Y885335D01*
X448123Y883938D01*
X448154Y883851D01*
G02X448226Y883423I-1225J-426D01*
G02X445632I-1297J0D01*
G02X446687Y884698I1298J0D01*
G01X446777Y884715D01*
X447584Y886112D01*
X447553Y886199D01*
G02X447480Y886627I1225J429D01*
G37*
G36*
G01X454880D02*
G02X457476I1298J0D01*
G02X456420Y885352I-1298J0D01*
G01X456330Y885335D01*
X455523Y883938D01*
X455554Y883851D01*
G02X455626Y883423I-1225J-426D01*
G02X453032I-1297J0D01*
G02X454087Y884698I1298J0D01*
G01X454177Y884715D01*
X454984Y886112D01*
X454953Y886199D01*
G02X454880Y886627I1225J429D01*
G37*
G36*
G01X462280D02*
G02X464876I1298J0D01*
G02X463820Y885352I-1298J0D01*
G01X463730Y885335D01*
X462923Y883938D01*
X462954Y883851D01*
G02X463026Y883423I-1225J-426D01*
G02X460432I-1297J0D01*
G02X461487Y884698I1298J0D01*
G01X461577Y884715D01*
X462384Y886112D01*
X462353Y886199D01*
G02X462280Y886627I1225J429D01*
G37*
G36*
G01X469680D02*
G02X472276I1298J0D01*
G02X471220Y885352I-1298J0D01*
G01X471130Y885335D01*
X470323Y883938D01*
X470354Y883851D01*
G02X470426Y883423I-1225J-426D01*
G02X467832I-1297J0D01*
G02X468887Y884698I1298J0D01*
G01X468977Y884715D01*
X469784Y886112D01*
X469753Y886199D01*
G02X469680Y886627I1225J429D01*
G37*
G36*
G01X477080D02*
G02X479676I1298J0D01*
G02X478620Y885352I-1298J0D01*
G01X478530Y885335D01*
X477723Y883938D01*
X477754Y883851D01*
G02X477826Y883423I-1225J-426D01*
G02X475232I-1297J0D01*
G02X476287Y884698I1298J0D01*
G01X476377Y884715D01*
X477184Y886112D01*
X477153Y886199D01*
G02X477080Y886627I1225J429D01*
G37*
G36*
G01X484480D02*
G02X487076I1298J0D01*
G02X486020Y885352I-1298J0D01*
G01X485930Y885335D01*
X485123Y883938D01*
X485154Y883851D01*
G02X485226Y883423I-1225J-426D01*
G02X482632I-1297J0D01*
G02X483687Y884698I1298J0D01*
G01X483777Y884715D01*
X484584Y886112D01*
X484553Y886199D01*
G02X484480Y886627I1225J429D01*
G37*
G36*
G01X491880D02*
G02X494476I1298J0D01*
G02X493420Y885352I-1298J0D01*
G01X493330Y885335D01*
X492523Y883938D01*
X492554Y883851D01*
G02X492626Y883423I-1225J-426D01*
G02X490032I-1297J0D01*
G02X491087Y884698I1298J0D01*
G01X491177Y884715D01*
X491984Y886112D01*
X491953Y886199D01*
G02X491880Y886627I1225J429D01*
G37*
G36*
G01X499280D02*
G02X501876I1298J0D01*
G02X500820Y885352I-1298J0D01*
G01X500730Y885335D01*
X499923Y883938D01*
X499954Y883851D01*
G02X500026Y883423I-1225J-426D01*
G02X497432I-1297J0D01*
G02X498487Y884698I1298J0D01*
G01X498577Y884715D01*
X499384Y886112D01*
X499353Y886199D01*
G02X499280Y886627I1225J429D01*
G37*
G36*
G01X506680D02*
G02X509276I1298J0D01*
G02X508220Y885352I-1298J0D01*
G01X508130Y885335D01*
X507323Y883938D01*
X507354Y883851D01*
G02X507426Y883423I-1225J-426D01*
G02X504832I-1297J0D01*
G02X505887Y884698I1298J0D01*
G01X505977Y884715D01*
X506784Y886112D01*
X506753Y886199D01*
G02X506680Y886627I1225J429D01*
G37*
G36*
G01X514080D02*
G02X516676I1298J0D01*
G02X515620Y885352I-1298J0D01*
G01X515530Y885335D01*
X514723Y883938D01*
X514754Y883851D01*
G02X514826Y883423I-1225J-426D01*
G02X512232I-1297J0D01*
G02X513287Y884698I1298J0D01*
G01X513377Y884715D01*
X514184Y886112D01*
X514153Y886199D01*
G02X514080Y886627I1225J429D01*
G37*
G36*
G01X521480D02*
G02X524076I1298J0D01*
G02X523020Y885352I-1298J0D01*
G01X522930Y885335D01*
X522123Y883938D01*
X522154Y883851D01*
G02X522226Y883423I-1225J-426D01*
G02X519632I-1297J0D01*
G02X520687Y884698I1298J0D01*
G01X520777Y884715D01*
X521584Y886112D01*
X521553Y886199D01*
G02X521480Y886627I1225J429D01*
G37*
G36*
G01X1349622D02*
G02X1352218I1298J0D01*
G02X1351162Y885352I-1298J0D01*
G01X1351072Y885335D01*
X1350265Y883938D01*
X1350296Y883851D01*
G02X1350368Y883423I-1225J-426D01*
G02X1347774I-1297J0D01*
G02X1348829Y884698I1298J0D01*
G01X1348919Y884715D01*
X1349726Y886112D01*
X1349695Y886199D01*
G02X1349622Y886627I1225J429D01*
G37*
G36*
G01X1357022D02*
G02X1359618I1298J0D01*
G02X1358562Y885352I-1298J0D01*
G01X1358472Y885335D01*
X1357665Y883938D01*
X1357696Y883851D01*
G02X1357768Y883423I-1225J-426D01*
G02X1355174I-1297J0D01*
G02X1356229Y884698I1298J0D01*
G01X1356319Y884715D01*
X1357126Y886112D01*
X1357095Y886199D01*
G02X1357022Y886627I1225J429D01*
G37*
G36*
G01X1364422D02*
G02X1367018I1298J0D01*
G02X1365962Y885352I-1298J0D01*
G01X1365872Y885335D01*
X1365065Y883938D01*
X1365096Y883851D01*
G02X1365168Y883423I-1225J-426D01*
G02X1362574I-1297J0D01*
G02X1363629Y884698I1298J0D01*
G01X1363719Y884715D01*
X1364526Y886112D01*
X1364495Y886199D01*
G02X1364422Y886627I1225J429D01*
G37*
G36*
G01X1371822D02*
G02X1374418I1298J0D01*
G02X1373362Y885352I-1298J0D01*
G01X1373272Y885335D01*
X1372465Y883938D01*
X1372496Y883851D01*
G02X1372568Y883423I-1225J-426D01*
G02X1369974I-1297J0D01*
G02X1371029Y884698I1298J0D01*
G01X1371119Y884715D01*
X1371926Y886112D01*
X1371895Y886199D01*
G02X1371822Y886627I1225J429D01*
G37*
G36*
G01X1379222D02*
G02X1381818I1298J0D01*
G02X1380762Y885352I-1298J0D01*
G01X1380672Y885335D01*
X1379865Y883938D01*
X1379896Y883851D01*
G02X1379968Y883423I-1225J-426D01*
G02X1377374I-1297J0D01*
G02X1378429Y884698I1298J0D01*
G01X1378519Y884715D01*
X1379326Y886112D01*
X1379295Y886199D01*
G02X1379222Y886627I1225J429D01*
G37*
G36*
G01X1386622D02*
G02X1389218I1298J0D01*
G02X1388162Y885352I-1298J0D01*
G01X1388072Y885335D01*
X1387265Y883938D01*
X1387296Y883851D01*
G02X1387368Y883423I-1225J-426D01*
G02X1384774I-1297J0D01*
G02X1385829Y884698I1298J0D01*
G01X1385919Y884715D01*
X1386726Y886112D01*
X1386695Y886199D01*
G02X1386622Y886627I1225J429D01*
G37*
G36*
G01X1394022D02*
G02X1396618I1298J0D01*
G02X1395562Y885352I-1298J0D01*
G01X1395472Y885335D01*
X1394665Y883938D01*
X1394696Y883851D01*
G02X1394768Y883423I-1225J-426D01*
G02X1392174I-1297J0D01*
G02X1393229Y884698I1298J0D01*
G01X1393319Y884715D01*
X1394126Y886112D01*
X1394095Y886199D01*
G02X1394022Y886627I1225J429D01*
G37*
G36*
G01X1401422D02*
G02X1404018I1298J0D01*
G02X1402962Y885352I-1298J0D01*
G01X1402872Y885335D01*
X1402065Y883938D01*
X1402096Y883851D01*
G02X1402168Y883423I-1225J-426D01*
G02X1399574I-1297J0D01*
G02X1400629Y884698I1298J0D01*
G01X1400719Y884715D01*
X1401526Y886112D01*
X1401495Y886199D01*
G02X1401422Y886627I1225J429D01*
G37*
G36*
G01X1408822D02*
G02X1411418I1298J0D01*
G02X1410362Y885352I-1298J0D01*
G01X1410272Y885335D01*
X1409465Y883938D01*
X1409496Y883851D01*
G02X1409568Y883423I-1225J-426D01*
G02X1406974I-1297J0D01*
G02X1408029Y884698I1298J0D01*
G01X1408119Y884715D01*
X1408926Y886112D01*
X1408895Y886199D01*
G02X1408822Y886627I1225J429D01*
G37*
G36*
G01X1416222D02*
G02X1418818I1298J0D01*
G02X1417762Y885352I-1298J0D01*
G01X1417672Y885335D01*
X1416865Y883938D01*
X1416896Y883851D01*
G02X1416968Y883423I-1225J-426D01*
G02X1414374I-1297J0D01*
G02X1415429Y884698I1298J0D01*
G01X1415519Y884715D01*
X1416326Y886112D01*
X1416295Y886199D01*
G02X1416222Y886627I1225J429D01*
G37*
G36*
G01X1423622D02*
G02X1426218I1298J0D01*
G02X1425162Y885352I-1298J0D01*
G01X1425072Y885335D01*
X1424265Y883938D01*
X1424296Y883851D01*
G02X1424368Y883423I-1225J-426D01*
G02X1421774I-1297J0D01*
G02X1422829Y884698I1298J0D01*
G01X1422919Y884715D01*
X1423726Y886112D01*
X1423695Y886199D01*
G02X1423622Y886627I1225J429D01*
G37*
G36*
G01X1431022D02*
G02X1433618I1298J0D01*
G02X1432562Y885352I-1298J0D01*
G01X1432472Y885335D01*
X1431665Y883938D01*
X1431696Y883851D01*
G02X1431768Y883423I-1225J-426D01*
G02X1429174I-1297J0D01*
G02X1430229Y884698I1298J0D01*
G01X1430319Y884715D01*
X1431126Y886112D01*
X1431095Y886199D01*
G02X1431022Y886627I1225J429D01*
G37*
G36*
G01X1438422D02*
G02X1441018I1298J0D01*
G02X1439962Y885352I-1298J0D01*
G01X1439872Y885335D01*
X1439065Y883938D01*
X1439096Y883851D01*
G02X1439168Y883423I-1225J-426D01*
G02X1436574I-1297J0D01*
G02X1437629Y884698I1298J0D01*
G01X1437719Y884715D01*
X1438526Y886112D01*
X1438495Y886199D01*
G02X1438422Y886627I1225J429D01*
G37*
G36*
G01X1445822D02*
G02X1448418I1298J0D01*
G02X1447362Y885352I-1298J0D01*
G01X1447272Y885335D01*
X1446465Y883938D01*
X1446496Y883851D01*
G02X1446568Y883423I-1225J-426D01*
G02X1443974I-1297J0D01*
G02X1445029Y884698I1298J0D01*
G01X1445119Y884715D01*
X1445926Y886112D01*
X1445895Y886199D01*
G02X1445822Y886627I1225J429D01*
G37*
G36*
G01X1453222D02*
G02X1455818I1298J0D01*
G02X1454762Y885352I-1298J0D01*
G01X1454672Y885335D01*
X1453865Y883938D01*
X1453896Y883851D01*
G02X1453968Y883423I-1225J-426D01*
G02X1451374I-1297J0D01*
G02X1452429Y884698I1298J0D01*
G01X1452519Y884715D01*
X1453326Y886112D01*
X1453295Y886199D01*
G02X1453222Y886627I1225J429D01*
G37*
G36*
G01X1460622D02*
G02X1463218I1298J0D01*
G02X1462162Y885352I-1298J0D01*
G01X1462072Y885335D01*
X1461265Y883938D01*
X1461296Y883851D01*
G02X1461368Y883423I-1225J-426D01*
G02X1458774I-1297J0D01*
G02X1459829Y884698I1298J0D01*
G01X1459919Y884715D01*
X1460726Y886112D01*
X1460695Y886199D01*
G02X1460622Y886627I1225J429D01*
G37*
G36*
G01X1468022D02*
G02X1470618I1298J0D01*
G02X1469562Y885352I-1298J0D01*
G01X1469472Y885335D01*
X1468665Y883938D01*
X1468696Y883851D01*
G02X1468768Y883423I-1225J-426D01*
G02X1466174I-1297J0D01*
G02X1467229Y884698I1298J0D01*
G01X1467319Y884715D01*
X1468126Y886112D01*
X1468095Y886199D01*
G02X1468022Y886627I1225J429D01*
G37*
G36*
G01X1475422D02*
G02X1478018I1298J0D01*
G02X1476962Y885352I-1298J0D01*
G01X1476872Y885335D01*
X1476065Y883938D01*
X1476096Y883851D01*
G02X1476168Y883423I-1225J-426D01*
G02X1473574I-1297J0D01*
G02X1474629Y884698I1298J0D01*
G01X1474719Y884715D01*
X1475526Y886112D01*
X1475495Y886199D01*
G02X1475422Y886627I1225J429D01*
G37*
G36*
G01X1482822D02*
G02X1485418I1298J0D01*
G02X1484362Y885352I-1298J0D01*
G01X1484272Y885335D01*
X1483465Y883938D01*
X1483496Y883851D01*
G02X1483568Y883423I-1225J-426D01*
G02X1480974I-1297J0D01*
G02X1482029Y884698I1298J0D01*
G01X1482119Y884715D01*
X1482926Y886112D01*
X1482895Y886199D01*
G02X1482822Y886627I1225J429D01*
G37*
G36*
G01X1490222D02*
G02X1492818I1298J0D01*
G02X1491762Y885352I-1298J0D01*
G01X1491672Y885335D01*
X1490865Y883938D01*
X1490896Y883851D01*
G02X1490968Y883423I-1225J-426D01*
G02X1488374I-1297J0D01*
G02X1489429Y884698I1298J0D01*
G01X1489519Y884715D01*
X1490326Y886112D01*
X1490295Y886199D01*
G02X1490222Y886627I1225J429D01*
G37*
G36*
G01X1497622D02*
G02X1500218I1298J0D01*
G02X1499162Y885352I-1298J0D01*
G01X1499072Y885335D01*
X1498265Y883938D01*
X1498296Y883851D01*
G02X1498368Y883423I-1225J-426D01*
G02X1495774I-1297J0D01*
G02X1496829Y884698I1298J0D01*
G01X1496919Y884715D01*
X1497726Y886112D01*
X1497695Y886199D01*
G02X1497622Y886627I1225J429D01*
G37*
G36*
G01X429414Y1079791D02*
G02X432008I1297J0D01*
G02X430953Y1078516I-1298J0D01*
G01X430863Y1078499D01*
X430056Y1077101D01*
X430086Y1077015D01*
G02X430158Y1076587I-1225J-426D01*
G02X427564I-1297J0D01*
G02X428620Y1077862I1298J0D01*
G01X428710Y1077879D01*
X429517Y1079276D01*
X429486Y1079363D01*
G02X429414Y1079791I1225J426D01*
G37*
G36*
G01X1405556D02*
G02X1408150I1297J0D01*
G02X1407095Y1078516I-1298J0D01*
G01X1407005Y1078499D01*
X1406198Y1077101D01*
X1406228Y1077015D01*
G02X1406300Y1076587I-1225J-426D01*
G02X1403706I-1297J0D01*
G02X1404762Y1077862I1298J0D01*
G01X1404852Y1077879D01*
X1405659Y1079276D01*
X1405628Y1079363D01*
G02X1405556Y1079791I1225J426D01*
G37*
G36*
G01X402962Y1084292D02*
G02X404001Y1083772I0J-1298D01*
G01X405623D01*
G02X406662Y1084292I1039J-778D01*
G02Y1081698I0J-1297D01*
G02X405623Y1082218I0J1298D01*
G01X404001D01*
G02X402962Y1081698I-1039J778D01*
G02Y1084292I0J1297D01*
G37*
G36*
G01X409064Y1082995D02*
G02X411660I1298J0D01*
G02X410604Y1081720I-1298J0D01*
G01X410514Y1081703D01*
X409706Y1080304D01*
X409736Y1080218D01*
G02X409808Y1079793I-1225J-426D01*
G01Y1079791D01*
G02X407214I-1297J0D01*
G02X408271Y1081066I1297J0D01*
G01X408361Y1081083D01*
X409168Y1082480D01*
X409137Y1082567D01*
G02X409064Y1082995I1225J429D01*
G37*
G36*
G01X1379104Y1084292D02*
G02X1380143Y1083772I0J-1298D01*
G01X1381765D01*
G02X1382804Y1084292I1039J-778D01*
G02Y1081698I0J-1297D01*
G02X1381765Y1082218I0J1298D01*
G01X1380143D01*
G02X1379104Y1081698I-1039J778D01*
G02Y1084292I0J1297D01*
G37*
G36*
G01X1385206Y1082995D02*
G02X1387802I1298J0D01*
G02X1386746Y1081720I-1298J0D01*
G01X1386656Y1081703D01*
X1385848Y1080304D01*
X1385878Y1080218D01*
G02X1385950Y1079793I-1225J-426D01*
G01Y1079791D01*
G02X1383356I-1297J0D01*
G02X1384413Y1081066I1297J0D01*
G01X1384503Y1081083D01*
X1385310Y1082480D01*
X1385279Y1082567D01*
G02X1385206Y1082995I1225J429D01*
G37*
G36*
G01X410914Y1086200D02*
G02X413508I1297J0D01*
G02X413436Y1085772I-1297J-2D01*
G01X413405Y1085685D01*
X414212Y1084287D01*
X414303Y1084270D01*
G02X415360Y1082995I-240J-1275D01*
G02X412764I-1298J0D01*
G02X412837Y1083422I1298J-2D01*
G01X412867Y1083509D01*
X412059Y1084908D01*
X411969Y1084925D01*
G02X410914Y1086200I243J1275D01*
G37*
G36*
G01X419611Y1087498D02*
G02X420650Y1086978I0J-1298D01*
G01X422272D01*
G02X423311Y1087498I1039J-778D01*
G02Y1084902I0J-1298D01*
G02X422272Y1085422I0J1298D01*
G01X420650D01*
G02X419611Y1084902I-1039J778D01*
G02Y1087498I0J1298D01*
G37*
G36*
G01X425714Y1086200D02*
G02X428310I1298J0D01*
G02X427254Y1084925I-1298J0D01*
G01X427164Y1084908D01*
X426356Y1083510D01*
X426387Y1083423D01*
G02X426460Y1082995I-1225J-429D01*
G02X423864I-1298J0D01*
G02X424920Y1084270I1298J0D01*
G01X425010Y1084287D01*
X425818Y1085685D01*
X425787Y1085772D01*
G02X425714Y1086200I1225J429D01*
G37*
G36*
G01X1387056D02*
G02X1389650I1297J0D01*
G02X1389578Y1085772I-1297J-2D01*
G01X1389547Y1085685D01*
X1390354Y1084287D01*
X1390445Y1084270D01*
G02X1391502Y1082995I-240J-1275D01*
G02X1388906I-1298J0D01*
G02X1388979Y1083422I1298J-2D01*
G01X1389009Y1083509D01*
X1388201Y1084908D01*
X1388111Y1084925D01*
G02X1387056Y1086200I243J1275D01*
G37*
G36*
G01X1395753Y1087498D02*
G02X1396792Y1086978I0J-1298D01*
G01X1398414D01*
G02X1399453Y1087498I1039J-778D01*
G02Y1084902I0J-1298D01*
G02X1398414Y1085422I0J1298D01*
G01X1396792D01*
G02X1395753Y1084902I-1039J778D01*
G02Y1087498I0J1298D01*
G37*
G36*
G01X1401856Y1086200D02*
G02X1404452I1298J0D01*
G02X1403396Y1084925I-1298J0D01*
G01X1403306Y1084908D01*
X1402498Y1083510D01*
X1402529Y1083423D01*
G02X1402602Y1082995I-1225J-429D01*
G02X1400006I-1298J0D01*
G02X1401062Y1084270I1298J0D01*
G01X1401152Y1084287D01*
X1401960Y1085685D01*
X1401929Y1085772D01*
G02X1401856Y1086200I1225J429D01*
G37*
G36*
G01X401664Y1089404D02*
G02X404258I1297J0D01*
G02X404186Y1088976I-1297J-2D01*
G01X404155Y1088889D01*
X404962Y1087492D01*
X405052Y1087475D01*
G02X406108Y1086200I-242J-1275D01*
G02X403514I-1297J0D01*
G02X403586Y1086628I1297J2D01*
G01X403616Y1086714D01*
X402809Y1088112D01*
X402719Y1088129D01*
G02X401664Y1089404I243J1275D01*
G37*
G36*
G01X410362Y1090702D02*
G02X411401Y1090182I0J-1298D01*
G01X413023D01*
G02X414062Y1090702I1039J-778D01*
G02Y1088106I0J-1298D01*
G02X413023Y1088626I0J1298D01*
G01X411401D01*
G02X410362Y1088106I-1039J778D01*
G02Y1090702I0J1298D01*
G37*
G36*
G01X427564Y1089404D02*
G02X430158I1297J0D01*
G02X430086Y1088976I-1297J-2D01*
G01X430055Y1088889D01*
X430862Y1087492D01*
X430952Y1087475D01*
G02X432008Y1086200I-242J-1275D01*
G02X429412I-1298J0D01*
G02X429485Y1086629I1297J0D01*
G01X429516Y1086715D01*
X428709Y1088112D01*
X428619Y1088129D01*
G02X427564Y1089404I243J1275D01*
G37*
G36*
G01X1377806D02*
G02X1380400I1297J0D01*
G02X1380328Y1088976I-1297J-2D01*
G01X1380297Y1088889D01*
X1381104Y1087492D01*
X1381194Y1087475D01*
G02X1382250Y1086200I-242J-1275D01*
G02X1379656I-1297J0D01*
G02X1379728Y1086628I1297J2D01*
G01X1379758Y1086714D01*
X1378951Y1088112D01*
X1378861Y1088129D01*
G02X1377806Y1089404I243J1275D01*
G37*
G36*
G01X1386504Y1090702D02*
G02X1387543Y1090182I0J-1298D01*
G01X1389165D01*
G02X1390204Y1090702I1039J-778D01*
G02Y1088106I0J-1298D01*
G02X1389165Y1088626I0J1298D01*
G01X1387543D01*
G02X1386504Y1088106I-1039J778D01*
G02Y1090702I0J1298D01*
G37*
G36*
G01X1403706Y1089404D02*
G02X1406300I1297J0D01*
G02X1406228Y1088976I-1297J-2D01*
G01X1406197Y1088889D01*
X1407004Y1087492D01*
X1407094Y1087475D01*
G02X1408150Y1086200I-242J-1275D01*
G02X1405554I-1298J0D01*
G02X1405627Y1086629I1297J0D01*
G01X1405658Y1086715D01*
X1404851Y1088112D01*
X1404761Y1088129D01*
G02X1403706Y1089404I243J1275D01*
G37*
G36*
G01X407214Y1092608D02*
G02X409808I1297J0D01*
G02X408753Y1091333I-1298J0D01*
G01X408663Y1091316D01*
X407856Y1089919D01*
X407887Y1089833D01*
G02X407960Y1089404I-1224J-429D01*
G02X405364I-1298J0D01*
G02X406420Y1090679I1298J0D01*
G01X406510Y1090696D01*
X407317Y1092093D01*
X407286Y1092180D01*
G02X407214Y1092608I1225J426D01*
G37*
G36*
G01X418314D02*
G02X420908I1297J0D01*
G02X420836Y1092180I-1297J-2D01*
G01X420805Y1092093D01*
X421612Y1090696D01*
X421702Y1090679D01*
G02X422760Y1089404I-239J-1275D01*
G02X420164I-1298J0D01*
G02X420237Y1089831I1298J-2D01*
G01X420267Y1089917D01*
X419459Y1091316D01*
X419369Y1091333D01*
G02X418314Y1092608I243J1275D01*
G37*
G36*
G01X427011Y1093906D02*
G02X428050Y1093386I0J-1298D01*
G01X429672D01*
G02X430711Y1093906I1039J-778D01*
G02Y1091310I0J-1298D01*
G02X429672Y1091830I0J1298D01*
G01X428050D01*
G02X427011Y1091310I-1039J778D01*
G02Y1093906I0J1298D01*
G37*
G36*
G01X1383356Y1092608D02*
G02X1385950I1297J0D01*
G02X1384895Y1091333I-1298J0D01*
G01X1384805Y1091316D01*
X1383998Y1089919D01*
X1384029Y1089833D01*
G02X1384102Y1089404I-1224J-429D01*
G02X1381506I-1298J0D01*
G02X1382562Y1090679I1298J0D01*
G01X1382652Y1090696D01*
X1383459Y1092093D01*
X1383428Y1092180D01*
G02X1383356Y1092608I1225J426D01*
G37*
G36*
G01X1394456D02*
G02X1397050I1297J0D01*
G02X1396978Y1092180I-1297J-2D01*
G01X1396947Y1092093D01*
X1397754Y1090696D01*
X1397844Y1090679D01*
G02X1398902Y1089404I-239J-1275D01*
G02X1396306I-1298J0D01*
G02X1396379Y1089831I1298J-2D01*
G01X1396409Y1089917D01*
X1395601Y1091316D01*
X1395511Y1091333D01*
G02X1394456Y1092608I243J1275D01*
G37*
G36*
G01X1403153Y1093906D02*
G02X1404192Y1093386I0J-1298D01*
G01X1405814D01*
G02X1406853Y1093906I1039J-778D01*
G02Y1091310I0J-1298D01*
G02X1405814Y1091830I0J1298D01*
G01X1404192D01*
G02X1403153Y1091310I-1039J778D01*
G02Y1093906I0J1298D01*
G37*
G36*
G01X423864Y1095813D02*
G02X426460I1298J0D01*
G02X425404Y1094538I-1298J0D01*
G01X425314Y1094521D01*
X424506Y1093122D01*
X424536Y1093035D01*
G02X424608Y1092610I-1225J-426D01*
G01Y1092608D01*
G02X422014I-1297J0D01*
G02X423070Y1093883I1298J0D01*
G01X423161Y1093900D01*
X423968Y1095298D01*
X423937Y1095385D01*
G02X423864Y1095813I1225J429D01*
G37*
G36*
G01X1400006D02*
G02X1402602I1298J0D01*
G02X1401546Y1094538I-1298J0D01*
G01X1401456Y1094521D01*
X1400648Y1093122D01*
X1400678Y1093035D01*
G02X1400750Y1092610I-1225J-426D01*
G01Y1092608D01*
G02X1398156I-1297J0D01*
G02X1399212Y1093883I1298J0D01*
G01X1399303Y1093900D01*
X1400110Y1095298D01*
X1400079Y1095385D01*
G02X1400006Y1095813I1225J429D01*
G37*
G36*
G01X404811Y1100314D02*
G02X405850Y1099794I0J-1298D01*
G01X407472D01*
G02X408511Y1100314I1039J-778D01*
G02Y1097720I0J-1297D01*
G02X407472Y1098240I0J1298D01*
G01X405850D01*
G02X404811Y1097720I-1039J778D01*
G02Y1100314I0J1297D01*
G37*
G36*
G01X1380953D02*
G02X1381992Y1099794I0J-1298D01*
G01X1383614D01*
G02X1384653Y1100314I1039J-778D01*
G02Y1097720I0J-1297D01*
G02X1383614Y1098240I0J1298D01*
G01X1381992D01*
G02X1380953Y1097720I-1039J778D01*
G02Y1100314I0J1297D01*
G37*
G36*
G01X351161Y1103518D02*
G02X352200Y1102998I0J-1298D01*
G01X353822D01*
G02X354861Y1103518I1039J-778D01*
G02Y1100924I0J-1297D01*
G02X353822Y1101444I0J1298D01*
G01X352200D01*
G02X351161Y1100924I-1039J778D01*
G02Y1103518I0J1297D01*
G37*
G36*
G01X401664Y1102221D02*
G02X404260I1298J0D01*
G02X403204Y1100946I-1298J0D01*
G01X403114Y1100929D01*
X402306Y1099530D01*
X402336Y1099444D01*
G02X402408Y1099019I-1225J-426D01*
G01Y1099017D01*
G02X399814I-1297J0D01*
G02X400871Y1100292I1297J0D01*
G01X400961Y1100309D01*
X401768Y1101706D01*
X401737Y1101793D01*
G02X401664Y1102221I1225J429D01*
G37*
G36*
G01X1327303Y1103518D02*
G02X1328342Y1102998I0J-1298D01*
G01X1329964D01*
G02X1331003Y1103518I1039J-778D01*
G02Y1100924I0J-1297D01*
G02X1329964Y1101444I0J1298D01*
G01X1328342D01*
G02X1327303Y1100924I-1039J778D01*
G02Y1103518I0J1297D01*
G37*
G36*
G01X1377806Y1102221D02*
G02X1380402I1298J0D01*
G02X1379346Y1100946I-1298J0D01*
G01X1379256Y1100929D01*
X1378448Y1099530D01*
X1378478Y1099444D01*
G02X1378550Y1099019I-1225J-426D01*
G01Y1099017D01*
G02X1375956I-1297J0D01*
G02X1377013Y1100292I1297J0D01*
G01X1377103Y1100309D01*
X1377910Y1101706D01*
X1377879Y1101793D01*
G02X1377806Y1102221I1225J429D01*
G37*
G36*
G01X375211Y1106724D02*
G02X376250Y1106204I0J-1298D01*
G01X377873D01*
G02X378912Y1106724I1039J-778D01*
G02Y1104128I0J-1298D01*
G02X377873Y1104648I0J1298D01*
G01X376250D01*
G02X375211Y1104128I-1039J778D01*
G02Y1106724I0J1298D01*
G37*
G36*
G01X381314Y1105426D02*
G02X383908I1297J0D01*
G02X382853Y1104151I-1298J0D01*
G01X382763Y1104134D01*
X381956Y1102737D01*
X381986Y1102650D01*
G02X382060Y1102221I-1223J-432D01*
G02X379464I-1298J0D01*
G02X380519Y1103496I1298J0D01*
G01X380609Y1103513D01*
X381417Y1104911D01*
X381386Y1104998D01*
G02X381314Y1105426I1225J426D01*
G37*
G36*
G01X410914D02*
G02X413508I1297J0D01*
G02X413436Y1104998I-1297J-2D01*
G01X413405Y1104911D01*
X414212Y1103513D01*
X414303Y1103496D01*
G02X415360Y1102221I-240J-1275D01*
G02X412764I-1298J0D01*
G02X412837Y1102648I1298J-2D01*
G01X412867Y1102735D01*
X412059Y1104134D01*
X411969Y1104151D01*
G02X410914Y1105426I243J1275D01*
G37*
G36*
G01X415911Y1106724D02*
G02X416950Y1106204I0J-1298D01*
G01X418572D01*
G02X419611Y1106724I1039J-778D01*
G02Y1104128I0J-1298D01*
G02X418572Y1104648I0J1298D01*
G01X416950D01*
G02X415911Y1104128I-1039J778D01*
G02Y1106724I0J1298D01*
G37*
G36*
G01X1351353D02*
G02X1352392Y1106204I0J-1298D01*
G01X1354015D01*
G02X1355054Y1106724I1039J-778D01*
G02Y1104128I0J-1298D01*
G02X1354015Y1104648I0J1298D01*
G01X1352392D01*
G02X1351353Y1104128I-1039J778D01*
G02Y1106724I0J1298D01*
G37*
G36*
G01X1357456Y1105426D02*
G02X1360050I1297J0D01*
G02X1358995Y1104151I-1298J0D01*
G01X1358905Y1104134D01*
X1358098Y1102737D01*
X1358128Y1102650D01*
G02X1358202Y1102221I-1223J-432D01*
G02X1355606I-1298J0D01*
G02X1356661Y1103496I1298J0D01*
G01X1356751Y1103513D01*
X1357559Y1104911D01*
X1357528Y1104998D01*
G02X1357456Y1105426I1225J426D01*
G37*
G36*
G01X1387056D02*
G02X1389650I1297J0D01*
G02X1389578Y1104998I-1297J-2D01*
G01X1389547Y1104911D01*
X1390354Y1103513D01*
X1390445Y1103496D01*
G02X1391502Y1102221I-240J-1275D01*
G02X1388906I-1298J0D01*
G02X1388979Y1102648I1298J-2D01*
G01X1389009Y1102735D01*
X1388201Y1104134D01*
X1388111Y1104151D01*
G02X1387056Y1105426I243J1275D01*
G37*
G36*
G01X1392053Y1106724D02*
G02X1393092Y1106204I0J-1298D01*
G01X1394714D01*
G02X1395753Y1106724I1039J-778D01*
G02Y1104128I0J-1298D01*
G02X1394714Y1104648I0J1298D01*
G01X1393092D01*
G02X1392053Y1104128I-1039J778D01*
G02Y1106724I0J1298D01*
G37*
G36*
G01X358561Y1109928D02*
G02X359600Y1109408I0J-1298D01*
G01X361222D01*
G02X362261Y1109928I1039J-778D01*
G02Y1107332I0J-1298D01*
G02X361222Y1107852I0J1298D01*
G01X359600D01*
G02X358561Y1107332I-1039J778D01*
G02Y1109928I0J1298D01*
G37*
G36*
G01X383164Y1108630D02*
G02X385760I1298J0D01*
G02X385687Y1108202I-1298J1D01*
G01X385656Y1108115D01*
X386463Y1106718D01*
X386553Y1106701D01*
G02X387608Y1105426I-243J-1275D01*
G02X385014I-1297J0D01*
G02X385086Y1105855I1297J3D01*
G01X385117Y1105941D01*
X384310Y1107338D01*
X384220Y1107355D01*
G02X383164Y1108630I242J1275D01*
G37*
G36*
G01X391862Y1109928D02*
G02X392901Y1109408I0J-1298D01*
G01X394523D01*
G02X395562Y1109928I1039J-778D01*
G02Y1107332I0J-1298D01*
G02X394523Y1107852I0J1298D01*
G01X392901D01*
G02X391862Y1107332I-1039J778D01*
G02Y1109928I0J1298D01*
G37*
G36*
G01X397964Y1108630D02*
G02X400560I1298J0D01*
G02X399504Y1107355I-1298J0D01*
G01X399414Y1107338D01*
X398606Y1105939D01*
X398636Y1105853D01*
G02X398708Y1105428I-1225J-426D01*
G01Y1105426D01*
G02X396114I-1297J0D01*
G02X397171Y1106701I1297J0D01*
G01X397261Y1106718D01*
X398068Y1108115D01*
X398037Y1108202D01*
G02X397964Y1108630I1225J429D01*
G37*
G36*
G01X409064D02*
G02X411660I1298J0D01*
G02X410604Y1107355I-1298J0D01*
G01X410514Y1107338D01*
X409706Y1105939D01*
X409736Y1105853D01*
G02X409808Y1105428I-1225J-426D01*
G01Y1105426D01*
G02X407214I-1297J0D01*
G02X408271Y1106701I1297J0D01*
G01X408361Y1106718D01*
X409168Y1108115D01*
X409137Y1108202D01*
G02X409064Y1108630I1225J429D01*
G37*
G36*
G01X1334703Y1109928D02*
G02X1335742Y1109408I0J-1298D01*
G01X1337364D01*
G02X1338403Y1109928I1039J-778D01*
G02Y1107332I0J-1298D01*
G02X1337364Y1107852I0J1298D01*
G01X1335742D01*
G02X1334703Y1107332I-1039J778D01*
G02Y1109928I0J1298D01*
G37*
G36*
G01X1359306Y1108630D02*
G02X1361902I1298J0D01*
G02X1361829Y1108202I-1298J1D01*
G01X1361798Y1108115D01*
X1362605Y1106718D01*
X1362695Y1106701D01*
G02X1363750Y1105426I-243J-1275D01*
G02X1361156I-1297J0D01*
G02X1361228Y1105855I1297J3D01*
G01X1361259Y1105941D01*
X1360452Y1107338D01*
X1360362Y1107355D01*
G02X1359306Y1108630I242J1275D01*
G37*
G36*
G01X1368004Y1109928D02*
G02X1369043Y1109408I0J-1298D01*
G01X1370665D01*
G02X1371704Y1109928I1039J-778D01*
G02Y1107332I0J-1298D01*
G02X1370665Y1107852I0J1298D01*
G01X1369043D01*
G02X1368004Y1107332I-1039J778D01*
G02Y1109928I0J1298D01*
G37*
G36*
G01X1374106Y1108630D02*
G02X1376702I1298J0D01*
G02X1375646Y1107355I-1298J0D01*
G01X1375556Y1107338D01*
X1374748Y1105939D01*
X1374778Y1105853D01*
G02X1374850Y1105428I-1225J-426D01*
G01Y1105426D01*
G02X1372256I-1297J0D01*
G02X1373313Y1106701I1297J0D01*
G01X1373403Y1106718D01*
X1374210Y1108115D01*
X1374179Y1108202D01*
G02X1374106Y1108630I1225J429D01*
G37*
G36*
G01X1385206D02*
G02X1387802I1298J0D01*
G02X1386746Y1107355I-1298J0D01*
G01X1386656Y1107338D01*
X1385848Y1105939D01*
X1385878Y1105853D01*
G02X1385950Y1105428I-1225J-426D01*
G01Y1105426D01*
G02X1383356I-1297J0D01*
G02X1384413Y1106701I1297J0D01*
G01X1384503Y1106718D01*
X1385310Y1108115D01*
X1385279Y1108202D01*
G02X1385206Y1108630I1225J429D01*
G37*
G36*
G01X366514Y1111834D02*
G02X369110I1298J0D01*
G02X369037Y1111406I-1298J1D01*
G01X369006Y1111319D01*
X369813Y1109922D01*
X369903Y1109905D01*
G02X370958Y1108630I-243J-1275D01*
G02X368364I-1297J0D01*
G02X368436Y1109059I1297J3D01*
G01X368467Y1109145D01*
X367660Y1110542D01*
X367570Y1110559D01*
G02X366514Y1111834I242J1275D01*
G37*
G36*
G01X373914D02*
G02X376508I1297J0D01*
G02X376436Y1111406I-1297J-2D01*
G01X376405Y1111319D01*
X377212Y1109922D01*
X377302Y1109905D01*
G02X378360Y1108630I-239J-1275D01*
G02X375764I-1298J0D01*
G02X375837Y1109057I1298J-2D01*
G01X375867Y1109143D01*
X375059Y1110542D01*
X374969Y1110559D01*
G02X373914Y1111834I243J1275D01*
G37*
G36*
G01X382611Y1113132D02*
G02X383650Y1112612I0J-1298D01*
G01X385272D01*
G02X386311Y1113132I1039J-778D01*
G02Y1110536I0J-1298D01*
G02X385272Y1111056I0J1298D01*
G01X383650D01*
G02X382611Y1110536I-1039J778D01*
G02Y1113132I0J1298D01*
G37*
G36*
G01X399814Y1111834D02*
G02X402408I1297J0D01*
G02X402336Y1111406I-1297J-2D01*
G01X402305Y1111319D01*
X403112Y1109922D01*
X403202Y1109905D01*
G02X404260Y1108630I-239J-1275D01*
G02X401664I-1298J0D01*
G02X401737Y1109057I1298J-2D01*
G01X401767Y1109143D01*
X400959Y1110542D01*
X400869Y1110559D01*
G02X399814Y1111834I243J1275D01*
G37*
G36*
G01X408511Y1113132D02*
G02X409550Y1112612I0J-1298D01*
G01X411172D01*
G02X412211Y1113132I1039J-778D01*
G02Y1110536I0J-1298D01*
G02X411172Y1111056I0J1298D01*
G01X409550D01*
G02X408511Y1110536I-1039J778D01*
G02Y1113132I0J1298D01*
G37*
G36*
G01X418314Y1111834D02*
G02X420908I1297J0D01*
G02X419853Y1110559I-1298J0D01*
G01X419763Y1110542D01*
X418956Y1109145D01*
X418987Y1109059D01*
G02X419060Y1108630I-1224J-429D01*
G02X416464I-1298J0D01*
G02X417520Y1109905I1298J0D01*
G01X417610Y1109922D01*
X418417Y1111319D01*
X418386Y1111406D01*
G02X418314Y1111834I1225J426D01*
G37*
G36*
G01X1342656D02*
G02X1345252I1298J0D01*
G02X1345179Y1111406I-1298J1D01*
G01X1345148Y1111319D01*
X1345955Y1109922D01*
X1346045Y1109905D01*
G02X1347100Y1108630I-243J-1275D01*
G02X1344506I-1297J0D01*
G02X1344578Y1109059I1297J3D01*
G01X1344609Y1109145D01*
X1343802Y1110542D01*
X1343712Y1110559D01*
G02X1342656Y1111834I242J1275D01*
G37*
G36*
G01X1350056D02*
G02X1352650I1297J0D01*
G02X1352578Y1111406I-1297J-2D01*
G01X1352547Y1111319D01*
X1353354Y1109922D01*
X1353444Y1109905D01*
G02X1354502Y1108630I-239J-1275D01*
G02X1351906I-1298J0D01*
G02X1351979Y1109057I1298J-2D01*
G01X1352009Y1109143D01*
X1351201Y1110542D01*
X1351111Y1110559D01*
G02X1350056Y1111834I243J1275D01*
G37*
G36*
G01X1358753Y1113132D02*
G02X1359792Y1112612I0J-1298D01*
G01X1361414D01*
G02X1362453Y1113132I1039J-778D01*
G02Y1110536I0J-1298D01*
G02X1361414Y1111056I0J1298D01*
G01X1359792D01*
G02X1358753Y1110536I-1039J778D01*
G02Y1113132I0J1298D01*
G37*
G36*
G01X1375956Y1111834D02*
G02X1378550I1297J0D01*
G02X1378478Y1111406I-1297J-2D01*
G01X1378447Y1111319D01*
X1379254Y1109922D01*
X1379344Y1109905D01*
G02X1380402Y1108630I-239J-1275D01*
G02X1377806I-1298J0D01*
G02X1377879Y1109057I1298J-2D01*
G01X1377909Y1109143D01*
X1377101Y1110542D01*
X1377011Y1110559D01*
G02X1375956Y1111834I243J1275D01*
G37*
G36*
G01X1384653Y1113132D02*
G02X1385692Y1112612I0J-1298D01*
G01X1387314D01*
G02X1388353Y1113132I1039J-778D01*
G02Y1110536I0J-1298D01*
G02X1387314Y1111056I0J1298D01*
G01X1385692D01*
G02X1384653Y1110536I-1039J778D01*
G02Y1113132I0J1298D01*
G37*
G36*
G01X1394456Y1111834D02*
G02X1397050I1297J0D01*
G02X1395995Y1110559I-1298J0D01*
G01X1395905Y1110542D01*
X1395098Y1109145D01*
X1395129Y1109059D01*
G02X1395202Y1108630I-1224J-429D01*
G02X1392606I-1298J0D01*
G02X1393662Y1109905I1298J0D01*
G01X1393752Y1109922D01*
X1394559Y1111319D01*
X1394528Y1111406D01*
G02X1394456Y1111834I1225J426D01*
G37*
G36*
G01X346164Y1115039D02*
G02X348758I1297J0D01*
G02X347703Y1113764I-1298J0D01*
G01X347613Y1113747D01*
X346805Y1112349D01*
X346836Y1112262D01*
G02X346908Y1111834I-1225J-426D01*
G02X344314I-1297J0D01*
G02X345369Y1113109I1298J0D01*
G01X345459Y1113126D01*
X346267Y1114524D01*
X346236Y1114611D01*
G02X346164Y1115039I1225J426D01*
G37*
G36*
G01X365961Y1116336D02*
G02X367000Y1115816I0J-1298D01*
G01X368622D01*
G02X369661Y1116336I1039J-778D01*
G02Y1113742I0J-1297D01*
G02X368622Y1114262I0J1298D01*
G01X367000D01*
G02X365961Y1113742I-1039J778D01*
G02Y1116336I0J1297D01*
G37*
G36*
G01X379464Y1115039D02*
G02X382060I1298J0D01*
G02X381004Y1113764I-1298J0D01*
G01X380914Y1113747D01*
X380106Y1112348D01*
X380136Y1112261D01*
G02X380208Y1111836I-1225J-426D01*
G01Y1111834D01*
G02X377614I-1297J0D01*
G02X378670Y1113109I1298J0D01*
G01X378761Y1113126D01*
X379568Y1114524D01*
X379537Y1114611D01*
G02X379464Y1115039I1225J429D01*
G37*
G36*
G01X390564D02*
G02X393160I1298J0D01*
G02X393087Y1114611I-1298J1D01*
G01X393056Y1114524D01*
X393864Y1113126D01*
X393954Y1113109D01*
G02X395008Y1111834I-244J-1275D01*
G02X392414I-1297J0D01*
G02X392487Y1112263I1297J0D01*
G01X392517Y1112350D01*
X391710Y1113747D01*
X391620Y1113764D01*
G02X390564Y1115039I242J1275D01*
G37*
G36*
G01X399262Y1116336D02*
G02X400301Y1115816I0J-1298D01*
G01X401923D01*
G02X402962Y1116336I1039J-778D01*
G02Y1113742I0J-1297D01*
G02X401923Y1114262I0J1298D01*
G01X400301D01*
G02X399262Y1113742I-1039J778D01*
G02Y1116336I0J1297D01*
G37*
G36*
G01X412764Y1115039D02*
G02X415360I1298J0D01*
G02X415287Y1114611I-1298J1D01*
G01X415256Y1114524D01*
X416064Y1113126D01*
X416154Y1113109D01*
G02X417208Y1111834I-244J-1275D01*
G02X414614I-1297J0D01*
G02X414687Y1112263I1297J0D01*
G01X414717Y1112350D01*
X413910Y1113747D01*
X413820Y1113764D01*
G02X412764Y1115039I242J1275D01*
G37*
G36*
G01X1322306D02*
G02X1324900I1297J0D01*
G02X1323845Y1113764I-1298J0D01*
G01X1323755Y1113747D01*
X1322947Y1112349D01*
X1322978Y1112262D01*
G02X1323050Y1111834I-1225J-426D01*
G02X1320456I-1297J0D01*
G02X1321511Y1113109I1298J0D01*
G01X1321601Y1113126D01*
X1322409Y1114524D01*
X1322378Y1114611D01*
G02X1322306Y1115039I1225J426D01*
G37*
G36*
G01X1342103Y1116336D02*
G02X1343142Y1115816I0J-1298D01*
G01X1344764D01*
G02X1345803Y1116336I1039J-778D01*
G02Y1113742I0J-1297D01*
G02X1344764Y1114262I0J1298D01*
G01X1343142D01*
G02X1342103Y1113742I-1039J778D01*
G02Y1116336I0J1297D01*
G37*
G36*
G01X1355606Y1115039D02*
G02X1358202I1298J0D01*
G02X1357146Y1113764I-1298J0D01*
G01X1357056Y1113747D01*
X1356248Y1112348D01*
X1356278Y1112261D01*
G02X1356350Y1111836I-1225J-426D01*
G01Y1111834D01*
G02X1353756I-1297J0D01*
G02X1354812Y1113109I1298J0D01*
G01X1354903Y1113126D01*
X1355710Y1114524D01*
X1355679Y1114611D01*
G02X1355606Y1115039I1225J429D01*
G37*
G36*
G01X1366706D02*
G02X1369302I1298J0D01*
G02X1369229Y1114611I-1298J1D01*
G01X1369198Y1114524D01*
X1370006Y1113126D01*
X1370096Y1113109D01*
G02X1371150Y1111834I-244J-1275D01*
G02X1368556I-1297J0D01*
G02X1368629Y1112263I1297J0D01*
G01X1368659Y1112350D01*
X1367852Y1113747D01*
X1367762Y1113764D01*
G02X1366706Y1115039I242J1275D01*
G37*
G36*
G01X1375404Y1116336D02*
G02X1376443Y1115816I0J-1298D01*
G01X1378065D01*
G02X1379104Y1116336I1039J-778D01*
G02Y1113742I0J-1297D01*
G02X1378065Y1114262I0J1298D01*
G01X1376443D01*
G02X1375404Y1113742I-1039J778D01*
G02Y1116336I0J1297D01*
G37*
G36*
G01X1388906Y1115039D02*
G02X1391502I1298J0D01*
G02X1391429Y1114611I-1298J1D01*
G01X1391398Y1114524D01*
X1392206Y1113126D01*
X1392296Y1113109D01*
G02X1393350Y1111834I-244J-1275D01*
G02X1390756I-1297J0D01*
G02X1390829Y1112263I1297J0D01*
G01X1390859Y1112350D01*
X1390052Y1113747D01*
X1389962Y1113764D01*
G02X1388906Y1115039I242J1275D01*
G37*
G36*
G01X342464Y1121447D02*
G02X345058I1297J0D01*
G02X344003Y1120172I-1298J0D01*
G01X343913Y1120155D01*
X343106Y1118758D01*
X343137Y1118671D01*
G02X343210Y1118243I-1225J-429D01*
G02X340614I-1298J0D01*
G02X341670Y1119518I1298J0D01*
G01X341760Y1119535D01*
X342567Y1120932D01*
X342536Y1121019D01*
G02X342464Y1121447I1225J426D01*
G37*
G36*
G01X1318606D02*
G02X1321200I1297J0D01*
G02X1320145Y1120172I-1298J0D01*
G01X1320055Y1120155D01*
X1319248Y1118758D01*
X1319279Y1118671D01*
G02X1319352Y1118243I-1225J-429D01*
G02X1316756I-1298J0D01*
G02X1317812Y1119518I1298J0D01*
G01X1317902Y1119535D01*
X1318709Y1120932D01*
X1318678Y1121019D01*
G02X1318606Y1121447I1225J426D01*
G37*
G36*
G01X355414Y1124651D02*
G02X358010I1298J0D01*
G02X357937Y1124223I-1298J1D01*
G01X357906Y1124136D01*
X358713Y1122739D01*
X358803Y1122722D01*
G02X359858Y1121447I-243J-1275D01*
G02X357264I-1297J0D01*
G02X357336Y1121876I1297J3D01*
G01X357367Y1121962D01*
X356560Y1123359D01*
X356470Y1123376D01*
G02X355414Y1124651I242J1275D01*
G37*
G36*
G01X362814D02*
G02X365408I1297J0D01*
G02X365336Y1124223I-1297J-2D01*
G01X365305Y1124136D01*
X366112Y1122739D01*
X366202Y1122722D01*
G02X367260Y1121447I-239J-1275D01*
G02X364664I-1298J0D01*
G02X364737Y1121874I1298J-2D01*
G01X364767Y1121960D01*
X363959Y1123359D01*
X363869Y1123376D01*
G02X362814Y1124651I243J1275D01*
G37*
G36*
G01X370214D02*
G02X372808I1297J0D01*
G02X372736Y1124223I-1297J-2D01*
G01X372705Y1124136D01*
X373512Y1122739D01*
X373602Y1122722D01*
G02X374660Y1121447I-239J-1275D01*
G02X372064I-1298J0D01*
G02X372137Y1121874I1298J-2D01*
G01X372167Y1121960D01*
X371359Y1123359D01*
X371269Y1123376D01*
G02X370214Y1124651I243J1275D01*
G37*
G36*
G01X377614D02*
G02X380208I1297J0D01*
G02X380136Y1124223I-1297J-2D01*
G01X380105Y1124136D01*
X380912Y1122739D01*
X381002Y1122722D01*
G02X382060Y1121447I-239J-1275D01*
G02X379464I-1298J0D01*
G02X379537Y1121874I1298J-2D01*
G01X379567Y1121960D01*
X378759Y1123359D01*
X378669Y1123376D01*
G02X377614Y1124651I243J1275D01*
G37*
G36*
G01X385014D02*
G02X387608I1297J0D01*
G02X387536Y1124223I-1297J-2D01*
G01X387505Y1124136D01*
X388312Y1122739D01*
X388402Y1122722D01*
G02X389460Y1121447I-239J-1275D01*
G02X386864I-1298J0D01*
G02X386937Y1121874I1298J-2D01*
G01X386967Y1121960D01*
X386159Y1123359D01*
X386069Y1123376D01*
G02X385014Y1124651I243J1275D01*
G37*
G36*
G01X392414D02*
G02X395008I1297J0D01*
G02X394936Y1124223I-1297J-2D01*
G01X394905Y1124136D01*
X395712Y1122739D01*
X395802Y1122722D01*
G02X396860Y1121447I-239J-1275D01*
G02X394264I-1298J0D01*
G02X394337Y1121874I1298J-2D01*
G01X394367Y1121960D01*
X393559Y1123359D01*
X393469Y1123376D01*
G02X392414Y1124651I243J1275D01*
G37*
G36*
G01X399814D02*
G02X402408I1297J0D01*
G02X402336Y1124223I-1297J-2D01*
G01X402305Y1124136D01*
X403112Y1122739D01*
X403202Y1122722D01*
G02X404260Y1121447I-239J-1275D01*
G02X401664I-1298J0D01*
G02X401737Y1121874I1298J-2D01*
G01X401767Y1121960D01*
X400959Y1123359D01*
X400869Y1123376D01*
G02X399814Y1124651I243J1275D01*
G37*
G36*
G01X407214D02*
G02X409808I1297J0D01*
G02X409736Y1124223I-1297J-2D01*
G01X409705Y1124136D01*
X410512Y1122739D01*
X410602Y1122722D01*
G02X411660Y1121447I-239J-1275D01*
G02X409064I-1298J0D01*
G02X409137Y1121874I1298J-2D01*
G01X409167Y1121960D01*
X408359Y1123359D01*
X408269Y1123376D01*
G02X407214Y1124651I243J1275D01*
G37*
G36*
G01X470114D02*
G02X472708I1297J0D01*
G02X471653Y1123376I-1298J0D01*
G01X471563Y1123359D01*
X470756Y1121962D01*
X470787Y1121875D01*
G02X470860Y1121447I-1225J-429D01*
G02X468264I-1298J0D01*
G02X469320Y1122722I1298J0D01*
G01X469410Y1122739D01*
X470217Y1124136D01*
X470186Y1124223D01*
G02X470114Y1124651I1225J426D01*
G37*
G36*
G01X477514D02*
G02X480108I1297J0D01*
G02X479053Y1123376I-1298J0D01*
G01X478963Y1123359D01*
X478156Y1121962D01*
X478187Y1121875D01*
G02X478260Y1121447I-1225J-429D01*
G02X475664I-1298J0D01*
G02X476720Y1122722I1298J0D01*
G01X476810Y1122739D01*
X477617Y1124136D01*
X477586Y1124223D01*
G02X477514Y1124651I1225J426D01*
G37*
G36*
G01X484914D02*
G02X487508I1297J0D01*
G02X486453Y1123376I-1298J0D01*
G01X486363Y1123359D01*
X485556Y1121962D01*
X485587Y1121875D01*
G02X485660Y1121447I-1225J-429D01*
G02X483064I-1298J0D01*
G02X484120Y1122722I1298J0D01*
G01X484210Y1122739D01*
X485017Y1124136D01*
X484986Y1124223D01*
G02X484914Y1124651I1225J426D01*
G37*
G36*
G01X492314D02*
G02X494908I1297J0D01*
G02X493853Y1123376I-1298J0D01*
G01X493763Y1123359D01*
X492956Y1121962D01*
X492987Y1121875D01*
G02X493060Y1121447I-1225J-429D01*
G02X490464I-1298J0D01*
G02X491520Y1122722I1298J0D01*
G01X491610Y1122739D01*
X492417Y1124136D01*
X492386Y1124223D01*
G02X492314Y1124651I1225J426D01*
G37*
G36*
G01X499714D02*
G02X502308I1297J0D01*
G02X501253Y1123376I-1298J0D01*
G01X501163Y1123359D01*
X500356Y1121962D01*
X500387Y1121875D01*
G02X500460Y1121447I-1225J-429D01*
G02X497864I-1298J0D01*
G02X498920Y1122722I1298J0D01*
G01X499010Y1122739D01*
X499817Y1124136D01*
X499786Y1124223D01*
G02X499714Y1124651I1225J426D01*
G37*
G36*
G01X507114D02*
G02X509708I1297J0D01*
G02X508653Y1123376I-1298J0D01*
G01X508563Y1123359D01*
X507756Y1121962D01*
X507787Y1121875D01*
G02X507860Y1121447I-1225J-429D01*
G02X505264I-1298J0D01*
G02X506320Y1122722I1298J0D01*
G01X506410Y1122739D01*
X507217Y1124136D01*
X507186Y1124223D01*
G02X507114Y1124651I1225J426D01*
G37*
G36*
G01X514514D02*
G02X517108I1297J0D01*
G02X516053Y1123376I-1298J0D01*
G01X515963Y1123359D01*
X515156Y1121962D01*
X515187Y1121875D01*
G02X515260Y1121447I-1225J-429D01*
G02X512664I-1298J0D01*
G02X513720Y1122722I1298J0D01*
G01X513810Y1122739D01*
X514617Y1124136D01*
X514586Y1124223D01*
G02X514514Y1124651I1225J426D01*
G37*
G36*
G01X521914D02*
G02X524508I1297J0D01*
G02X523453Y1123376I-1298J0D01*
G01X523363Y1123359D01*
X522556Y1121962D01*
X522587Y1121875D01*
G02X522660Y1121447I-1225J-429D01*
G02X520064I-1298J0D01*
G02X521120Y1122722I1298J0D01*
G01X521210Y1122739D01*
X522017Y1124136D01*
X521986Y1124223D01*
G02X521914Y1124651I1225J426D01*
G37*
G36*
G01X1331556D02*
G02X1334152I1298J0D01*
G02X1334079Y1124223I-1298J1D01*
G01X1334048Y1124136D01*
X1334855Y1122739D01*
X1334945Y1122722D01*
G02X1336000Y1121447I-243J-1275D01*
G02X1333406I-1297J0D01*
G02X1333478Y1121876I1297J3D01*
G01X1333509Y1121962D01*
X1332702Y1123359D01*
X1332612Y1123376D01*
G02X1331556Y1124651I242J1275D01*
G37*
G36*
G01X1338956D02*
G02X1341550I1297J0D01*
G02X1341478Y1124223I-1297J-2D01*
G01X1341447Y1124136D01*
X1342254Y1122739D01*
X1342344Y1122722D01*
G02X1343402Y1121447I-239J-1275D01*
G02X1340806I-1298J0D01*
G02X1340879Y1121874I1298J-2D01*
G01X1340909Y1121960D01*
X1340101Y1123359D01*
X1340011Y1123376D01*
G02X1338956Y1124651I243J1275D01*
G37*
G36*
G01X1346356D02*
G02X1348950I1297J0D01*
G02X1348878Y1124223I-1297J-2D01*
G01X1348847Y1124136D01*
X1349654Y1122739D01*
X1349744Y1122722D01*
G02X1350802Y1121447I-239J-1275D01*
G02X1348206I-1298J0D01*
G02X1348279Y1121874I1298J-2D01*
G01X1348309Y1121960D01*
X1347501Y1123359D01*
X1347411Y1123376D01*
G02X1346356Y1124651I243J1275D01*
G37*
G36*
G01X1353756D02*
G02X1356350I1297J0D01*
G02X1356278Y1124223I-1297J-2D01*
G01X1356247Y1124136D01*
X1357054Y1122739D01*
X1357144Y1122722D01*
G02X1358202Y1121447I-239J-1275D01*
G02X1355606I-1298J0D01*
G02X1355679Y1121874I1298J-2D01*
G01X1355709Y1121960D01*
X1354901Y1123359D01*
X1354811Y1123376D01*
G02X1353756Y1124651I243J1275D01*
G37*
G36*
G01X1361156D02*
G02X1363750I1297J0D01*
G02X1363678Y1124223I-1297J-2D01*
G01X1363647Y1124136D01*
X1364454Y1122739D01*
X1364544Y1122722D01*
G02X1365602Y1121447I-239J-1275D01*
G02X1363006I-1298J0D01*
G02X1363079Y1121874I1298J-2D01*
G01X1363109Y1121960D01*
X1362301Y1123359D01*
X1362211Y1123376D01*
G02X1361156Y1124651I243J1275D01*
G37*
G36*
G01X1368556D02*
G02X1371150I1297J0D01*
G02X1371078Y1124223I-1297J-2D01*
G01X1371047Y1124136D01*
X1371854Y1122739D01*
X1371944Y1122722D01*
G02X1373002Y1121447I-239J-1275D01*
G02X1370406I-1298J0D01*
G02X1370479Y1121874I1298J-2D01*
G01X1370509Y1121960D01*
X1369701Y1123359D01*
X1369611Y1123376D01*
G02X1368556Y1124651I243J1275D01*
G37*
G36*
G01X1375956D02*
G02X1378550I1297J0D01*
G02X1378478Y1124223I-1297J-2D01*
G01X1378447Y1124136D01*
X1379254Y1122739D01*
X1379344Y1122722D01*
G02X1380402Y1121447I-239J-1275D01*
G02X1377806I-1298J0D01*
G02X1377879Y1121874I1298J-2D01*
G01X1377909Y1121960D01*
X1377101Y1123359D01*
X1377011Y1123376D01*
G02X1375956Y1124651I243J1275D01*
G37*
G36*
G01X1383356D02*
G02X1385950I1297J0D01*
G02X1385878Y1124223I-1297J-2D01*
G01X1385847Y1124136D01*
X1386654Y1122739D01*
X1386744Y1122722D01*
G02X1387802Y1121447I-239J-1275D01*
G02X1385206I-1298J0D01*
G02X1385279Y1121874I1298J-2D01*
G01X1385309Y1121960D01*
X1384501Y1123359D01*
X1384411Y1123376D01*
G02X1383356Y1124651I243J1275D01*
G37*
G36*
G01X1446256D02*
G02X1448850I1297J0D01*
G02X1447795Y1123376I-1298J0D01*
G01X1447705Y1123359D01*
X1446898Y1121962D01*
X1446929Y1121875D01*
G02X1447002Y1121447I-1225J-429D01*
G02X1444406I-1298J0D01*
G02X1445462Y1122722I1298J0D01*
G01X1445552Y1122739D01*
X1446359Y1124136D01*
X1446328Y1124223D01*
G02X1446256Y1124651I1225J426D01*
G37*
G36*
G01X1453656D02*
G02X1456250I1297J0D01*
G02X1455195Y1123376I-1298J0D01*
G01X1455105Y1123359D01*
X1454298Y1121962D01*
X1454329Y1121875D01*
G02X1454402Y1121447I-1225J-429D01*
G02X1451806I-1298J0D01*
G02X1452862Y1122722I1298J0D01*
G01X1452952Y1122739D01*
X1453759Y1124136D01*
X1453728Y1124223D01*
G02X1453656Y1124651I1225J426D01*
G37*
G36*
G01X1461056D02*
G02X1463650I1297J0D01*
G02X1462595Y1123376I-1298J0D01*
G01X1462505Y1123359D01*
X1461698Y1121962D01*
X1461729Y1121875D01*
G02X1461802Y1121447I-1225J-429D01*
G02X1459206I-1298J0D01*
G02X1460262Y1122722I1298J0D01*
G01X1460352Y1122739D01*
X1461159Y1124136D01*
X1461128Y1124223D01*
G02X1461056Y1124651I1225J426D01*
G37*
G36*
G01X1468456D02*
G02X1471050I1297J0D01*
G02X1469995Y1123376I-1298J0D01*
G01X1469905Y1123359D01*
X1469098Y1121962D01*
X1469129Y1121875D01*
G02X1469202Y1121447I-1225J-429D01*
G02X1466606I-1298J0D01*
G02X1467662Y1122722I1298J0D01*
G01X1467752Y1122739D01*
X1468559Y1124136D01*
X1468528Y1124223D01*
G02X1468456Y1124651I1225J426D01*
G37*
G36*
G01X1475856D02*
G02X1478450I1297J0D01*
G02X1477395Y1123376I-1298J0D01*
G01X1477305Y1123359D01*
X1476498Y1121962D01*
X1476529Y1121875D01*
G02X1476602Y1121447I-1225J-429D01*
G02X1474006I-1298J0D01*
G02X1475062Y1122722I1298J0D01*
G01X1475152Y1122739D01*
X1475959Y1124136D01*
X1475928Y1124223D01*
G02X1475856Y1124651I1225J426D01*
G37*
G36*
G01X1483256D02*
G02X1485850I1297J0D01*
G02X1484795Y1123376I-1298J0D01*
G01X1484705Y1123359D01*
X1483898Y1121962D01*
X1483929Y1121875D01*
G02X1484002Y1121447I-1225J-429D01*
G02X1481406I-1298J0D01*
G02X1482462Y1122722I1298J0D01*
G01X1482552Y1122739D01*
X1483359Y1124136D01*
X1483328Y1124223D01*
G02X1483256Y1124651I1225J426D01*
G37*
G36*
G01X1490656D02*
G02X1493250I1297J0D01*
G02X1492195Y1123376I-1298J0D01*
G01X1492105Y1123359D01*
X1491298Y1121962D01*
X1491329Y1121875D01*
G02X1491402Y1121447I-1225J-429D01*
G02X1488806I-1298J0D01*
G02X1489862Y1122722I1298J0D01*
G01X1489952Y1122739D01*
X1490759Y1124136D01*
X1490728Y1124223D01*
G02X1490656Y1124651I1225J426D01*
G37*
G36*
G01X1498056D02*
G02X1500650I1297J0D01*
G02X1499595Y1123376I-1298J0D01*
G01X1499505Y1123359D01*
X1498698Y1121962D01*
X1498729Y1121875D01*
G02X1498802Y1121447I-1225J-429D01*
G02X1496206I-1298J0D01*
G02X1497262Y1122722I1298J0D01*
G01X1497352Y1122739D01*
X1498159Y1124136D01*
X1498128Y1124223D01*
G02X1498056Y1124651I1225J426D01*
G37*
G36*
G01X353564Y1127856D02*
G02X356158I1297J0D01*
G02X355103Y1126581I-1298J0D01*
G01X355013Y1126564D01*
X354205Y1125166D01*
X354236Y1125079D01*
G02X354308Y1124651I-1225J-426D01*
G02X351714I-1297J0D01*
G02X352769Y1125926I1298J0D01*
G01X352859Y1125943D01*
X353667Y1127341D01*
X353636Y1127428D01*
G02X353564Y1127856I1225J426D01*
G37*
G36*
G01X360964D02*
G02X363560I1298J0D01*
G02X362504Y1126581I-1298J0D01*
G01X362414Y1126564D01*
X361606Y1125166D01*
X361637Y1125079D01*
G02X361710Y1124651I-1225J-429D01*
G02X359114I-1298J0D01*
G02X360170Y1125926I1298J0D01*
G01X360260Y1125943D01*
X361068Y1127341D01*
X361037Y1127428D01*
G02X360964Y1127856I1225J429D01*
G37*
G36*
G01X368364D02*
G02X370960I1298J0D01*
G02X369904Y1126581I-1298J0D01*
G01X369814Y1126564D01*
X369006Y1125165D01*
X369036Y1125078D01*
G02X369108Y1124653I-1225J-426D01*
G01Y1124651D01*
G02X366514I-1297J0D01*
G02X367570Y1125926I1298J0D01*
G01X367661Y1125943D01*
X368468Y1127341D01*
X368437Y1127428D01*
G02X368364Y1127856I1225J429D01*
G37*
G36*
G01X375764D02*
G02X378360I1298J0D01*
G02X377304Y1126581I-1298J0D01*
G01X377214Y1126564D01*
X376406Y1125165D01*
X376436Y1125078D01*
G02X376508Y1124653I-1225J-426D01*
G01Y1124651D01*
G02X373914I-1297J0D01*
G02X374970Y1125926I1298J0D01*
G01X375061Y1125943D01*
X375868Y1127341D01*
X375837Y1127428D01*
G02X375764Y1127856I1225J429D01*
G37*
G36*
G01X383164D02*
G02X385760I1298J0D01*
G02X384704Y1126581I-1298J0D01*
G01X384614Y1126564D01*
X383806Y1125165D01*
X383836Y1125078D01*
G02X383908Y1124653I-1225J-426D01*
G01Y1124651D01*
G02X381314I-1297J0D01*
G02X382370Y1125926I1298J0D01*
G01X382461Y1125943D01*
X383268Y1127341D01*
X383237Y1127428D01*
G02X383164Y1127856I1225J429D01*
G37*
G36*
G01X390564D02*
G02X393160I1298J0D01*
G02X392104Y1126581I-1298J0D01*
G01X392014Y1126564D01*
X391206Y1125165D01*
X391236Y1125078D01*
G02X391308Y1124653I-1225J-426D01*
G01Y1124651D01*
G02X388714I-1297J0D01*
G02X389770Y1125926I1298J0D01*
G01X389861Y1125943D01*
X390668Y1127341D01*
X390637Y1127428D01*
G02X390564Y1127856I1225J429D01*
G37*
G36*
G01X397964D02*
G02X400560I1298J0D01*
G02X399504Y1126581I-1298J0D01*
G01X399414Y1126564D01*
X398606Y1125165D01*
X398636Y1125078D01*
G02X398708Y1124653I-1225J-426D01*
G01Y1124651D01*
G02X396114I-1297J0D01*
G02X397170Y1125926I1298J0D01*
G01X397261Y1125943D01*
X398068Y1127341D01*
X398037Y1127428D01*
G02X397964Y1127856I1225J429D01*
G37*
G36*
G01X405364D02*
G02X407960I1298J0D01*
G02X406904Y1126581I-1298J0D01*
G01X406814Y1126564D01*
X406006Y1125165D01*
X406036Y1125078D01*
G02X406108Y1124653I-1225J-426D01*
G01Y1124651D01*
G02X403514I-1297J0D01*
G02X404570Y1125926I1298J0D01*
G01X404661Y1125943D01*
X405468Y1127341D01*
X405437Y1127428D01*
G02X405364Y1127856I1225J429D01*
G37*
G36*
G01X471964D02*
G02X474560I1298J0D01*
G02X474487Y1127427I-1297J0D01*
G01X474456Y1127341D01*
X475263Y1125943D01*
X475353Y1125926D01*
G02X476408Y1124651I-243J-1275D01*
G02X473814I-1297J0D01*
G02X473886Y1125080I1297J3D01*
G01X473917Y1125166D01*
X473110Y1126564D01*
X473020Y1126581D01*
G02X471964Y1127856I242J1275D01*
G37*
G36*
G01X479364D02*
G02X481960I1298J0D01*
G02X481887Y1127427I-1297J0D01*
G01X481856Y1127341D01*
X482663Y1125943D01*
X482753Y1125926D01*
G02X483808Y1124651I-243J-1275D01*
G02X481214I-1297J0D01*
G02X481286Y1125080I1297J3D01*
G01X481317Y1125166D01*
X480510Y1126564D01*
X480420Y1126581D01*
G02X479364Y1127856I242J1275D01*
G37*
G36*
G01X486764D02*
G02X489360I1298J0D01*
G02X489287Y1127427I-1297J0D01*
G01X489256Y1127341D01*
X490063Y1125943D01*
X490153Y1125926D01*
G02X491208Y1124651I-243J-1275D01*
G02X488614I-1297J0D01*
G02X488686Y1125080I1297J3D01*
G01X488717Y1125166D01*
X487910Y1126564D01*
X487820Y1126581D01*
G02X486764Y1127856I242J1275D01*
G37*
G36*
G01X494164D02*
G02X496760I1298J0D01*
G02X496687Y1127427I-1297J0D01*
G01X496656Y1127341D01*
X497463Y1125943D01*
X497553Y1125926D01*
G02X498608Y1124651I-243J-1275D01*
G02X496014I-1297J0D01*
G02X496086Y1125080I1297J3D01*
G01X496117Y1125166D01*
X495310Y1126564D01*
X495220Y1126581D01*
G02X494164Y1127856I242J1275D01*
G37*
G36*
G01X501564D02*
G02X504160I1298J0D01*
G02X504087Y1127427I-1297J0D01*
G01X504056Y1127341D01*
X504863Y1125943D01*
X504953Y1125926D01*
G02X506008Y1124651I-243J-1275D01*
G02X503414I-1297J0D01*
G02X503486Y1125080I1297J3D01*
G01X503517Y1125166D01*
X502710Y1126564D01*
X502620Y1126581D01*
G02X501564Y1127856I242J1275D01*
G37*
G36*
G01X508964D02*
G02X511560I1298J0D01*
G02X511487Y1127427I-1297J0D01*
G01X511456Y1127341D01*
X512263Y1125943D01*
X512353Y1125926D01*
G02X513408Y1124651I-243J-1275D01*
G02X510814I-1297J0D01*
G02X510886Y1125080I1297J3D01*
G01X510917Y1125166D01*
X510110Y1126564D01*
X510020Y1126581D01*
G02X508964Y1127856I242J1275D01*
G37*
G36*
G01X516364D02*
G02X518960I1298J0D01*
G02X518887Y1127427I-1297J0D01*
G01X518856Y1127341D01*
X519663Y1125943D01*
X519753Y1125926D01*
G02X520808Y1124651I-243J-1275D01*
G02X518214I-1297J0D01*
G02X518286Y1125080I1297J3D01*
G01X518317Y1125166D01*
X517510Y1126564D01*
X517420Y1126581D01*
G02X516364Y1127856I242J1275D01*
G37*
G36*
G01X523764D02*
G02X526360I1298J0D01*
G02X526287Y1127427I-1297J0D01*
G01X526256Y1127341D01*
X527063Y1125943D01*
X527153Y1125926D01*
G02X528208Y1124651I-243J-1275D01*
G02X525614I-1297J0D01*
G02X525686Y1125080I1297J3D01*
G01X525717Y1125166D01*
X524910Y1126564D01*
X524820Y1126581D01*
G02X523764Y1127856I242J1275D01*
G37*
G36*
G01X1329706D02*
G02X1332300I1297J0D01*
G02X1331245Y1126581I-1298J0D01*
G01X1331155Y1126564D01*
X1330347Y1125166D01*
X1330378Y1125079D01*
G02X1330450Y1124651I-1225J-426D01*
G02X1327856I-1297J0D01*
G02X1328911Y1125926I1298J0D01*
G01X1329001Y1125943D01*
X1329809Y1127341D01*
X1329778Y1127428D01*
G02X1329706Y1127856I1225J426D01*
G37*
G36*
G01X1337106D02*
G02X1339702I1298J0D01*
G02X1338646Y1126581I-1298J0D01*
G01X1338556Y1126564D01*
X1337748Y1125166D01*
X1337779Y1125079D01*
G02X1337852Y1124651I-1225J-429D01*
G02X1335256I-1298J0D01*
G02X1336312Y1125926I1298J0D01*
G01X1336402Y1125943D01*
X1337210Y1127341D01*
X1337179Y1127428D01*
G02X1337106Y1127856I1225J429D01*
G37*
G36*
G01X1344506D02*
G02X1347102I1298J0D01*
G02X1346046Y1126581I-1298J0D01*
G01X1345956Y1126564D01*
X1345148Y1125165D01*
X1345178Y1125078D01*
G02X1345250Y1124653I-1225J-426D01*
G01Y1124651D01*
G02X1342656I-1297J0D01*
G02X1343712Y1125926I1298J0D01*
G01X1343803Y1125943D01*
X1344610Y1127341D01*
X1344579Y1127428D01*
G02X1344506Y1127856I1225J429D01*
G37*
G36*
G01X1351906D02*
G02X1354502I1298J0D01*
G02X1353446Y1126581I-1298J0D01*
G01X1353356Y1126564D01*
X1352548Y1125165D01*
X1352578Y1125078D01*
G02X1352650Y1124653I-1225J-426D01*
G01Y1124651D01*
G02X1350056I-1297J0D01*
G02X1351112Y1125926I1298J0D01*
G01X1351203Y1125943D01*
X1352010Y1127341D01*
X1351979Y1127428D01*
G02X1351906Y1127856I1225J429D01*
G37*
G36*
G01X1359306D02*
G02X1361902I1298J0D01*
G02X1360846Y1126581I-1298J0D01*
G01X1360756Y1126564D01*
X1359948Y1125165D01*
X1359978Y1125078D01*
G02X1360050Y1124653I-1225J-426D01*
G01Y1124651D01*
G02X1357456I-1297J0D01*
G02X1358512Y1125926I1298J0D01*
G01X1358603Y1125943D01*
X1359410Y1127341D01*
X1359379Y1127428D01*
G02X1359306Y1127856I1225J429D01*
G37*
G36*
G01X1366706D02*
G02X1369302I1298J0D01*
G02X1368246Y1126581I-1298J0D01*
G01X1368156Y1126564D01*
X1367348Y1125165D01*
X1367378Y1125078D01*
G02X1367450Y1124653I-1225J-426D01*
G01Y1124651D01*
G02X1364856I-1297J0D01*
G02X1365912Y1125926I1298J0D01*
G01X1366003Y1125943D01*
X1366810Y1127341D01*
X1366779Y1127428D01*
G02X1366706Y1127856I1225J429D01*
G37*
G36*
G01X1374106D02*
G02X1376702I1298J0D01*
G02X1375646Y1126581I-1298J0D01*
G01X1375556Y1126564D01*
X1374748Y1125165D01*
X1374778Y1125078D01*
G02X1374850Y1124653I-1225J-426D01*
G01Y1124651D01*
G02X1372256I-1297J0D01*
G02X1373312Y1125926I1298J0D01*
G01X1373403Y1125943D01*
X1374210Y1127341D01*
X1374179Y1127428D01*
G02X1374106Y1127856I1225J429D01*
G37*
G36*
G01X1381506D02*
G02X1384102I1298J0D01*
G02X1383046Y1126581I-1298J0D01*
G01X1382956Y1126564D01*
X1382148Y1125165D01*
X1382178Y1125078D01*
G02X1382250Y1124653I-1225J-426D01*
G01Y1124651D01*
G02X1379656I-1297J0D01*
G02X1380712Y1125926I1298J0D01*
G01X1380803Y1125943D01*
X1381610Y1127341D01*
X1381579Y1127428D01*
G02X1381506Y1127856I1225J429D01*
G37*
G36*
G01X1448106D02*
G02X1450702I1298J0D01*
G02X1450629Y1127427I-1297J0D01*
G01X1450598Y1127341D01*
X1451405Y1125943D01*
X1451495Y1125926D01*
G02X1452550Y1124651I-243J-1275D01*
G02X1449956I-1297J0D01*
G02X1450028Y1125080I1297J3D01*
G01X1450059Y1125166D01*
X1449252Y1126564D01*
X1449162Y1126581D01*
G02X1448106Y1127856I242J1275D01*
G37*
G36*
G01X1455506D02*
G02X1458102I1298J0D01*
G02X1458029Y1127427I-1297J0D01*
G01X1457998Y1127341D01*
X1458805Y1125943D01*
X1458895Y1125926D01*
G02X1459950Y1124651I-243J-1275D01*
G02X1457356I-1297J0D01*
G02X1457428Y1125080I1297J3D01*
G01X1457459Y1125166D01*
X1456652Y1126564D01*
X1456562Y1126581D01*
G02X1455506Y1127856I242J1275D01*
G37*
G36*
G01X1462906D02*
G02X1465502I1298J0D01*
G02X1465429Y1127427I-1297J0D01*
G01X1465398Y1127341D01*
X1466205Y1125943D01*
X1466295Y1125926D01*
G02X1467350Y1124651I-243J-1275D01*
G02X1464756I-1297J0D01*
G02X1464828Y1125080I1297J3D01*
G01X1464859Y1125166D01*
X1464052Y1126564D01*
X1463962Y1126581D01*
G02X1462906Y1127856I242J1275D01*
G37*
G36*
G01X1470306D02*
G02X1472902I1298J0D01*
G02X1472829Y1127427I-1297J0D01*
G01X1472798Y1127341D01*
X1473605Y1125943D01*
X1473695Y1125926D01*
G02X1474750Y1124651I-243J-1275D01*
G02X1472156I-1297J0D01*
G02X1472228Y1125080I1297J3D01*
G01X1472259Y1125166D01*
X1471452Y1126564D01*
X1471362Y1126581D01*
G02X1470306Y1127856I242J1275D01*
G37*
G36*
G01X1477706D02*
G02X1480302I1298J0D01*
G02X1480229Y1127427I-1297J0D01*
G01X1480198Y1127341D01*
X1481005Y1125943D01*
X1481095Y1125926D01*
G02X1482150Y1124651I-243J-1275D01*
G02X1479556I-1297J0D01*
G02X1479628Y1125080I1297J3D01*
G01X1479659Y1125166D01*
X1478852Y1126564D01*
X1478762Y1126581D01*
G02X1477706Y1127856I242J1275D01*
G37*
G36*
G01X1485106D02*
G02X1487702I1298J0D01*
G02X1487629Y1127427I-1297J0D01*
G01X1487598Y1127341D01*
X1488405Y1125943D01*
X1488495Y1125926D01*
G02X1489550Y1124651I-243J-1275D01*
G02X1486956I-1297J0D01*
G02X1487028Y1125080I1297J3D01*
G01X1487059Y1125166D01*
X1486252Y1126564D01*
X1486162Y1126581D01*
G02X1485106Y1127856I242J1275D01*
G37*
G36*
G01X1492506D02*
G02X1495102I1298J0D01*
G02X1495029Y1127427I-1297J0D01*
G01X1494998Y1127341D01*
X1495805Y1125943D01*
X1495895Y1125926D01*
G02X1496950Y1124651I-243J-1275D01*
G02X1494356I-1297J0D01*
G02X1494428Y1125080I1297J3D01*
G01X1494459Y1125166D01*
X1493652Y1126564D01*
X1493562Y1126581D01*
G02X1492506Y1127856I242J1275D01*
G37*
G36*
G01X1499906D02*
G02X1502502I1298J0D01*
G02X1502429Y1127427I-1297J0D01*
G01X1502398Y1127341D01*
X1503205Y1125943D01*
X1503295Y1125926D01*
G02X1504350Y1124651I-243J-1275D01*
G02X1501756I-1297J0D01*
G02X1501828Y1125080I1297J3D01*
G01X1501859Y1125166D01*
X1501052Y1126564D01*
X1500962Y1126581D01*
G02X1499906Y1127856I242J1275D01*
G37*
G36*
G01X340614Y1131060D02*
G02X343208I1297J0D01*
G02X342153Y1129785I-1298J0D01*
G01X342063Y1129768D01*
X341256Y1128370D01*
X341286Y1128284D01*
G02X341358Y1127856I-1225J-426D01*
G02X338764I-1297J0D01*
G02X339819Y1129131I1298J0D01*
G01X339909Y1129148D01*
X340716Y1130546D01*
X340686Y1130632D01*
G02X340614Y1131060I1225J426D01*
G37*
G36*
G01X1316756D02*
G02X1319350I1297J0D01*
G02X1318295Y1129785I-1298J0D01*
G01X1318205Y1129768D01*
X1317398Y1128370D01*
X1317428Y1128284D01*
G02X1317500Y1127856I-1225J-426D01*
G02X1314906I-1297J0D01*
G02X1315961Y1129131I1298J0D01*
G01X1316051Y1129148D01*
X1316858Y1130546D01*
X1316828Y1130632D01*
G02X1316756Y1131060I1225J426D01*
G37*
G36*
G01X348014Y1137469D02*
G02X350610I1298J0D01*
G02X350537Y1137040I-1297J0D01*
G01X350506Y1136954D01*
X351313Y1135556D01*
X351403Y1135539D01*
G02X352458Y1134264I-243J-1275D01*
G02X349864I-1297J0D01*
G02X349936Y1134693I1297J3D01*
G01X349967Y1134779D01*
X349160Y1136177D01*
X349070Y1136194D01*
G02X348014Y1137469I242J1275D01*
G37*
G36*
G01X355414D02*
G02X358010I1298J0D01*
G02X357937Y1137040I-1297J0D01*
G01X357906Y1136954D01*
X358713Y1135556D01*
X358803Y1135539D01*
G02X359858Y1134264I-243J-1275D01*
G02X357264I-1297J0D01*
G02X357336Y1134693I1297J3D01*
G01X357367Y1134779D01*
X356560Y1136177D01*
X356470Y1136194D01*
G02X355414Y1137469I242J1275D01*
G37*
G36*
G01X362814D02*
G02X365410I1298J0D01*
G02X365337Y1137041I-1298J1D01*
G01X365306Y1136954D01*
X366114Y1135556D01*
X366204Y1135539D01*
G02X367260Y1134264I-242J-1275D01*
G02X364664I-1298J0D01*
G02X364737Y1134692I1298J-1D01*
G01X364768Y1134779D01*
X363960Y1136177D01*
X363870Y1136194D01*
G02X362814Y1137469I242J1275D01*
G37*
G36*
G01X370214D02*
G02X372810I1298J0D01*
G02X372737Y1137041I-1298J1D01*
G01X372706Y1136954D01*
X373514Y1135556D01*
X373604Y1135539D01*
G02X374660Y1134264I-242J-1275D01*
G02X372064I-1298J0D01*
G02X372137Y1134692I1298J-1D01*
G01X372168Y1134779D01*
X371360Y1136177D01*
X371270Y1136194D01*
G02X370214Y1137469I242J1275D01*
G37*
G36*
G01X377614D02*
G02X380210I1298J0D01*
G02X380137Y1137041I-1298J1D01*
G01X380106Y1136954D01*
X380914Y1135556D01*
X381004Y1135539D01*
G02X382060Y1134264I-242J-1275D01*
G02X379464I-1298J0D01*
G02X379537Y1134692I1298J-1D01*
G01X379568Y1134779D01*
X378760Y1136177D01*
X378670Y1136194D01*
G02X377614Y1137469I242J1275D01*
G37*
G36*
G01X385014D02*
G02X387610I1298J0D01*
G02X387537Y1137041I-1298J1D01*
G01X387506Y1136954D01*
X388314Y1135556D01*
X388404Y1135539D01*
G02X389460Y1134264I-242J-1275D01*
G02X386864I-1298J0D01*
G02X386937Y1134692I1298J-1D01*
G01X386968Y1134779D01*
X386160Y1136177D01*
X386070Y1136194D01*
G02X385014Y1137469I242J1275D01*
G37*
G36*
G01X392414D02*
G02X395010I1298J0D01*
G02X394937Y1137041I-1298J1D01*
G01X394906Y1136954D01*
X395714Y1135556D01*
X395804Y1135539D01*
G02X396860Y1134264I-242J-1275D01*
G02X394264I-1298J0D01*
G02X394337Y1134692I1298J-1D01*
G01X394368Y1134779D01*
X393560Y1136177D01*
X393470Y1136194D01*
G02X392414Y1137469I242J1275D01*
G37*
G36*
G01X399814D02*
G02X402410I1298J0D01*
G02X402337Y1137041I-1298J1D01*
G01X402306Y1136954D01*
X403114Y1135556D01*
X403204Y1135539D01*
G02X404260Y1134264I-242J-1275D01*
G02X401664I-1298J0D01*
G02X401737Y1134692I1298J-1D01*
G01X401768Y1134779D01*
X400960Y1136177D01*
X400870Y1136194D01*
G02X399814Y1137469I242J1275D01*
G37*
G36*
G01X407214D02*
G02X409810I1298J0D01*
G02X409737Y1137041I-1298J1D01*
G01X409706Y1136954D01*
X410514Y1135556D01*
X410604Y1135539D01*
G02X411660Y1134264I-242J-1275D01*
G02X409064I-1298J0D01*
G02X409137Y1134692I1298J-1D01*
G01X409168Y1134779D01*
X408360Y1136177D01*
X408270Y1136194D01*
G02X407214Y1137469I242J1275D01*
G37*
G36*
G01X477514D02*
G02X480110I1298J0D01*
G02X479054Y1136194I-1298J0D01*
G01X478964Y1136177D01*
X478156Y1134779D01*
X478187Y1134692D01*
G02X478260Y1134264I-1225J-429D01*
G02X475664I-1298J0D01*
G02X476720Y1135539I1298J0D01*
G01X476810Y1135556D01*
X477618Y1136954D01*
X477587Y1137041D01*
G02X477514Y1137469I1225J429D01*
G37*
G36*
G01X484914D02*
G02X487510I1298J0D01*
G02X486454Y1136194I-1298J0D01*
G01X486364Y1136177D01*
X485557Y1134779D01*
X485587Y1134692D01*
G02X485660Y1134264I-1225J-429D01*
G02X483064I-1298J0D01*
G02X484121Y1135539I1297J0D01*
G01X484211Y1135556D01*
X485018Y1136954D01*
X484987Y1137041D01*
G02X484914Y1137469I1225J429D01*
G37*
G36*
G01X492314D02*
G02X494910I1298J0D01*
G02X493854Y1136194I-1298J0D01*
G01X493764Y1136177D01*
X492957Y1134779D01*
X492987Y1134692D01*
G02X493060Y1134264I-1225J-429D01*
G02X490464I-1298J0D01*
G02X491521Y1135539I1297J0D01*
G01X491611Y1135556D01*
X492418Y1136954D01*
X492387Y1137041D01*
G02X492314Y1137469I1225J429D01*
G37*
G36*
G01X499714D02*
G02X502310I1298J0D01*
G02X501254Y1136194I-1298J0D01*
G01X501164Y1136177D01*
X500357Y1134779D01*
X500387Y1134692D01*
G02X500460Y1134264I-1225J-429D01*
G02X497864I-1298J0D01*
G02X498921Y1135539I1297J0D01*
G01X499011Y1135556D01*
X499818Y1136954D01*
X499787Y1137041D01*
G02X499714Y1137469I1225J429D01*
G37*
G36*
G01X507114D02*
G02X509710I1298J0D01*
G02X508654Y1136194I-1298J0D01*
G01X508564Y1136177D01*
X507757Y1134779D01*
X507787Y1134692D01*
G02X507860Y1134264I-1225J-429D01*
G02X505264I-1298J0D01*
G02X506321Y1135539I1297J0D01*
G01X506411Y1135556D01*
X507218Y1136954D01*
X507187Y1137041D01*
G02X507114Y1137469I1225J429D01*
G37*
G36*
G01X514514D02*
G02X517110I1298J0D01*
G02X516054Y1136194I-1298J0D01*
G01X515964Y1136177D01*
X515157Y1134779D01*
X515187Y1134692D01*
G02X515260Y1134264I-1225J-429D01*
G02X512664I-1298J0D01*
G02X513721Y1135539I1297J0D01*
G01X513811Y1135556D01*
X514618Y1136954D01*
X514587Y1137041D01*
G02X514514Y1137469I1225J429D01*
G37*
G36*
G01X521914D02*
G02X524510I1298J0D01*
G02X523454Y1136194I-1298J0D01*
G01X523364Y1136177D01*
X522557Y1134779D01*
X522587Y1134692D01*
G02X522660Y1134264I-1225J-429D01*
G02X520064I-1298J0D01*
G02X521121Y1135539I1297J0D01*
G01X521211Y1135556D01*
X522018Y1136954D01*
X521987Y1137041D01*
G02X521914Y1137469I1225J429D01*
G37*
G36*
G01X533014D02*
G02X535610I1298J0D01*
G02X534554Y1136194I-1298J0D01*
G01X534464Y1136177D01*
X533656Y1134779D01*
X533687Y1134692D01*
G02X533760Y1134264I-1225J-429D01*
G02X531164I-1298J0D01*
G02X532220Y1135539I1298J0D01*
G01X532310Y1135556D01*
X533118Y1136954D01*
X533087Y1137041D01*
G02X533014Y1137469I1225J429D01*
G37*
G36*
G01X1324156D02*
G02X1326752I1298J0D01*
G02X1326679Y1137040I-1297J0D01*
G01X1326648Y1136954D01*
X1327455Y1135556D01*
X1327545Y1135539D01*
G02X1328600Y1134264I-243J-1275D01*
G02X1326006I-1297J0D01*
G02X1326078Y1134693I1297J3D01*
G01X1326109Y1134779D01*
X1325302Y1136177D01*
X1325212Y1136194D01*
G02X1324156Y1137469I242J1275D01*
G37*
G36*
G01X1331556D02*
G02X1334152I1298J0D01*
G02X1334079Y1137040I-1297J0D01*
G01X1334048Y1136954D01*
X1334855Y1135556D01*
X1334945Y1135539D01*
G02X1336000Y1134264I-243J-1275D01*
G02X1333406I-1297J0D01*
G02X1333478Y1134693I1297J3D01*
G01X1333509Y1134779D01*
X1332702Y1136177D01*
X1332612Y1136194D01*
G02X1331556Y1137469I242J1275D01*
G37*
G36*
G01X1338956D02*
G02X1341552I1298J0D01*
G02X1341479Y1137041I-1298J1D01*
G01X1341448Y1136954D01*
X1342256Y1135556D01*
X1342346Y1135539D01*
G02X1343402Y1134264I-242J-1275D01*
G02X1340806I-1298J0D01*
G02X1340879Y1134692I1298J-1D01*
G01X1340910Y1134779D01*
X1340102Y1136177D01*
X1340012Y1136194D01*
G02X1338956Y1137469I242J1275D01*
G37*
G36*
G01X1346356D02*
G02X1348952I1298J0D01*
G02X1348879Y1137041I-1298J1D01*
G01X1348848Y1136954D01*
X1349656Y1135556D01*
X1349746Y1135539D01*
G02X1350802Y1134264I-242J-1275D01*
G02X1348206I-1298J0D01*
G02X1348279Y1134692I1298J-1D01*
G01X1348310Y1134779D01*
X1347502Y1136177D01*
X1347412Y1136194D01*
G02X1346356Y1137469I242J1275D01*
G37*
G36*
G01X1353756D02*
G02X1356352I1298J0D01*
G02X1356279Y1137041I-1298J1D01*
G01X1356248Y1136954D01*
X1357056Y1135556D01*
X1357146Y1135539D01*
G02X1358202Y1134264I-242J-1275D01*
G02X1355606I-1298J0D01*
G02X1355679Y1134692I1298J-1D01*
G01X1355710Y1134779D01*
X1354902Y1136177D01*
X1354812Y1136194D01*
G02X1353756Y1137469I242J1275D01*
G37*
G36*
G01X1361156D02*
G02X1363752I1298J0D01*
G02X1363679Y1137041I-1298J1D01*
G01X1363648Y1136954D01*
X1364456Y1135556D01*
X1364546Y1135539D01*
G02X1365602Y1134264I-242J-1275D01*
G02X1363006I-1298J0D01*
G02X1363079Y1134692I1298J-1D01*
G01X1363110Y1134779D01*
X1362302Y1136177D01*
X1362212Y1136194D01*
G02X1361156Y1137469I242J1275D01*
G37*
G36*
G01X1368556D02*
G02X1371152I1298J0D01*
G02X1371079Y1137041I-1298J1D01*
G01X1371048Y1136954D01*
X1371856Y1135556D01*
X1371946Y1135539D01*
G02X1373002Y1134264I-242J-1275D01*
G02X1370406I-1298J0D01*
G02X1370479Y1134692I1298J-1D01*
G01X1370510Y1134779D01*
X1369702Y1136177D01*
X1369612Y1136194D01*
G02X1368556Y1137469I242J1275D01*
G37*
G36*
G01X1375956D02*
G02X1378552I1298J0D01*
G02X1378479Y1137041I-1298J1D01*
G01X1378448Y1136954D01*
X1379256Y1135556D01*
X1379346Y1135539D01*
G02X1380402Y1134264I-242J-1275D01*
G02X1377806I-1298J0D01*
G02X1377879Y1134692I1298J-1D01*
G01X1377910Y1134779D01*
X1377102Y1136177D01*
X1377012Y1136194D01*
G02X1375956Y1137469I242J1275D01*
G37*
G36*
G01X1383356D02*
G02X1385952I1298J0D01*
G02X1385879Y1137041I-1298J1D01*
G01X1385848Y1136954D01*
X1386656Y1135556D01*
X1386746Y1135539D01*
G02X1387802Y1134264I-242J-1275D01*
G02X1385206I-1298J0D01*
G02X1385279Y1134692I1298J-1D01*
G01X1385310Y1134779D01*
X1384502Y1136177D01*
X1384412Y1136194D01*
G02X1383356Y1137469I242J1275D01*
G37*
G36*
G01X1453656D02*
G02X1456252I1298J0D01*
G02X1455196Y1136194I-1298J0D01*
G01X1455106Y1136177D01*
X1454298Y1134779D01*
X1454329Y1134692D01*
G02X1454402Y1134264I-1225J-429D01*
G02X1451806I-1298J0D01*
G02X1452862Y1135539I1298J0D01*
G01X1452952Y1135556D01*
X1453760Y1136954D01*
X1453729Y1137041D01*
G02X1453656Y1137469I1225J429D01*
G37*
G36*
G01X1461056D02*
G02X1463652I1298J0D01*
G02X1462596Y1136194I-1298J0D01*
G01X1462506Y1136177D01*
X1461699Y1134779D01*
X1461729Y1134692D01*
G02X1461802Y1134264I-1225J-429D01*
G02X1459206I-1298J0D01*
G02X1460263Y1135539I1297J0D01*
G01X1460353Y1135556D01*
X1461160Y1136954D01*
X1461129Y1137041D01*
G02X1461056Y1137469I1225J429D01*
G37*
G36*
G01X1468456D02*
G02X1471052I1298J0D01*
G02X1469996Y1136194I-1298J0D01*
G01X1469906Y1136177D01*
X1469099Y1134779D01*
X1469129Y1134692D01*
G02X1469202Y1134264I-1225J-429D01*
G02X1466606I-1298J0D01*
G02X1467663Y1135539I1297J0D01*
G01X1467753Y1135556D01*
X1468560Y1136954D01*
X1468529Y1137041D01*
G02X1468456Y1137469I1225J429D01*
G37*
G36*
G01X1475856D02*
G02X1478452I1298J0D01*
G02X1477396Y1136194I-1298J0D01*
G01X1477306Y1136177D01*
X1476499Y1134779D01*
X1476529Y1134692D01*
G02X1476602Y1134264I-1225J-429D01*
G02X1474006I-1298J0D01*
G02X1475063Y1135539I1297J0D01*
G01X1475153Y1135556D01*
X1475960Y1136954D01*
X1475929Y1137041D01*
G02X1475856Y1137469I1225J429D01*
G37*
G36*
G01X1483256D02*
G02X1485852I1298J0D01*
G02X1484796Y1136194I-1298J0D01*
G01X1484706Y1136177D01*
X1483899Y1134779D01*
X1483929Y1134692D01*
G02X1484002Y1134264I-1225J-429D01*
G02X1481406I-1298J0D01*
G02X1482463Y1135539I1297J0D01*
G01X1482553Y1135556D01*
X1483360Y1136954D01*
X1483329Y1137041D01*
G02X1483256Y1137469I1225J429D01*
G37*
G36*
G01X1490656D02*
G02X1493252I1298J0D01*
G02X1492196Y1136194I-1298J0D01*
G01X1492106Y1136177D01*
X1491299Y1134779D01*
X1491329Y1134692D01*
G02X1491402Y1134264I-1225J-429D01*
G02X1488806I-1298J0D01*
G02X1489863Y1135539I1297J0D01*
G01X1489953Y1135556D01*
X1490760Y1136954D01*
X1490729Y1137041D01*
G02X1490656Y1137469I1225J429D01*
G37*
G36*
G01X1498056D02*
G02X1500652I1298J0D01*
G02X1499596Y1136194I-1298J0D01*
G01X1499506Y1136177D01*
X1498699Y1134779D01*
X1498729Y1134692D01*
G02X1498802Y1134264I-1225J-429D01*
G02X1496206I-1298J0D01*
G02X1497263Y1135539I1297J0D01*
G01X1497353Y1135556D01*
X1498160Y1136954D01*
X1498129Y1137041D01*
G02X1498056Y1137469I1225J429D01*
G37*
G36*
G01X1509156D02*
G02X1511752I1298J0D01*
G02X1510696Y1136194I-1298J0D01*
G01X1510606Y1136177D01*
X1509798Y1134779D01*
X1509829Y1134692D01*
G02X1509902Y1134264I-1225J-429D01*
G02X1507306I-1298J0D01*
G02X1508362Y1135539I1298J0D01*
G01X1508452Y1135556D01*
X1509260Y1136954D01*
X1509229Y1137041D01*
G02X1509156Y1137469I1225J429D01*
G37*
G36*
G01X360964Y1140973D02*
G02X363558I1297J0D01*
G02X362496Y1139697I-1298J0D01*
G01X362401Y1139679D01*
X361559Y1138084D01*
X361598Y1137995D01*
G02X361710Y1137469I-1186J-527D01*
G02X359114I-1298J0D01*
G02X360177Y1138745I1297J0D01*
G01X360272Y1138763D01*
X361114Y1140358D01*
X361075Y1140447D01*
G02X360964Y1140971I1186J525D01*
G01Y1140973D01*
G37*
G36*
G01X368364D02*
G02X370958I1297J0D01*
G02X369896Y1139697I-1298J0D01*
G01X369801Y1139679D01*
X368959Y1138084D01*
X368998Y1137995D01*
G02X369110Y1137469I-1186J-527D01*
G02X366514I-1298J0D01*
G02X367577Y1138745I1297J0D01*
G01X367672Y1138763D01*
X368514Y1140358D01*
X368475Y1140447D01*
G02X368364Y1140971I1186J525D01*
G01Y1140973D01*
G37*
G36*
G01X375764D02*
G02X378358I1297J0D01*
G02X377296Y1139697I-1298J0D01*
G01X377201Y1139679D01*
X376359Y1138084D01*
X376398Y1137995D01*
G02X376510Y1137469I-1186J-527D01*
G02X373914I-1298J0D01*
G02X374977Y1138745I1297J0D01*
G01X375072Y1138763D01*
X375914Y1140358D01*
X375875Y1140447D01*
G02X375764Y1140971I1186J525D01*
G01Y1140973D01*
G37*
G36*
G01X383164D02*
G02X385758I1297J0D01*
G02X384696Y1139697I-1298J0D01*
G01X384601Y1139679D01*
X383759Y1138084D01*
X383798Y1137995D01*
G02X383910Y1137469I-1186J-527D01*
G02X381314I-1298J0D01*
G02X382377Y1138745I1297J0D01*
G01X382472Y1138763D01*
X383314Y1140358D01*
X383275Y1140447D01*
G02X383164Y1140971I1186J525D01*
G01Y1140973D01*
G37*
G36*
G01X390564D02*
G02X393158I1297J0D01*
G02X392096Y1139697I-1298J0D01*
G01X392001Y1139679D01*
X391159Y1138084D01*
X391198Y1137995D01*
G02X391310Y1137469I-1186J-527D01*
G02X388714I-1298J0D01*
G02X389777Y1138745I1297J0D01*
G01X389872Y1138763D01*
X390714Y1140358D01*
X390675Y1140447D01*
G02X390564Y1140971I1186J525D01*
G01Y1140973D01*
G37*
G36*
G01X397964D02*
G02X400558I1297J0D01*
G02X399496Y1139697I-1298J0D01*
G01X399401Y1139679D01*
X398559Y1138084D01*
X398598Y1137995D01*
G02X398710Y1137469I-1186J-527D01*
G02X396114I-1298J0D01*
G02X397177Y1138745I1297J0D01*
G01X397272Y1138763D01*
X398114Y1140358D01*
X398075Y1140447D01*
G02X397964Y1140971I1186J525D01*
G01Y1140973D01*
G37*
G36*
G01X405364D02*
G02X407958I1297J0D01*
G02X406896Y1139697I-1298J0D01*
G01X406801Y1139679D01*
X405959Y1138084D01*
X405998Y1137995D01*
G02X406110Y1137469I-1186J-527D01*
G02X403514I-1298J0D01*
G02X404577Y1138745I1297J0D01*
G01X404672Y1138763D01*
X405514Y1140358D01*
X405475Y1140447D01*
G02X405364Y1140971I1186J525D01*
G01Y1140973D01*
G37*
G36*
G01X471964D02*
G02X474558I1297J0D01*
G02X474447Y1140448I-1297J0D01*
G01X474408Y1140359D01*
X475252Y1138763D01*
X475347Y1138745D01*
G02X476410Y1137469I-234J-1276D01*
G02X473814I-1298J0D01*
G02X473926Y1137994I1297J-2D01*
G01X473965Y1138083D01*
X473121Y1139679D01*
X473026Y1139697D01*
G02X471964Y1140973I236J1276D01*
G37*
G36*
G01X479364D02*
G02X481958I1297J0D01*
G02X481847Y1140448I-1297J0D01*
G01X481808Y1140359D01*
X482652Y1138763D01*
X482747Y1138745D01*
G02X483810Y1137469I-234J-1276D01*
G02X481214I-1298J0D01*
G02X481326Y1137994I1297J-2D01*
G01X481365Y1138083D01*
X480521Y1139679D01*
X480426Y1139697D01*
G02X479364Y1140973I236J1276D01*
G37*
G36*
G01X486764D02*
G02X489358I1297J0D01*
G02X489247Y1140448I-1297J0D01*
G01X489208Y1140359D01*
X490052Y1138763D01*
X490147Y1138745D01*
G02X491210Y1137469I-234J-1276D01*
G02X488614I-1298J0D01*
G02X488726Y1137994I1297J-2D01*
G01X488765Y1138083D01*
X487921Y1139679D01*
X487826Y1139697D01*
G02X486764Y1140973I236J1276D01*
G37*
G36*
G01X494164D02*
G02X496758I1297J0D01*
G02X496647Y1140448I-1297J0D01*
G01X496608Y1140359D01*
X497452Y1138763D01*
X497547Y1138745D01*
G02X498610Y1137469I-234J-1276D01*
G02X496014I-1298J0D01*
G02X496126Y1137994I1297J-2D01*
G01X496165Y1138083D01*
X495321Y1139679D01*
X495226Y1139697D01*
G02X494164Y1140973I236J1276D01*
G37*
G36*
G01X501564D02*
G02X504158I1297J0D01*
G02X504047Y1140448I-1297J0D01*
G01X504008Y1140359D01*
X504852Y1138763D01*
X504947Y1138745D01*
G02X506010Y1137469I-234J-1276D01*
G02X503414I-1298J0D01*
G02X503526Y1137994I1297J-2D01*
G01X503565Y1138083D01*
X502721Y1139679D01*
X502626Y1139697D01*
G02X501564Y1140973I236J1276D01*
G37*
G36*
G01X508964D02*
G02X511558I1297J0D01*
G02X511447Y1140448I-1297J0D01*
G01X511408Y1140359D01*
X512252Y1138763D01*
X512347Y1138745D01*
G02X513410Y1137469I-234J-1276D01*
G02X510814I-1298J0D01*
G02X510926Y1137994I1297J-2D01*
G01X510965Y1138083D01*
X510121Y1139679D01*
X510026Y1139697D01*
G02X508964Y1140973I236J1276D01*
G37*
G36*
G01X516364D02*
G02X518958I1297J0D01*
G02X518847Y1140448I-1297J0D01*
G01X518808Y1140359D01*
X519652Y1138763D01*
X519747Y1138745D01*
G02X520810Y1137469I-234J-1276D01*
G02X518214I-1298J0D01*
G02X518326Y1137994I1297J-2D01*
G01X518365Y1138083D01*
X517521Y1139679D01*
X517426Y1139697D01*
G02X516364Y1140973I236J1276D01*
G37*
G36*
G01X523764D02*
G02X526358I1297J0D01*
G02X526247Y1140448I-1297J0D01*
G01X526208Y1140359D01*
X527052Y1138763D01*
X527147Y1138745D01*
G02X528210Y1137469I-234J-1276D01*
G02X525614I-1298J0D01*
G02X525726Y1137994I1297J-2D01*
G01X525765Y1138083D01*
X524921Y1139679D01*
X524826Y1139697D01*
G02X523764Y1140973I236J1276D01*
G37*
G36*
G01X1337106D02*
G02X1339700I1297J0D01*
G02X1338638Y1139697I-1298J0D01*
G01X1338543Y1139679D01*
X1337701Y1138084D01*
X1337740Y1137995D01*
G02X1337852Y1137469I-1186J-527D01*
G02X1335256I-1298J0D01*
G02X1336319Y1138745I1297J0D01*
G01X1336414Y1138763D01*
X1337256Y1140358D01*
X1337217Y1140447D01*
G02X1337106Y1140971I1186J525D01*
G01Y1140973D01*
G37*
G36*
G01X1344506D02*
G02X1347100I1297J0D01*
G02X1346038Y1139697I-1298J0D01*
G01X1345943Y1139679D01*
X1345101Y1138084D01*
X1345140Y1137995D01*
G02X1345252Y1137469I-1186J-527D01*
G02X1342656I-1298J0D01*
G02X1343719Y1138745I1297J0D01*
G01X1343814Y1138763D01*
X1344656Y1140358D01*
X1344617Y1140447D01*
G02X1344506Y1140971I1186J525D01*
G01Y1140973D01*
G37*
G36*
G01X1351906D02*
G02X1354500I1297J0D01*
G02X1353438Y1139697I-1298J0D01*
G01X1353343Y1139679D01*
X1352501Y1138084D01*
X1352540Y1137995D01*
G02X1352652Y1137469I-1186J-527D01*
G02X1350056I-1298J0D01*
G02X1351119Y1138745I1297J0D01*
G01X1351214Y1138763D01*
X1352056Y1140358D01*
X1352017Y1140447D01*
G02X1351906Y1140971I1186J525D01*
G01Y1140973D01*
G37*
G36*
G01X1359306D02*
G02X1361900I1297J0D01*
G02X1360838Y1139697I-1298J0D01*
G01X1360743Y1139679D01*
X1359901Y1138084D01*
X1359940Y1137995D01*
G02X1360052Y1137469I-1186J-527D01*
G02X1357456I-1298J0D01*
G02X1358519Y1138745I1297J0D01*
G01X1358614Y1138763D01*
X1359456Y1140358D01*
X1359417Y1140447D01*
G02X1359306Y1140971I1186J525D01*
G01Y1140973D01*
G37*
G36*
G01X1366706D02*
G02X1369300I1297J0D01*
G02X1368238Y1139697I-1298J0D01*
G01X1368143Y1139679D01*
X1367301Y1138084D01*
X1367340Y1137995D01*
G02X1367452Y1137469I-1186J-527D01*
G02X1364856I-1298J0D01*
G02X1365919Y1138745I1297J0D01*
G01X1366014Y1138763D01*
X1366856Y1140358D01*
X1366817Y1140447D01*
G02X1366706Y1140971I1186J525D01*
G01Y1140973D01*
G37*
G36*
G01X1374106D02*
G02X1376700I1297J0D01*
G02X1375638Y1139697I-1298J0D01*
G01X1375543Y1139679D01*
X1374701Y1138084D01*
X1374740Y1137995D01*
G02X1374852Y1137469I-1186J-527D01*
G02X1372256I-1298J0D01*
G02X1373319Y1138745I1297J0D01*
G01X1373414Y1138763D01*
X1374256Y1140358D01*
X1374217Y1140447D01*
G02X1374106Y1140971I1186J525D01*
G01Y1140973D01*
G37*
G36*
G01X1381506D02*
G02X1384100I1297J0D01*
G02X1383038Y1139697I-1298J0D01*
G01X1382943Y1139679D01*
X1382101Y1138084D01*
X1382140Y1137995D01*
G02X1382252Y1137469I-1186J-527D01*
G02X1379656I-1298J0D01*
G02X1380719Y1138745I1297J0D01*
G01X1380814Y1138763D01*
X1381656Y1140358D01*
X1381617Y1140447D01*
G02X1381506Y1140971I1186J525D01*
G01Y1140973D01*
G37*
G36*
G01X1448106D02*
G02X1450700I1297J0D01*
G02X1450589Y1140448I-1297J0D01*
G01X1450550Y1140359D01*
X1451394Y1138763D01*
X1451489Y1138745D01*
G02X1452552Y1137469I-234J-1276D01*
G02X1449956I-1298J0D01*
G02X1450068Y1137994I1297J-2D01*
G01X1450107Y1138083D01*
X1449263Y1139679D01*
X1449168Y1139697D01*
G02X1448106Y1140973I236J1276D01*
G37*
G36*
G01X1455506D02*
G02X1458100I1297J0D01*
G02X1457989Y1140448I-1297J0D01*
G01X1457950Y1140359D01*
X1458794Y1138763D01*
X1458889Y1138745D01*
G02X1459952Y1137469I-234J-1276D01*
G02X1457356I-1298J0D01*
G02X1457468Y1137994I1297J-2D01*
G01X1457507Y1138083D01*
X1456663Y1139679D01*
X1456568Y1139697D01*
G02X1455506Y1140973I236J1276D01*
G37*
G36*
G01X1462906D02*
G02X1465500I1297J0D01*
G02X1465389Y1140448I-1297J0D01*
G01X1465350Y1140359D01*
X1466194Y1138763D01*
X1466289Y1138745D01*
G02X1467352Y1137469I-234J-1276D01*
G02X1464756I-1298J0D01*
G02X1464868Y1137994I1297J-2D01*
G01X1464907Y1138083D01*
X1464063Y1139679D01*
X1463968Y1139697D01*
G02X1462906Y1140973I236J1276D01*
G37*
G36*
G01X1470306D02*
G02X1472900I1297J0D01*
G02X1472789Y1140448I-1297J0D01*
G01X1472750Y1140359D01*
X1473594Y1138763D01*
X1473689Y1138745D01*
G02X1474752Y1137469I-234J-1276D01*
G02X1472156I-1298J0D01*
G02X1472268Y1137994I1297J-2D01*
G01X1472307Y1138083D01*
X1471463Y1139679D01*
X1471368Y1139697D01*
G02X1470306Y1140973I236J1276D01*
G37*
G36*
G01X1477706D02*
G02X1480300I1297J0D01*
G02X1480189Y1140448I-1297J0D01*
G01X1480150Y1140359D01*
X1480994Y1138763D01*
X1481089Y1138745D01*
G02X1482152Y1137469I-234J-1276D01*
G02X1479556I-1298J0D01*
G02X1479668Y1137994I1297J-2D01*
G01X1479707Y1138083D01*
X1478863Y1139679D01*
X1478768Y1139697D01*
G02X1477706Y1140973I236J1276D01*
G37*
G36*
G01X1485106D02*
G02X1487700I1297J0D01*
G02X1487589Y1140448I-1297J0D01*
G01X1487550Y1140359D01*
X1488394Y1138763D01*
X1488489Y1138745D01*
G02X1489552Y1137469I-234J-1276D01*
G02X1486956I-1298J0D01*
G02X1487068Y1137994I1297J-2D01*
G01X1487107Y1138083D01*
X1486263Y1139679D01*
X1486168Y1139697D01*
G02X1485106Y1140973I236J1276D01*
G37*
G36*
G01X1492506D02*
G02X1495100I1297J0D01*
G02X1494989Y1140448I-1297J0D01*
G01X1494950Y1140359D01*
X1495794Y1138763D01*
X1495889Y1138745D01*
G02X1496952Y1137469I-234J-1276D01*
G02X1494356I-1298J0D01*
G02X1494468Y1137994I1297J-2D01*
G01X1494507Y1138083D01*
X1493663Y1139679D01*
X1493568Y1139697D01*
G02X1492506Y1140973I236J1276D01*
G37*
G36*
G01X1499906D02*
G02X1502500I1297J0D01*
G02X1502389Y1140448I-1297J0D01*
G01X1502350Y1140359D01*
X1503194Y1138763D01*
X1503289Y1138745D01*
G02X1504352Y1137469I-234J-1276D01*
G02X1501756I-1298J0D01*
G02X1501868Y1137994I1297J-2D01*
G01X1501907Y1138083D01*
X1501063Y1139679D01*
X1500968Y1139697D01*
G02X1499906Y1140973I236J1276D01*
G37*
G36*
G01X1143020Y1540382D02*
G03X1143411Y1540758I-8J400D01*
G02X1145410Y1542642I1999J-119D01*
G02X1147412Y1540640I0J-2002D01*
G02X1145450Y1538638I-2002J0D01*
G03X1145059Y1538262I8J-400D01*
G02X1143060Y1536378I-1999J119D01*
G02X1141058Y1538380I0J2002D01*
G02X1143020Y1540382I2002J0D01*
G37*
G36*
G01X1162980Y1551449D02*
G03X1163635I328J229D01*
G02X1166917I1641J-1147D01*
G03X1167572I327J229D01*
G02X1169213Y1552304I1641J-1147D01*
G02Y1548298I0J-2003D01*
G02X1167572Y1549153I0J2002D01*
G03X1166917I-328J-229D01*
G02X1163635I-1641J1147D01*
G03X1162980I-327J-229D01*
G02X1159698I-1641J1147D01*
G03X1159043I-328J-229D01*
G02X1155761I-1641J1147D01*
G03X1155106I-328J-229D01*
G02X1151824I-1641J1147D01*
G03X1151169I-328J-229D01*
G02X1149528Y1548298I-1641J1147D01*
G02Y1552304I0J2003D01*
G02X1151169Y1551449I0J-2002D01*
G03X1151824I327J229D01*
G02X1155106I1641J-1147D01*
G03X1155761I328J229D01*
G02X1159043I1641J-1147D01*
G03X1159698I327J229D01*
G02X1162980I1641J-1147D01*
G37*
G36*
G01X1139652Y1550301D02*
Y1550302D01*
G02X1140157Y1551631I2002J0D01*
G02X1139688Y1552918I1533J1288D01*
G01Y1552920D01*
G02X1143692I2002J0D01*
G01Y1552919D01*
G02X1143187Y1551590I-2002J0D01*
G02X1143656Y1550303I-1533J-1288D01*
G01Y1550301D01*
G02X1139652I-2002J0D01*
G37*
G36*
G01X1101405Y1550386D02*
G03X1101083Y1550900I-382J119D01*
G02X1098098Y1554364I517J3464D01*
G02X1105102I3502J0D01*
G02X1104945Y1553324I-3502J-3D01*
G03X1105267Y1552810I382J-119D01*
G02X1108252Y1549346I-517J-3464D01*
G02X1101248I-3502J0D01*
G02X1101405Y1550386I3502J3D01*
G37*
G36*
G01X1143823Y1573272D02*
G03X1143551I-136J-147D01*
G02X1142188Y1572736I-1363J1466D01*
G01X1142187D01*
G02Y1576740I0J2002D01*
G01X1142188D01*
G02X1143551Y1576204I0J-2002D01*
G03X1143823I136J147D01*
G02X1145186Y1576740I1363J-1466D01*
G01X1145187D01*
G02Y1572736I0J-2002D01*
G01X1145186D01*
G02X1143823Y1573272I0J2002D01*
G37*
G36*
G01X1153823D02*
G03X1153551I-136J-147D01*
G02X1152188Y1572736I-1363J1466D01*
G01X1152187D01*
G02Y1576740I0J2002D01*
G01X1152188D01*
G02X1153551Y1576204I0J-2002D01*
G03X1153823I136J147D01*
G02X1155186Y1576740I1363J-1466D01*
G01X1155187D01*
G02Y1572736I0J-2002D01*
G01X1155186D01*
G02X1153823Y1573272I0J2002D01*
G37*
G36*
G01X1163231D02*
G03X1162959I-136J-147D01*
G02X1161596Y1572736I-1363J1466D01*
G01X1161595D01*
G02Y1576740I0J2002D01*
G01X1161596D01*
G02X1162959Y1576204I0J-2002D01*
G03X1163231I136J147D01*
G02X1164594Y1576740I1363J-1466D01*
G01X1164595D01*
G02Y1572736I0J-2002D01*
G01X1164594D01*
G02X1163231Y1573272I0J2002D01*
G37*
G36*
G01X1173231D02*
G03X1172959I-136J-147D01*
G02X1171596Y1572736I-1363J1466D01*
G01X1171595D01*
G02Y1576740I0J2002D01*
G01X1171596D01*
G02X1172959Y1576204I0J-2002D01*
G03X1173231I136J147D01*
G02X1174594Y1576740I1363J-1466D01*
G01X1174595D01*
G02Y1572736I0J-2002D01*
G01X1174594D01*
G02X1173231Y1573272I0J2002D01*
G37*
G36*
G01X1133823Y1581272D02*
G03X1133551I-136J-147D01*
G02X1132188Y1580736I-1363J1466D01*
G01X1132187D01*
G02Y1584740I0J2002D01*
G01X1132188D01*
G02X1133551Y1584204I0J-2002D01*
G03X1133823I136J147D01*
G02X1135186Y1584740I1363J-1466D01*
G01X1135187D01*
G02Y1580736I0J-2002D01*
G01X1135186D01*
G02X1133823Y1581272I0J2002D01*
G37*
G36*
G01X1143823D02*
G03X1143551I-136J-147D01*
G02X1142188Y1580736I-1363J1466D01*
G01X1142187D01*
G02Y1584740I0J2002D01*
G01X1142188D01*
G02X1143551Y1584204I0J-2002D01*
G03X1143823I136J147D01*
G02X1145186Y1584740I1363J-1466D01*
G01X1145187D01*
G02Y1580736I0J-2002D01*
G01X1145186D01*
G02X1143823Y1581272I0J2002D01*
G37*
G36*
G01X1153823D02*
G03X1153551I-136J-147D01*
G02X1152188Y1580736I-1363J1466D01*
G01X1152187D01*
G02Y1584740I0J2002D01*
G01X1152188D01*
G02X1153551Y1584204I0J-2002D01*
G03X1153823I136J147D01*
G02X1155186Y1584740I1363J-1466D01*
G01X1155187D01*
G02Y1580736I0J-2002D01*
G01X1155186D01*
G02X1153823Y1581272I0J2002D01*
G37*
G36*
G01X1163231D02*
G03X1162959I-136J-147D01*
G02X1161596Y1580736I-1363J1466D01*
G01X1161595D01*
G02Y1584740I0J2002D01*
G01X1161596D01*
G02X1162959Y1584204I0J-2002D01*
G03X1163231I136J147D01*
G02X1164594Y1584740I1363J-1466D01*
G01X1164595D01*
G02Y1580736I0J-2002D01*
G01X1164594D01*
G02X1163231Y1581272I0J2002D01*
G37*
G36*
G01X1173231D02*
G03X1172959I-136J-147D01*
G02X1171596Y1580736I-1363J1466D01*
G01X1171595D01*
G02Y1584740I0J2002D01*
G01X1171596D01*
G02X1172959Y1584204I0J-2002D01*
G03X1173231I136J147D01*
G02X1174594Y1584740I1363J-1466D01*
G01X1174595D01*
G02Y1580736I0J-2002D01*
G01X1174594D01*
G02X1173231Y1581272I0J2002D01*
G37*
G36*
G01X1133823Y1589272D02*
G03X1133551I-136J-147D01*
G02X1132188Y1588736I-1363J1466D01*
G01X1132187D01*
G02Y1592740I0J2002D01*
G01X1132188D01*
G02X1133551Y1592204I0J-2002D01*
G03X1133823I136J147D01*
G02X1135186Y1592740I1363J-1466D01*
G01X1135187D01*
G02Y1588736I0J-2002D01*
G01X1135186D01*
G02X1133823Y1589272I0J2002D01*
G37*
G36*
G01X1143823D02*
G03X1143551I-136J-147D01*
G02X1142188Y1588736I-1363J1466D01*
G01X1142187D01*
G02Y1592740I0J2002D01*
G01X1142188D01*
G02X1143551Y1592204I0J-2002D01*
G03X1143823I136J147D01*
G02X1145186Y1592740I1363J-1466D01*
G01X1145187D01*
G02Y1588736I0J-2002D01*
G01X1145186D01*
G02X1143823Y1589272I0J2002D01*
G37*
G36*
G01X1153823D02*
G03X1153551I-136J-147D01*
G02X1152188Y1588736I-1363J1466D01*
G01X1152187D01*
G02Y1592740I0J2002D01*
G01X1152188D01*
G02X1153551Y1592204I0J-2002D01*
G03X1153823I136J147D01*
G02X1155186Y1592740I1363J-1466D01*
G01X1155187D01*
G02Y1588736I0J-2002D01*
G01X1155186D01*
G02X1153823Y1589272I0J2002D01*
G37*
G36*
G01X1163231D02*
G03X1162959I-136J-147D01*
G02X1161596Y1588736I-1363J1466D01*
G01X1161595D01*
G02Y1592740I0J2002D01*
G01X1161596D01*
G02X1162959Y1592204I0J-2002D01*
G03X1163231I136J147D01*
G02X1164594Y1592740I1363J-1466D01*
G01X1164595D01*
G02Y1588736I0J-2002D01*
G01X1164594D01*
G02X1163231Y1589272I0J2002D01*
G37*
G36*
G01X1173231D02*
G03X1172959I-136J-147D01*
G02X1171596Y1588736I-1363J1466D01*
G01X1171595D01*
G02Y1592740I0J2002D01*
G01X1171596D01*
G02X1172959Y1592204I0J-2002D01*
G03X1173231I136J147D01*
G02X1174594Y1592740I1363J-1466D01*
G01X1174595D01*
G02Y1588736I0J-2002D01*
G01X1174594D01*
G02X1173231Y1589272I0J2002D01*
G37*
G36*
G01X1411037Y1711457D02*
G03X1411142Y1712134I-151J370D01*
G02X1421732I5295J6330D01*
G03X1421837Y1711457I256J-307D01*
G02X1430690Y1698267I-5399J-13190D01*
G02X1402184I-14253J0D01*
G02X1411037Y1711457I14252J0D01*
G37*
G36*
G01X435643Y1711458D02*
G03X435748Y1712135I-151J370D01*
G02X446338I5295J6330D01*
G03X446443Y1711458I256J-307D01*
G02X455296Y1698268I-5399J-13190D01*
G02X426790I-14253J0D01*
G02X435643Y1711458I14252J0D01*
G37*
G54D105*
X1137717Y1558020D03*
G54D102*
X1290005Y293768D03*
G54D98*
X1455787Y1421784D03*
X1710550Y691327D03*
X479646Y1421784D03*
X93547Y692260D03*
G54D103*
X1175215Y1532913D03*
X1131715D03*
G54D83*
X1307572Y-26511D03*
X1040152Y-16511D03*
X1015152D03*
X1307572Y13489D03*
X1282572Y23489D03*
X1307572D03*
X1282572Y13489D03*
X1040152Y23489D03*
Y13489D03*
X973180Y-6500D03*
X998180D03*
X1015152Y13489D03*
X1282572Y-16511D03*
X973180Y-26500D03*
X998180D03*
Y-16500D03*
X1015152Y23489D03*
X1307572Y-16511D03*
X973180Y-16500D03*
X1474931Y23489D03*
X1499931D03*
X705760Y-26500D03*
X730760D03*
X705760Y-6500D03*
Y-16500D03*
X730760D03*
Y-6500D03*
X1474931Y13489D03*
X998180Y3500D03*
X973180D03*
X1499931Y13489D03*
X998180Y13500D03*
Y23500D03*
X973180D03*
Y13500D03*
X1499931Y-16511D03*
X1474931D03*
X1324471Y23489D03*
X1349471D03*
X822720Y3500D03*
X847720D03*
X822720Y23500D03*
Y13500D03*
X847720D03*
Y23500D03*
X1324471Y-16511D03*
X1349471D03*
X1324471Y13489D03*
X1349471D03*
X1307572Y-36511D03*
X1282572D03*
Y-26511D03*
X1307572Y-6511D03*
Y3489D03*
X1282572D03*
Y-6511D03*
X1015152Y-36511D03*
Y-26511D03*
X1040152D03*
Y-36511D03*
X1015152Y3489D03*
Y-6511D03*
X1040152D03*
Y3489D03*
X1499931Y-26511D03*
Y-36511D03*
X1474931D03*
Y-26511D03*
X1499931Y-6511D03*
Y3489D03*
X1474931D03*
Y-6511D03*
X1324471Y-36511D03*
Y-26511D03*
X1349471D03*
Y-36511D03*
X1324471Y3489D03*
Y-6511D03*
X1349471D03*
Y3489D03*
G54D90*
X70472Y173228D03*
Y236220D03*
G54D94*
X1565236Y184783D03*
Y264035D03*
G54D95*
X929331Y160413D03*
X922441Y237697D03*
X1534712Y20354D03*
X1787330Y24291D03*
X505185Y41142D03*
X757803Y45079D03*
X312921Y24291D03*
G54D93*
X676508Y224606D03*
G54D92*
Y145866D03*
G54D89*
X1829725Y130315D03*
G54D85*
X791280Y1704890D03*
X1066280D03*
G54D100*
X1405118Y112008D03*
G54D82*
X1341752Y-31511D03*
Y-21511D03*
Y-11511D03*
Y-1511D03*
X1482650Y-31511D03*
Y-21511D03*
Y-11511D03*
Y-1511D03*
X90998Y1517237D03*
X78120Y1517136D03*
X99750Y1563678D03*
X75922Y1560674D03*
X404030Y1593690D03*
X957156Y228863D03*
X899830Y973184D03*
X1380522Y261936D03*
X1388754Y255503D03*
X1380638Y247394D03*
X1386630Y240351D03*
X397406Y1634842D03*
X1031950Y385471D03*
X736710Y605542D03*
X527310Y96447D03*
X414406Y1626692D03*
X460910Y1627472D03*
X64410Y1600802D03*
X1340420Y540122D03*
X704770Y204921D03*
X896060Y482922D03*
X716698Y210721D03*
X704770Y216732D03*
X895340Y499582D03*
X907470Y213680D03*
X902350Y220768D03*
X953970Y206575D03*
X716698Y198887D03*
X704770Y193110D03*
Y181299D03*
X947496Y227835D03*
X705800Y169488D03*
X947496Y213697D03*
X907470Y227854D03*
X941050Y530552D03*
X968286Y482241D03*
X716698Y175387D03*
X902350Y206594D03*
X944032Y435931D03*
X716698Y187387D03*
X944250Y196189D03*
X954420Y512952D03*
Y498852D03*
G54D101*
X1247638Y269488D03*
G54D97*
X1550708Y991220D03*
X525275Y1171319D03*
X1332204D03*
X1326240Y811122D03*
X1501417Y1171319D03*
X1507381Y811122D03*
X1282913Y991220D03*
X306771D03*
X574566D03*
X350098Y811122D03*
X531240D03*
X356062Y1171319D03*
G54D81*
X723041Y-11500D03*
Y-21500D03*
X840001Y8500D03*
Y18500D03*
X980899Y-21500D03*
Y-11500D03*
Y8500D03*
Y18500D03*
X1032433Y-31511D03*
Y-21511D03*
Y-11511D03*
Y-1511D03*
X1290291Y-31511D03*
Y-21511D03*
Y-11511D03*
Y-1511D03*
X62813Y414300D03*
X47619Y417205D03*
X1386273Y270370D03*
X615573Y178034D03*
X628195Y174214D03*
X1282645Y253971D03*
X941059Y426211D03*
X901829Y514430D03*
X889439Y491299D03*
X1407029Y154432D03*
X922879Y530276D03*
X946727Y506252D03*
G54D96*
X1819208Y1420330D03*
X38346D03*
G54D84*
X19685Y-29134D03*
X1837795D03*
X1808192Y1569255D03*
X41870Y1511291D03*
X1812980Y502472D03*
X49280Y337402D03*
X441043Y1672205D03*
X1416437Y1672204D03*
X2081889Y1803261D03*
Y-29134D03*
G54D91*
X1057658Y204724D03*
X805690D03*
G54D99*
X763602Y605413D03*
X1739744D03*
X1094075Y605378D03*
X117933D03*
G54D104*
X841240Y1420330D03*
X1016240D03*
G54D88*
X1680327Y277236D03*
X1153555Y277208D03*
X704185Y277236D03*
X177413Y277208D03*
G54D86*
X177311Y1657953D03*
G54D87*
X1680232D03*
%LPC*%
G75*
G36*
G01X917256Y1656436D02*
G03X918140Y1656070I884J885D01*
G01X1064422D01*
X1084287Y1636205D01*
G03X1085358Y1635600I1071J645D01*
G01X1101560D01*
X1103140Y1634020D01*
Y1607480D01*
X1102240Y1606580D01*
X944270D01*
X917966Y1632884D01*
G03X917082Y1633250I-884J-885D01*
G01X816320D01*
X812960Y1636610D01*
Y1714140D01*
X817460Y1718640D01*
X900700D01*
X907010Y1712330D01*
Y1667200D01*
G03X907376Y1666316I1251J0D01*
G01X917256Y1656436D01*
G37*
%LPD*%
G75*
G54D15*
X16925Y203366D03*
X17061Y196368D03*
X24720Y216362D03*
Y232362D03*
Y224362D03*
Y240362D03*
X16420Y420662D03*
X26500Y672862D03*
Y675862D03*
X27300Y764200D03*
X27520Y1245162D03*
X33500Y200862D03*
X33670Y192862D03*
Y208362D03*
X30795Y213358D03*
X33670Y232362D03*
X42500Y224409D03*
X30795Y227366D03*
X33670Y240362D03*
X40000Y298707D03*
X36000Y295952D03*
X40000Y293392D03*
X33105Y304972D03*
X35740Y363337D03*
X39320Y392269D03*
X40940Y387302D03*
X43020Y382942D03*
X41933Y395652D03*
X45960Y428806D03*
X38220Y589862D03*
Y592862D03*
X33020Y595232D03*
X32720Y598402D03*
X34790Y666595D03*
X31390D03*
X38470Y688122D03*
Y683122D03*
Y680622D03*
Y685622D03*
Y693122D03*
Y690622D03*
Y695622D03*
X34899Y711400D03*
X45700Y724100D03*
X45800Y726874D03*
X43841Y1248688D03*
X44833Y1656759D03*
X48269Y1672771D03*
X62020Y295952D03*
X62731Y305426D03*
X59322Y360702D03*
X51114Y360862D03*
X53406Y402862D03*
X49360Y428806D03*
X61171D03*
X47619Y418655D03*
X47618Y415613D03*
X48400Y586000D03*
X57595Y603476D03*
X59500Y738700D03*
X56777Y1314165D03*
X56799Y1520094D03*
Y1536094D03*
Y1540094D03*
Y1560094D03*
X59833Y1604359D03*
X54333Y1613359D03*
X50333D03*
X54478Y1663669D03*
X54535Y1658447D03*
X57833Y1671809D03*
X53333Y1671862D03*
X65000Y1681900D03*
X58325Y1679275D03*
X65937Y28403D03*
Y48720D03*
X77165Y278798D03*
Y295798D03*
Y286262D03*
Y303262D03*
X63429Y360702D03*
X67681D03*
X77220Y379022D03*
Y381522D03*
X68020Y395222D03*
X75516Y420319D03*
Y424319D03*
X64571Y428806D03*
X63540Y438802D03*
X72610Y441262D03*
Y444762D03*
X72981Y466385D03*
X77000Y485362D03*
X74550Y487812D03*
X80300Y641862D03*
X80241Y659011D03*
X80123Y664031D03*
X80135Y667933D03*
X74559Y667814D03*
X78080Y701832D03*
X63930Y739300D03*
X73759Y754726D03*
X68315Y765664D03*
X73759Y759246D03*
X72485Y1304152D03*
X75485D03*
X78485D03*
X72485Y1307152D03*
X75485D03*
X69485Y1304152D03*
Y1307152D03*
X65600Y1318588D03*
X65240Y1326068D03*
X75485Y1316152D03*
X72485Y1313152D03*
Y1310152D03*
X75485Y1313152D03*
Y1310152D03*
X69485D03*
X69809Y1333918D03*
Y1331418D03*
Y1336418D03*
X72809Y1333918D03*
Y1331418D03*
Y1336418D03*
X75809Y1333918D03*
Y1331418D03*
Y1336418D03*
X72909Y1339938D03*
X79009Y1340238D03*
X75909Y1339938D03*
X73027Y1347925D03*
X73059Y1345138D03*
X72987Y1342535D03*
X75909Y1342438D03*
X79009Y1342738D03*
Y1345238D03*
X78977Y1348025D03*
X75859Y1348138D03*
Y1345138D03*
X76369Y1507456D03*
X76680Y1530482D03*
X72774Y1546519D03*
X75922Y1558974D03*
Y1562374D03*
X77040Y1601102D03*
X65120Y1609909D03*
X65520Y1615972D03*
X74100Y1613300D03*
X77833Y1678902D03*
X73833Y1674252D03*
X69833Y1678582D03*
X87620Y285321D03*
X87845Y278798D03*
Y295798D03*
X87820Y302821D03*
X87520Y395865D03*
Y391391D03*
Y382219D03*
X85826Y428319D03*
X84410Y438519D03*
X83320Y445212D03*
X94439Y450081D03*
X81505Y447377D03*
X79400Y482862D03*
X91027Y643276D03*
X89859Y628246D03*
X86459D03*
X82961Y657111D03*
X95725Y654540D03*
X95860Y659622D03*
X83165Y652564D03*
X91078Y649584D03*
X83208Y646436D03*
X83250Y665428D03*
X84470Y668702D03*
X86433Y688160D03*
X81285Y689804D03*
X84035Y697604D03*
X93547Y692260D03*
X83004Y705141D03*
X97295Y699786D03*
X85095Y722164D03*
X95849Y716358D03*
X91610Y721414D03*
X82357Y737803D03*
X84623Y741249D03*
X81966Y759246D03*
X85877Y759275D03*
X93485Y1304152D03*
X87485D03*
X90485D03*
X93485Y1307152D03*
X84485Y1304152D03*
X81485D03*
X93485Y1318152D03*
Y1315652D03*
Y1310152D03*
Y1313152D03*
X94209Y1337738D03*
X81809Y1340238D03*
X84809D03*
X87809D03*
X90809D03*
X94209D03*
X84809Y1345238D03*
X81809Y1342738D03*
X84809D03*
X81809Y1348238D03*
Y1345238D03*
X84809Y1348238D03*
X87809D03*
Y1345238D03*
Y1342738D03*
X94209D03*
Y1348238D03*
Y1345238D03*
X90809Y1348238D03*
Y1345238D03*
Y1342738D03*
X88520Y1484482D03*
Y1491482D03*
Y1487982D03*
Y1494982D03*
X89264Y1507611D03*
X92664D03*
X79769Y1507456D03*
X87500Y1567069D03*
X91500D03*
X90713Y1581852D03*
Y1597867D03*
X81008Y1589872D03*
X90788Y1615821D03*
Y1601867D03*
X81900Y1613300D03*
X85800D03*
X90698Y1630362D03*
X90788Y1619821D03*
X90698Y1642362D03*
X90407Y1656672D03*
X88333Y1661334D03*
X81833Y1674526D03*
X86245Y1694362D03*
X96420Y1693803D03*
X86030Y1683092D03*
X113490Y216596D03*
X113400Y232128D03*
X110937Y285495D03*
Y302854D03*
X107200Y393562D03*
X107301Y388071D03*
X107419Y487807D03*
X104875Y490980D03*
X102384Y505374D03*
X112480Y507792D03*
X110689Y498271D03*
X110464Y505374D03*
X101983Y518100D03*
X99880Y526300D03*
X110060Y515279D03*
X99773Y515606D03*
X105587Y520727D03*
X106110Y633732D03*
X107489Y630917D03*
X110374Y630879D03*
X102269Y634466D03*
X107045Y661917D03*
X99021Y663732D03*
X103397Y667272D03*
X102120Y688650D03*
X102060Y692100D03*
X102420Y697262D03*
X96626Y736187D03*
X110527Y758869D03*
X108465Y1304292D03*
Y1307292D03*
X105475Y1304222D03*
Y1307222D03*
X102485Y1304152D03*
X99485D03*
X96485D03*
X102485Y1307152D03*
X99485D03*
X96485D03*
X108465Y1318292D03*
Y1310292D03*
Y1313292D03*
Y1315792D03*
X105475Y1318222D03*
Y1310222D03*
Y1313222D03*
Y1315722D03*
X99485Y1318152D03*
X96485D03*
Y1315652D03*
Y1310152D03*
Y1313152D03*
X99485Y1310152D03*
Y1313152D03*
Y1315652D03*
X102485Y1318152D03*
Y1310152D03*
Y1313152D03*
Y1315652D03*
X96809Y1340238D03*
Y1345238D03*
Y1348238D03*
Y1342738D03*
X112270Y1518907D03*
X99274Y1529169D03*
X96570Y1546187D03*
X99750Y1565378D03*
Y1561978D03*
X103902Y1584337D03*
X102251Y1576504D03*
X105651D03*
X104318Y1589352D03*
X100620Y1596367D03*
X101500Y1604400D03*
X100020Y1615821D03*
X98738Y1605867D03*
X104400Y1632385D03*
X104430Y1628012D03*
X104318Y1637862D03*
X99600Y1668332D03*
X99645Y1663217D03*
X99980Y1687921D03*
Y1698921D03*
X115850Y186362D03*
X122000Y207362D03*
X116920Y207462D03*
X118920Y278875D03*
X119220Y306236D03*
X119920Y379362D03*
X119457Y392071D03*
Y388071D03*
X125070Y486736D03*
X125013Y491829D03*
X124124Y495883D03*
X116171Y485041D03*
X112483Y510637D03*
X116411Y497707D03*
X118652Y528860D03*
X129762Y531942D03*
X115793Y528188D03*
X112393D03*
X111920Y632922D03*
X114540Y633032D03*
X117750Y633232D03*
X120440Y633347D03*
X121400Y638062D03*
X125890Y644163D03*
X122329Y654660D03*
X122280Y651934D03*
X124431Y649570D03*
X122575Y671930D03*
X118019Y661371D03*
X124737Y735726D03*
X118737D03*
X121737D03*
Y738726D03*
X118737D03*
X124737D03*
X123220Y1324662D03*
X120220D03*
X112749Y1532594D03*
Y1528594D03*
Y1552594D03*
Y1556594D03*
X117707Y1553759D03*
X125033Y1589352D03*
X116798D03*
X123230Y1597350D03*
X119500Y1622380D03*
X124795Y1681846D03*
X128195Y1674362D03*
X114645Y1698862D03*
X117220Y1683437D03*
X127195Y1696362D03*
Y1700362D03*
Y1704362D03*
X125082Y1727092D03*
X123394Y1723472D03*
X117426Y1726622D03*
X125720Y1719262D03*
X141520Y181462D03*
X139720Y179162D03*
X143470Y184012D03*
X133590Y212382D03*
X129394Y278875D03*
X129375Y274800D03*
X129394Y306236D03*
X135220Y397071D03*
X132490Y420062D03*
X138042Y480238D03*
X132833D03*
X136982Y497090D03*
X131737Y496295D03*
X135006Y487753D03*
X131295Y487822D03*
X141325Y503806D03*
X141462Y507600D03*
X141329Y510487D03*
X141220Y498810D03*
X138878Y512550D03*
X138408Y507366D03*
X139153Y516453D03*
X133160Y532002D03*
X132600Y537072D03*
Y540472D03*
X133467Y634531D03*
X131740Y640103D03*
X131600Y646861D03*
X131330Y665740D03*
X142960Y690807D03*
X140460D03*
X142754Y698811D03*
X140254D03*
X142778Y706835D03*
X140278D03*
X140326Y721660D03*
X142826D03*
X140142Y1392545D03*
Y1396275D03*
X129627Y1556360D03*
X129586Y1553759D03*
X129813Y1604367D03*
X130533Y1622321D03*
X129533Y1637862D03*
X137420Y1708362D03*
X144520Y1717562D03*
X141642Y1717592D03*
X134557Y1722778D03*
X137852Y1726572D03*
X147924Y28258D03*
X148784Y48720D03*
X145720Y186462D03*
Y202862D03*
Y206362D03*
X156670Y344542D03*
X159170D03*
X154220Y375682D03*
X158110Y376172D03*
X160090Y391170D03*
Y397470D03*
X152826Y439397D03*
Y434362D03*
X156306Y449045D03*
X153360Y449112D03*
X149557Y494353D03*
X150113Y488487D03*
X161267Y503143D03*
X149472Y506810D03*
X160000Y510052D03*
X152470Y495383D03*
X151378Y526924D03*
X149512Y514810D03*
X150800Y512021D03*
X153737Y514893D03*
X149504Y519881D03*
X154647Y521783D03*
X150877Y757969D03*
X151277Y1339183D03*
X153877D03*
X156477D03*
X156417Y1336343D03*
X151217Y1336393D03*
X153817D03*
X156417Y1333843D03*
X151217Y1333893D03*
X153817D03*
X151277Y1346883D03*
X153877D03*
X151277Y1349383D03*
X153877D03*
X156477Y1346883D03*
Y1349383D03*
Y1344383D03*
X151277D03*
X153877D03*
X156477Y1341883D03*
X151277D03*
X153877D03*
X147307Y1404745D03*
X149568Y1395145D03*
Y1397695D03*
X152684Y1403451D03*
X157490Y1421454D03*
X154990D03*
X159858Y1409361D03*
X155858Y1406669D03*
Y1409390D03*
X157530Y1432124D03*
X155030D03*
X157530Y1424124D03*
X155030D03*
X157530Y1429124D03*
X155030Y1426624D03*
Y1429124D03*
X157530Y1426624D03*
Y1435124D03*
X155030D03*
X157530Y1437754D03*
X155030D03*
X146390Y1504240D03*
X145538Y1517374D03*
X148938D03*
X153600Y1505600D03*
X147067Y1545985D03*
X157441Y1581932D03*
X146312Y1569525D03*
X149712D03*
X152026Y1614138D03*
X158335Y1614452D03*
X155180Y1619872D03*
X156070Y1695702D03*
X145745Y1712362D03*
X161310Y1708022D03*
X148145Y1701862D03*
X155145Y1713517D03*
X164830Y344542D03*
X161670D03*
X173275Y393497D03*
X164000Y415362D03*
X163926Y425383D03*
X164000Y420362D03*
X172507Y417205D03*
X163926Y430883D03*
Y443319D03*
Y439397D03*
Y435383D03*
X178546Y453806D03*
X172632Y454095D03*
X165176Y500782D03*
X176393Y575189D03*
X173793D03*
X176393Y572689D03*
X173793D03*
X171293D03*
Y575189D03*
X173793Y577790D03*
X171293D03*
X176393D03*
X176651Y596883D03*
Y594163D03*
X173878Y597027D03*
Y594307D03*
X176651Y599603D03*
X173878Y599747D03*
X161126Y721660D03*
X161078Y706835D03*
X163626Y721660D03*
X163578Y706835D03*
X170877Y1333783D03*
Y1336383D03*
X176077Y1333783D03*
X173477D03*
X176077Y1336383D03*
X173477D03*
X170907Y1339233D03*
X176107D03*
X173507D03*
X170877Y1341883D03*
X176077D03*
X173477D03*
Y1349383D03*
Y1346883D03*
Y1344383D03*
X176077D03*
Y1346883D03*
Y1349383D03*
X170877D03*
Y1346883D03*
Y1344383D03*
X176358Y1403669D03*
X176258Y1400669D03*
X173892Y1402749D03*
Y1405649D03*
X170922Y1399255D03*
X166262D03*
X173252Y1400005D03*
X168592D03*
X160490Y1421454D03*
X164000Y1408862D03*
X162257Y1406594D03*
X160530Y1432124D03*
Y1424124D03*
Y1429124D03*
Y1426624D03*
Y1435124D03*
Y1437754D03*
X165500Y1440362D03*
X173727Y1452134D03*
Y1448734D03*
X170570Y1509250D03*
X164710Y1518014D03*
X168110D03*
X173331Y1579399D03*
X172099Y1588141D03*
X164920Y1712017D03*
X163060Y1717017D03*
X178226Y1726517D03*
X172962Y1721234D03*
X169777Y1726517D03*
X178142Y1720652D03*
X186120Y24162D03*
X188620D03*
X190880Y383012D03*
Y387162D03*
Y391082D03*
X178375Y396571D03*
X181845Y401071D03*
X187371Y425383D03*
X187532Y421387D03*
X187371Y430883D03*
Y443383D03*
X180740Y437562D03*
X184550Y435712D03*
X187371Y440742D03*
X194440Y433895D03*
Y439565D03*
X187371Y447172D03*
X177871D03*
X181994Y453932D03*
X180640Y447172D03*
X185211Y453942D03*
X185191Y502439D03*
X186793Y575189D03*
X184193D03*
X186793Y572689D03*
X184193D03*
X181593Y575189D03*
X178993D03*
X181593Y572689D03*
X178993D03*
X189293Y575189D03*
X186793Y577790D03*
X184193D03*
X189293D03*
X181593D03*
X178993D03*
X181651Y596883D03*
X179151D03*
X186796Y594195D03*
Y596915D03*
X184151Y596883D03*
X179151Y594163D03*
X181651D03*
X184151D03*
X181651Y599603D03*
X179151D03*
X186796Y599635D03*
X184151Y599603D03*
X186720Y737862D03*
X180720D03*
X183720D03*
Y734862D03*
X180720D03*
X186720D03*
X185835Y757057D03*
X188978Y756855D03*
X191602Y756839D03*
X189377Y1333783D03*
X191977D03*
X189377Y1336383D03*
X191977D03*
X191947Y1339263D03*
X189347D03*
X189377Y1349383D03*
X191977D03*
X189377Y1346883D03*
X191977D03*
Y1344383D03*
X189377D03*
X191977Y1341883D03*
X189377D03*
X187711Y1395170D03*
Y1397670D03*
X190827Y1403451D03*
X180977Y1396173D03*
X178458Y1399269D03*
Y1402169D03*
Y1405069D03*
X188211Y1406691D03*
X186165Y1422589D03*
X183135Y1419784D03*
X180510Y1420258D03*
X177510D03*
X186135Y1419784D03*
X183165Y1422589D03*
X177510Y1423278D03*
X180510D03*
X183075Y1430424D03*
Y1425424D03*
Y1427924D03*
X186075Y1430424D03*
Y1425424D03*
Y1427924D03*
X183075Y1432924D03*
X186075D03*
X192600Y1557360D03*
X185895Y1557875D03*
X189600Y1566300D03*
X187400Y1568132D03*
X187542Y1729092D03*
X193293Y1722197D03*
X188794Y1725092D03*
X195050Y412055D03*
X199149Y425755D03*
Y420255D03*
Y414755D03*
X204699Y423242D03*
Y428742D03*
X195050Y417465D03*
X199149Y436755D03*
Y442255D03*
Y431255D03*
Y453255D03*
Y447755D03*
X197650Y455712D03*
X199149Y468255D03*
X208200Y493510D03*
X202338Y568746D03*
X201392Y574271D03*
X198336D03*
X204610Y571097D03*
X199164Y582481D03*
X200654Y578271D03*
X201622Y581009D03*
X208056Y591665D03*
X208806Y589335D03*
X208056Y587005D03*
X208806Y584675D03*
X202262Y592305D03*
X205162D03*
X202338Y602746D03*
X201392Y608271D03*
X198336D03*
X203892Y594471D03*
X202492Y596571D03*
X208292D03*
X206892Y594371D03*
X205392Y596571D03*
X204610Y605097D03*
X199164Y616481D03*
X200654Y612271D03*
X201622Y615009D03*
X208806Y618675D03*
X208056Y621005D03*
X208806Y623335D03*
X202338Y636746D03*
X208056Y625665D03*
X203892Y628471D03*
X202492Y630571D03*
X202262Y626305D03*
X208292Y630571D03*
X206892Y628371D03*
X205162Y626305D03*
X205392Y630571D03*
X204610Y639097D03*
X201392Y642271D03*
X199164Y650481D03*
X200654Y646271D03*
X201622Y649009D03*
X198336Y642271D03*
X208056Y655005D03*
X208806Y657335D03*
Y652675D03*
X207620Y671262D03*
X198420Y672662D03*
X198495Y669487D03*
X208056Y659665D03*
X205392Y664571D03*
X205162Y660305D03*
X206892Y662371D03*
X202262Y660305D03*
X202492Y664571D03*
X203892Y662471D03*
X208292Y664571D03*
X196049Y678195D03*
X194196Y687061D03*
X200018Y677492D03*
X193332Y678195D03*
X207129Y690027D03*
X203199Y690006D03*
X197086Y686326D03*
X203179Y693626D03*
X207140Y693636D03*
X195735Y696469D03*
X198235Y698969D03*
Y696469D03*
X200735Y698969D03*
Y696469D03*
X207140Y738462D03*
X205220Y736562D03*
X201220Y736662D03*
X203660Y731802D03*
X195602Y756839D03*
X203602Y756855D03*
X208977Y1336383D03*
Y1333783D03*
X194577D03*
Y1336383D03*
X209007Y1339263D03*
X194547D03*
X208977Y1341883D03*
X194577Y1349383D03*
Y1346883D03*
Y1344383D03*
X208977D03*
Y1346883D03*
Y1349383D03*
X194577Y1341883D03*
X206735Y1400005D03*
X209065Y1399255D03*
X204405D03*
X198001Y1409361D03*
X193941Y1407029D03*
X200797Y1409605D03*
X200492Y1406686D03*
X193941Y1409750D03*
X195966Y1542863D03*
X203120Y1624782D03*
X208115Y1624217D03*
X195590Y1714517D03*
X196010Y1709017D03*
X208295Y1703362D03*
X199050Y1726431D03*
X204600Y1733022D03*
X225407Y321831D03*
X209530Y426192D03*
X217770Y428262D03*
X224210Y431501D03*
X224305Y422977D03*
X219995Y426267D03*
X224210Y436619D03*
X218140Y440735D03*
X218010Y432735D03*
X223664Y443125D03*
X220000Y448735D03*
X212891Y566632D03*
X210391Y567981D03*
X212891Y601981D03*
X210391D03*
Y635981D03*
X212891D03*
X210320Y671262D03*
X224900Y713293D03*
X209720Y731862D03*
X220033Y756844D03*
X211602Y756855D03*
X216842Y756865D03*
X214177Y1336383D03*
X211577D03*
X214177Y1333783D03*
X211577D03*
X214207Y1339263D03*
X211607D03*
X214177Y1341883D03*
X211577D03*
X214177Y1349383D03*
Y1346883D03*
Y1344383D03*
X211577D03*
Y1346883D03*
Y1349383D03*
X211395Y1400005D03*
X214201Y1404169D03*
X212035Y1402899D03*
X214101Y1401169D03*
X216554Y1399264D03*
Y1402164D03*
Y1405064D03*
X212035Y1405799D03*
X219587Y1435402D03*
X217469Y1454725D03*
X219587Y1443402D03*
Y1439402D03*
X220869Y1454725D03*
X209820Y1631142D03*
X210593Y1714017D03*
X212120Y1703062D03*
X214120Y1713462D03*
X233339Y17662D03*
X235701Y21582D03*
X241310Y20322D03*
X229135Y26474D03*
X225735D03*
X238063Y26232D03*
X235701Y39570D03*
X229131Y50646D03*
X225731D03*
X239820Y54362D03*
X239720Y71862D03*
X239010Y78542D03*
X238297Y129703D03*
X234902Y174047D03*
X226800Y359464D03*
X230359Y461683D03*
X227430Y719772D03*
X238940Y716652D03*
X230864Y1254295D03*
X246510Y20362D03*
X242220Y39362D03*
X246220D03*
X250220D03*
X254050Y39422D03*
X246360Y26852D03*
X248820Y48962D03*
X252320D03*
X255820D03*
X257520Y51562D03*
X254020D03*
X250520D03*
X249885Y69623D03*
X245220Y67862D03*
X248097Y92143D03*
X247897Y100543D03*
X244822Y115543D03*
Y111543D03*
X253910Y115722D03*
X253878Y111771D03*
X243892Y140912D03*
X259933Y141122D03*
X257256Y156727D03*
X245490Y159702D03*
X252000Y395400D03*
X255810Y405582D03*
X252500Y415862D03*
X258066Y426735D03*
X256695Y461117D03*
X257750Y450842D03*
X254713Y518465D03*
X245700Y513262D03*
X250100Y521783D03*
X256885Y574805D03*
X254385D03*
X256855Y571995D03*
X251885Y574805D03*
X249800Y563262D03*
X254355Y589235D03*
X256855D03*
X251855D03*
X256855Y605995D03*
X251885Y608805D03*
X257643Y594220D03*
X255043D03*
Y596820D03*
X257643D03*
X256885Y608805D03*
X254385D03*
X256855Y603495D03*
X251855Y623265D03*
X254355D03*
X256855D03*
Y639995D03*
Y637495D03*
X257643Y628220D03*
X255043D03*
Y630820D03*
X257643D03*
X256885Y642805D03*
X254385D03*
X251855Y657265D03*
X251885Y642805D03*
X254355Y657265D03*
X256855D03*
X257643Y662220D03*
X255043D03*
Y664820D03*
X257643D03*
X253819Y675567D03*
X253849Y678077D03*
X256419Y675567D03*
X256449Y678077D03*
X251219Y675567D03*
X251249Y678077D03*
X248649D03*
X248989Y698827D03*
X249019Y693767D03*
X251589Y698827D03*
X251649Y696277D03*
X254189Y698827D03*
X251619Y693767D03*
X256849Y696277D03*
X256789Y698827D03*
X256819Y693767D03*
X254249Y696277D03*
X254219Y693767D03*
X248300Y703862D03*
X242460Y716652D03*
X253057Y755345D03*
X245487Y755435D03*
X259510Y757822D03*
X251187Y1255025D03*
X263240Y38122D03*
X266990Y41832D03*
X275120Y28562D03*
X275900Y48872D03*
X259320Y48962D03*
X261020Y51562D03*
X263520D03*
X261820Y48962D03*
X264740Y49182D03*
X266497Y69536D03*
Y72036D03*
X264720Y56362D03*
Y60362D03*
Y64362D03*
X266597Y77526D03*
Y80026D03*
X263320Y87662D03*
X261420Y100662D03*
X264920D03*
X268420D03*
X262920Y97962D03*
X266420D03*
X269920D03*
X273620Y96662D03*
X263550Y120922D03*
X269191Y121092D03*
X275797Y120245D03*
X265910Y125492D03*
X266975Y140107D03*
X260600Y151062D03*
X272800Y140162D03*
X264578Y151203D03*
X260100Y159562D03*
X265500Y227862D03*
X263000D03*
X260500Y227362D03*
Y224862D03*
X270240Y245332D03*
X271821Y251962D03*
X267759D03*
X259224Y419532D03*
X263430Y422235D03*
X259869Y431039D03*
X262963Y443735D03*
X272500Y447735D03*
X263040Y448752D03*
X272500Y452862D03*
X264055Y574505D03*
X264025Y571995D03*
X261555Y574505D03*
X261525Y571995D03*
X264055Y566935D03*
X263995Y569485D03*
X261495D03*
X261555Y566935D03*
X266555Y574505D03*
X266525Y571995D03*
X266495Y569485D03*
X266555Y566935D03*
X269055Y574505D03*
X269025Y571995D03*
X268995Y569485D03*
X269055Y566935D03*
X261465Y592115D03*
X261525Y589565D03*
X264025D03*
X263965Y592115D03*
X266525Y589565D03*
X266465Y592115D03*
X269025Y589565D03*
X268965Y592115D03*
X264025Y605995D03*
X261525D03*
X264055Y608505D03*
X261555D03*
X261435Y597175D03*
X261495Y594625D03*
X263995D03*
X263935Y597175D03*
X266525Y605995D03*
X266555Y608505D03*
X266435Y597175D03*
X266495Y594625D03*
X261525Y603495D03*
X264025D03*
X266525D03*
X269025Y605995D03*
X269055Y608505D03*
X268935Y597175D03*
X268995Y594625D03*
X269025Y603495D03*
X261495Y621055D03*
X263995D03*
X261525Y623565D03*
X264025D03*
X263995Y611055D03*
X261495D03*
X266495Y621055D03*
X266525Y623565D03*
X266495Y611055D03*
X268995Y621055D03*
X269025Y623565D03*
X268995Y611055D03*
X261525Y639995D03*
X264025D03*
X261525Y637495D03*
X266525Y639995D03*
X269025D03*
X264025Y637495D03*
X266525D03*
X269025D03*
X263965Y626115D03*
X261465D03*
X266465D03*
X268965D03*
X261495Y655055D03*
X263995D03*
X261525Y657565D03*
X264025D03*
X263995Y645055D03*
X264055Y642505D03*
X261495Y645055D03*
X261555Y642505D03*
X266495Y655055D03*
X266525Y657565D03*
X266495Y645055D03*
X266555Y642505D03*
X268995Y655055D03*
X269025Y657565D03*
X268995Y645055D03*
X269055Y642505D03*
X261465Y660115D03*
X263965D03*
X266465D03*
X268965D03*
X259049Y678077D03*
X259019Y675567D03*
X259419Y693767D03*
X259389Y698827D03*
X259449Y696277D03*
X269600Y715792D03*
X274247Y727165D03*
X268331Y738029D03*
X273046Y735662D03*
X270100Y727262D03*
X264000Y726262D03*
X266700Y730962D03*
X271570Y746422D03*
X265997Y747535D03*
X272208Y768516D03*
X271057Y765525D03*
Y762425D03*
X287000Y20862D03*
X284233Y26474D03*
X280833D03*
X290799Y28362D03*
X284230Y50646D03*
X280830D03*
X289400Y54222D03*
X285357Y105003D03*
X288557D03*
X280857Y107303D03*
X285857Y115603D03*
X282857D03*
X280857Y109903D03*
X275797Y129592D03*
X287000Y139862D03*
X283053Y139728D03*
X276825Y140462D03*
X290685Y165447D03*
X286481Y251962D03*
X281077D03*
X276491D03*
X289274Y290662D03*
X284515D03*
X276500Y444862D03*
X274850Y442562D03*
X279500Y455362D03*
X277578Y509039D03*
X284482Y566022D03*
X286582Y637809D03*
Y634283D03*
X284287Y716015D03*
X277046Y725709D03*
Y735442D03*
X284358Y732562D03*
X283350Y728483D03*
X289137Y735275D03*
X279507Y727025D03*
X285046Y737964D03*
X281046Y737938D03*
X275210Y738102D03*
X287607Y754962D03*
X277046Y746702D03*
X281046D03*
X285046D03*
X299500Y22862D03*
X295520Y12762D03*
X302610Y26362D03*
X292060Y24472D03*
X295520Y26362D03*
X300248Y28362D03*
X304927Y24654D03*
X304972Y28362D03*
X302720Y38182D03*
X292590Y53982D03*
X293161Y50522D03*
X306570Y50222D03*
X290720Y40017D03*
X294720D03*
X295524Y52092D03*
X301310Y52482D03*
X298550Y51602D03*
X303715Y50857D03*
X292942Y71499D03*
X305747Y64013D03*
Y61113D03*
X305247Y71567D03*
X301600Y82457D03*
X302310Y75673D03*
X295357Y88903D03*
X307820Y95724D03*
X301183Y107103D03*
Y110003D03*
Y112803D03*
X296478Y149203D03*
X296800Y139762D03*
X306000Y165662D03*
X295685Y165447D03*
X296478Y158703D03*
X306730Y173842D03*
X304651Y251962D03*
X291759D03*
X306736Y290662D03*
X302765D03*
X298184D03*
X293763D03*
X298587Y508074D03*
X300520Y552262D03*
X307987Y577658D03*
X293805Y569397D03*
Y565997D03*
X298000Y587890D03*
X308417Y585158D03*
X308447Y592255D03*
X306144Y602225D03*
X305612Y622530D03*
Y625030D03*
Y627530D03*
X296405Y630732D03*
Y634132D03*
X295962Y679374D03*
X294679Y688446D03*
Y685046D03*
X291600Y705162D03*
X298273Y715400D03*
X297087Y721249D03*
X304602Y727968D03*
X293027Y755985D03*
X303647Y1307981D03*
X303723Y1353316D03*
Y1355853D03*
X304051Y1365453D03*
X306667Y1361597D03*
X302805Y1379941D03*
Y1376541D03*
X296170Y1622852D03*
X310400Y50362D03*
X314657Y71803D03*
Y68903D03*
X323040Y73122D03*
X323117Y81168D03*
Y76938D03*
X322875Y84318D03*
X316364Y89212D03*
X310459Y75892D03*
X320430Y78002D03*
X313357Y89503D03*
X313457Y96803D03*
X311057Y107103D03*
Y110003D03*
Y112803D03*
X308175Y144202D03*
X308500Y165662D03*
X311200Y165562D03*
X309230Y173842D03*
X309756Y177449D03*
Y181449D03*
X310970Y195362D03*
X308790Y197622D03*
X320270Y200462D03*
X319370Y214492D03*
X316370D03*
X319370Y217492D03*
X316370D03*
X323314Y210645D03*
X306910Y228162D03*
X309910D03*
X306910Y225162D03*
X309910D03*
X322658Y229254D03*
X319718Y223750D03*
X317981Y237724D03*
X320940Y238372D03*
X317129Y251962D03*
X316463Y290662D03*
X316444Y559125D03*
X317860Y572322D03*
X319520Y577658D03*
X312007Y588675D03*
X319520Y582658D03*
X316127Y592785D03*
X318560Y587632D03*
X321276Y599298D03*
X317386Y623207D03*
X308605Y629525D03*
Y627025D03*
X319557Y736225D03*
X317967Y746985D03*
Y771875D03*
X320578Y1290197D03*
X323028Y1297967D03*
X320428D03*
Y1295467D03*
X323028D03*
Y1292967D03*
X320428D03*
X320245Y1357401D03*
X313841Y1365553D03*
X309841Y1364815D03*
X318051Y1367043D03*
X316579Y1364585D03*
X309841Y1367871D03*
X322575Y1358151D03*
X332500Y150738D03*
X326216Y138787D03*
X326900Y162287D03*
X323420Y207549D03*
X326168Y207580D03*
X334485Y216809D03*
X337000Y216862D03*
X335575Y214170D03*
X328588Y209677D03*
X334500Y219362D03*
X337000D03*
X328939Y229139D03*
X335385Y235309D03*
X335412Y222176D03*
X329648Y252202D03*
X341295Y290239D03*
X329002Y290662D03*
X330674Y365702D03*
X328167Y379073D03*
X336270Y402992D03*
X329050Y607402D03*
X331339Y709313D03*
X328120Y710862D03*
X335677Y715215D03*
X327107Y732665D03*
X335467Y725335D03*
X338097Y736235D03*
X335126Y728323D03*
X327096Y736005D03*
X336446Y746486D03*
X338667Y772452D03*
X341527Y778362D03*
X339148Y1269717D03*
X339088Y1272287D03*
X339028Y1274887D03*
X325688Y1290167D03*
X325718Y1287587D03*
X328078Y1288747D03*
X323178Y1290197D03*
X323208Y1287617D03*
X328168Y1280967D03*
X325748Y1284987D03*
X328108Y1286147D03*
X328138Y1283567D03*
X328018Y1291317D03*
X339035Y1280218D03*
X339040Y1277594D03*
X328065Y1299248D03*
X325538Y1297937D03*
Y1292937D03*
Y1295437D03*
X328058Y1293917D03*
X328070Y1296624D03*
X335679Y1330518D03*
X334973Y1333353D03*
X338795Y1338799D03*
X336179Y1342753D03*
X324905Y1357401D03*
X327235Y1358151D03*
X332475Y1357945D03*
X327875Y1363945D03*
Y1361045D03*
X330041Y1362315D03*
X329941Y1359315D03*
X332475Y1363345D03*
Y1360445D03*
X340440Y120552D03*
X343450Y131167D03*
X342700Y139662D03*
X355189Y144267D03*
X351100Y150412D03*
X348100Y185162D03*
X345600Y188162D03*
X356295Y219362D03*
X353145D03*
X342000Y252612D03*
X354672Y252693D03*
X354145Y290591D03*
X345411Y364702D03*
Y376923D03*
X343354Y391643D03*
X347340Y407462D03*
X348880Y703442D03*
X354100Y720743D03*
X352879Y728657D03*
X348037Y728735D03*
X348730Y735098D03*
Y731698D03*
X344264Y1272455D03*
X341754Y1272485D03*
X344252Y1269948D03*
X341742Y1269978D03*
X344258Y1267117D03*
X341748Y1267147D03*
X341754Y1274985D03*
X344264Y1274955D03*
X355036Y1272433D03*
Y1269933D03*
X355378Y1262027D03*
X355318Y1264597D03*
X355258Y1267197D03*
X355036Y1274933D03*
X341605Y1280248D03*
X344115Y1280218D03*
X344264Y1277455D03*
X341754Y1277485D03*
X355048Y1277440D03*
X355025Y1280248D03*
X352373Y1334603D03*
X354703Y1335353D03*
X345969Y1342755D03*
X341969Y1342017D03*
X350179Y1344245D03*
X348707Y1341787D03*
X341969Y1345073D03*
X354850Y1371908D03*
X351850D03*
X349260Y1373418D03*
X351850Y1375408D03*
X354850D03*
X351850Y1378408D03*
X354850D03*
X351850Y1381408D03*
X354850D03*
X349260Y1376918D03*
Y1379918D03*
X349636Y1399601D03*
X352713Y1399336D03*
X355513Y1402306D03*
X352513D03*
X349513D03*
X355325Y1405386D03*
X349463Y1405286D03*
X352463D03*
X355325Y1408386D03*
X346426Y1414401D03*
X352401Y1414432D03*
X355325Y1414386D03*
Y1417386D03*
X352401Y1411432D03*
X355325Y1411386D03*
X352401Y1408432D03*
X349123Y1411376D03*
X349323Y1408406D03*
X349073Y1414356D03*
X346256Y1417301D03*
X352231Y1417332D03*
X348903Y1417256D03*
X363625Y127662D03*
X361800Y122522D03*
X366060Y133912D03*
X363525Y158702D03*
X361190Y210762D03*
X357303Y213159D03*
X371551Y224862D03*
X367306Y252811D03*
X366498Y290264D03*
X357660Y318850D03*
X364014Y366391D03*
Y378649D03*
X364179Y392037D03*
X370200Y409582D03*
X373720Y431362D03*
X365720Y440562D03*
X365771Y449480D03*
X359669Y686744D03*
X359639Y690114D03*
X360470Y705965D03*
X363101Y697348D03*
Y693948D03*
X360990Y726862D03*
X358902Y736225D03*
X355946Y728800D03*
X359790Y729835D03*
X358902Y739755D03*
Y743035D03*
Y754945D03*
Y746405D03*
Y773352D03*
X371578Y1248967D03*
X371458Y1254137D03*
X371330Y1256687D03*
X371518Y1251537D03*
X371278Y1259257D03*
X360198Y1269777D03*
X357546Y1272403D03*
Y1269903D03*
X360138Y1272347D03*
X357828Y1264567D03*
X357888Y1261997D03*
X360378Y1264627D03*
X360438Y1262057D03*
X357768Y1267167D03*
X360318Y1267227D03*
X357546Y1274903D03*
X360128Y1274957D03*
X371218Y1261857D03*
X371225Y1267188D03*
X371230Y1264564D03*
X357558Y1277410D03*
X357535Y1280218D03*
X360120Y1277654D03*
X367694Y1317092D03*
X367807Y1319592D03*
X368391Y1328161D03*
X370923Y1325373D03*
X357033Y1334603D03*
X359363Y1335353D03*
X362147Y1336553D03*
X360003Y1338247D03*
X364269Y1338017D03*
X364073Y1334903D03*
X360003Y1341147D03*
X362147Y1339653D03*
X364347Y1340853D03*
X364647Y1371990D03*
X361647D03*
X358647D03*
X367647D03*
X370552Y1372073D03*
X364647Y1375490D03*
X361647D03*
X358647D03*
Y1378490D03*
X370552Y1375573D03*
X367647Y1375490D03*
X355713Y1399336D03*
X361703Y1399386D03*
X364703D03*
X367703D03*
X370703D03*
X358703Y1402386D03*
X361703D03*
X364703D03*
X367703D03*
X370703D03*
X358713Y1399336D03*
X358573Y1405336D03*
X361573D03*
X364573D03*
X367573D03*
X370573D03*
X358703Y1414606D03*
X361703D03*
X364703D03*
X361703Y1417386D03*
X358703D03*
X364703D03*
X367703D03*
Y1414606D03*
X358217Y1411405D03*
X370517Y1414615D03*
X370717Y1417405D03*
X357917Y1408205D03*
X367948Y1531529D03*
X371850Y1534062D03*
X368600Y1543200D03*
X367140Y1645390D03*
X366700Y1649000D03*
X370500Y1654362D03*
X370635Y1675820D03*
X369300Y1680400D03*
Y1682900D03*
X380930Y122022D03*
X383160Y124322D03*
X383060Y128491D03*
X372530Y122972D03*
X373200Y126052D03*
X379295Y131002D03*
X379860Y252162D03*
X379112Y290386D03*
X385720Y320902D03*
X376500Y366391D03*
Y378649D03*
X377136Y390307D03*
X390220Y392062D03*
X383060Y403542D03*
X379220Y436362D03*
X376220D03*
X382220D03*
X389920Y461362D03*
X379220Y470962D03*
X387500Y495362D03*
X389020Y522862D03*
X371970Y683892D03*
X381010Y734732D03*
X376638Y1248997D03*
X374088Y1248937D03*
X374028Y1251507D03*
X373823Y1256896D03*
X376333Y1256866D03*
X376518Y1254167D03*
X376578Y1251567D03*
X373968Y1254107D03*
X373835Y1259403D03*
X376345Y1259373D03*
X387478Y1248967D03*
X387358Y1254137D03*
X387117Y1256851D03*
X387418Y1251537D03*
X387117Y1259351D03*
X373835Y1261903D03*
Y1264403D03*
X376345Y1261873D03*
Y1264373D03*
X376285Y1267218D03*
X373735Y1267158D03*
X387117Y1261851D03*
X387129Y1264358D03*
X387125Y1267188D03*
X384501Y1321177D03*
X386831Y1321927D03*
X378097Y1329329D03*
X374097Y1328591D03*
X382307Y1330819D03*
X380835Y1328361D03*
X374097Y1331647D03*
X373552Y1372073D03*
X377025Y1371990D03*
X380025D03*
X373532Y1378598D03*
X373552Y1375573D03*
X380025Y1378490D03*
X377025D03*
X380025Y1375490D03*
X377025D03*
Y1381490D03*
X380025D03*
X376825Y1399386D03*
X379825D03*
X373703D03*
X379825Y1402386D03*
X376825D03*
X373703D03*
X376825Y1405386D03*
X379825D03*
X373573Y1405336D03*
X374027Y1411365D03*
X373703Y1414606D03*
X376825Y1414386D03*
X379825D03*
X376825Y1417386D03*
Y1411386D03*
X379825D03*
X373703Y1417386D03*
X376825Y1408386D03*
X379825D03*
X374307Y1408135D03*
X382489Y1428478D03*
X385667Y1433425D03*
X386827Y1429525D03*
X377830Y1534342D03*
X374900Y1534102D03*
X381120D03*
X377720Y1539862D03*
X374720D03*
X374800Y1546400D03*
X385100Y1539700D03*
X381800Y1539600D03*
X381000Y1546500D03*
X384000D03*
X378000Y1546400D03*
X387930Y1585155D03*
X384600Y1595100D03*
X382220Y1591870D03*
X374391Y1648476D03*
X385123Y1639732D03*
X378547D03*
X380170Y1660002D03*
X372640Y1662112D03*
X380077Y1654049D03*
X372009Y1682584D03*
X375430Y1676462D03*
X376610Y1688252D03*
X396380Y62742D03*
X402100Y62632D03*
X399240Y62722D03*
X404910Y62562D03*
X388735Y117322D03*
X395980Y148272D03*
X388965Y215067D03*
X388720Y218362D03*
X394720Y206362D03*
X402700Y234167D03*
X392616Y252162D03*
X396294Y281585D03*
X392083Y290954D03*
X404215Y291140D03*
X398720Y321202D03*
X398661Y323761D03*
X390876Y365640D03*
X390843Y378439D03*
X403875Y365640D03*
X404120Y378439D03*
X404291Y391433D03*
X391149Y404304D03*
X403720Y405552D03*
X388720Y430862D03*
X403220Y436362D03*
X395520Y448362D03*
X400080Y472652D03*
X402500Y495362D03*
X394500Y522862D03*
X400589Y575236D03*
X398796Y1161570D03*
Y1153070D03*
Y1170070D03*
X403738Y1249027D03*
X403618Y1254197D03*
X403498Y1256747D03*
X403678Y1251597D03*
X392538Y1248997D03*
X389928Y1251507D03*
X389988Y1248937D03*
X389868Y1254107D03*
X392298Y1256717D03*
X392418Y1254167D03*
X389627Y1256821D03*
X392478Y1251567D03*
X392238Y1259287D03*
X389627Y1259321D03*
X403438Y1259317D03*
X392220Y1264594D03*
X392228Y1261897D03*
X389627Y1261821D03*
X389639Y1264328D03*
X389635Y1267158D03*
X392185Y1267218D03*
X403385Y1267248D03*
X403378Y1261917D03*
X403390Y1264624D03*
X399935Y1317092D03*
Y1319592D03*
X389161Y1321177D03*
X391491Y1321927D03*
X392131Y1324821D03*
X396397Y1324591D03*
X394197Y1323091D03*
X396397Y1321691D03*
X400073Y1327653D03*
X403051Y1325373D03*
X394297Y1326091D03*
X392131Y1327721D03*
X396397Y1327491D03*
X400888Y1395508D03*
X392947Y1397827D03*
X390934Y1404085D03*
X401079Y1399208D03*
X400924Y1408227D03*
X400926Y1404707D03*
X392517Y1419015D03*
X400991Y1417264D03*
X390934Y1407605D03*
X390914Y1412991D03*
X403125Y1425008D03*
X390687Y1431713D03*
X390777Y1435152D03*
X394067Y1435323D03*
X401244Y1440773D03*
X396822Y1439340D03*
X396946Y1537632D03*
X396768Y1541810D03*
X404920Y1539362D03*
X396946Y1556810D03*
X391330Y1585155D03*
X404030Y1595390D03*
Y1591990D03*
X394360Y1616380D03*
X392550Y1618650D03*
X397406Y1633142D03*
X402590Y1618952D03*
X401740Y1648082D03*
X404240D03*
X404320Y1645452D03*
X401820D03*
X391563Y1640244D03*
X397406Y1636542D03*
X397400Y1641000D03*
X390180Y1668212D03*
X396824Y1673662D03*
X407970Y59612D03*
X407790Y62652D03*
X415800Y62665D03*
Y67465D03*
X419901Y117491D03*
X408284Y163662D03*
X420865Y215067D03*
X410996Y218834D03*
X420752Y239562D03*
X405139Y239908D03*
X417765Y252162D03*
X404985D03*
X417218Y291274D03*
X419920Y338162D03*
X416220Y364062D03*
X418704Y379201D03*
X416762Y367353D03*
X418540Y392163D03*
X416514Y407028D03*
X412720Y439362D03*
X417880Y461942D03*
X418520Y473562D03*
X419460Y1161570D03*
Y1153370D03*
Y1169597D03*
X406248Y1248997D03*
X408798Y1249057D03*
X408511Y1256866D03*
X406001Y1256896D03*
X406128Y1254167D03*
X408678Y1254227D03*
X406188Y1251567D03*
X419638Y1248967D03*
X419295Y1256851D03*
X419518Y1254137D03*
X419578Y1251537D03*
X419295Y1259351D03*
X408738Y1251627D03*
X408523Y1259373D03*
X406013Y1259403D03*
X419295Y1261851D03*
X419307Y1264358D03*
X419285Y1267188D03*
X408523Y1264373D03*
X406013Y1264403D03*
Y1261903D03*
X408523Y1261873D03*
X405895Y1267218D03*
X408445Y1267278D03*
X416629Y1321177D03*
X418959Y1321927D03*
X410225Y1329329D03*
X406225Y1328591D03*
X414435Y1330819D03*
X412963Y1328361D03*
X406225Y1331647D03*
X418320Y1383862D03*
X422320D03*
X414333Y1385292D03*
X410933Y1384648D03*
X414909Y1395658D03*
X408915Y1402606D03*
X411150Y1408163D03*
X410912Y1418177D03*
X408968Y1410427D03*
X411162Y1414126D03*
X416926Y1426471D03*
X412416Y1431645D03*
X419861Y1429718D03*
X419302Y1434700D03*
X422708Y1437560D03*
X410074Y1424993D03*
X416999Y1441908D03*
X413599D03*
X407625Y1552572D03*
X419820Y1555862D03*
X409140Y1566892D03*
X405000Y1566670D03*
X412600Y1601000D03*
X408600Y1607400D03*
X419780Y1602802D03*
X414406Y1624992D03*
Y1628392D03*
X405990Y1618952D03*
X416020Y1620862D03*
X412456Y1649838D03*
X417960Y1650072D03*
X410700Y1655310D03*
X409857Y1682767D03*
X421320Y1671699D03*
X410249Y1673082D03*
X427120Y59862D03*
X428500Y65016D03*
Y70016D03*
X435340Y122196D03*
X428889Y121515D03*
X428883Y131015D03*
X429780Y149373D03*
Y153477D03*
Y157466D03*
Y161466D03*
X433695Y209862D03*
X421200Y232562D03*
X423145Y227862D03*
X426490Y244262D03*
X429702Y290763D03*
X425720Y319492D03*
X432380Y346522D03*
X422420Y338162D03*
X431781Y379201D03*
X434006Y365203D03*
X433596Y391163D03*
X431920Y405288D03*
X428720Y439362D03*
X437720Y435362D03*
X431570Y435512D03*
X437520Y476337D03*
X431220Y496362D03*
X434343Y504233D03*
Y509733D03*
Y498733D03*
X431220Y507143D03*
Y512623D03*
Y501643D03*
X434343Y515233D03*
Y526233D03*
Y520733D03*
X431220Y518133D03*
Y523362D03*
X434620Y535762D03*
X434343Y542733D03*
X434320Y540153D03*
X434343Y547769D03*
Y552769D03*
X421960Y1161570D03*
Y1153370D03*
Y1169597D03*
X422148Y1248937D03*
X424698Y1248997D03*
X422088Y1251507D03*
X421805Y1256821D03*
X422028Y1254107D03*
X424458Y1256717D03*
X424578Y1254167D03*
X424638Y1251567D03*
X421805Y1259321D03*
X424398Y1259287D03*
X436068Y1248967D03*
X435828Y1256687D03*
X435948Y1254137D03*
X436008Y1251537D03*
X435768Y1259257D03*
X421805Y1261821D03*
X421817Y1264328D03*
X421795Y1267158D03*
X424345Y1267218D03*
X424380Y1264594D03*
X424388Y1261897D03*
X435715Y1267188D03*
X435720Y1264564D03*
X435708Y1261857D03*
X432063Y1317092D03*
Y1319592D03*
X421289Y1321177D03*
X423619Y1321927D03*
X428525Y1321691D03*
X426325Y1323091D03*
X424259Y1324821D03*
X428525Y1324591D03*
X432628Y1327845D03*
X435179Y1325373D03*
X424259Y1327721D03*
X426425Y1326091D03*
X428525Y1327491D03*
X426320Y1383862D03*
X430320D03*
X439030Y1383692D03*
X436780Y1387387D03*
X436467Y1391687D03*
X438458Y1402169D03*
X438645Y1426890D03*
X437299Y1436774D03*
X433539Y1430613D03*
X425030Y1434292D03*
X433897Y1434670D03*
X427546Y1443411D03*
X433954Y1439029D03*
X424146Y1443411D03*
X435396Y1551810D03*
X424820Y1552605D03*
X431620Y1541362D03*
X434430Y1567562D03*
X424570Y1579466D03*
X433350Y1579509D03*
X424800Y1616600D03*
X432200Y1607060D03*
X423180Y1602802D03*
X432500Y1613822D03*
X430015Y1626608D03*
X433670Y1639562D03*
X426728Y1636495D03*
X451418Y78782D03*
X446640Y104552D03*
X446746Y152662D03*
X453028Y154864D03*
X452500Y213362D03*
Y222362D03*
X452071Y254862D03*
X442265Y290939D03*
X439120Y314562D03*
X442220Y323362D03*
X448220Y323582D03*
Y319862D03*
X446000Y339362D03*
X455000Y340362D03*
X450500Y358862D03*
X443770Y371042D03*
X451062Y397262D03*
X447490Y409052D03*
X443300Y410962D03*
X447750Y414112D03*
X453020Y414262D03*
X449420Y424162D03*
X451520Y475837D03*
X442520Y476337D03*
X453680Y515072D03*
X451320Y533562D03*
X448276Y1161570D03*
X445776D03*
X443276D03*
X445776Y1153370D03*
X448276D03*
X443276D03*
X448276Y1170069D03*
X445776D03*
X443276D03*
X441128Y1248997D03*
X438578Y1248937D03*
X438518Y1251507D03*
X440858Y1256866D03*
X438348Y1256896D03*
X441008Y1254167D03*
X438458Y1254107D03*
X441068Y1251567D03*
X440870Y1259373D03*
X438360Y1259403D03*
X451642Y1256851D03*
X451878Y1254107D03*
X451642Y1259351D03*
X451938Y1251507D03*
X451998Y1248937D03*
X438360Y1261903D03*
X440870Y1261873D03*
Y1264373D03*
X438360Y1264403D03*
X438225Y1267158D03*
X440775Y1267218D03*
X451642Y1261851D03*
X451654Y1264358D03*
X451645Y1267158D03*
X448757Y1321177D03*
X451087Y1321927D03*
X442353Y1329329D03*
X438353Y1328591D03*
X446563Y1330819D03*
X445091Y1328361D03*
X438353Y1331647D03*
X443842Y1389106D03*
X448020Y1391862D03*
X443424Y1397869D03*
X439391Y1398266D03*
X441369Y1394260D03*
X451048Y1404914D03*
X447110Y1403812D03*
X448114Y1396812D03*
X445339Y1415731D03*
X446230Y1407722D03*
X445230Y1411719D03*
X445723Y1419730D03*
X443850Y1423404D03*
X451080Y1433740D03*
X440164Y1433982D03*
X445294Y1430415D03*
X443715Y1436052D03*
X452520Y1564862D03*
X448328Y1582476D03*
X446020Y1570412D03*
X452020Y1580412D03*
X448740Y1574862D03*
X444458Y1602654D03*
X437383Y1602629D03*
X454661Y1609235D03*
X442974Y1615615D03*
X448181Y1614401D03*
X443800Y1610712D03*
X449940Y1647412D03*
X447090Y1647472D03*
X444940Y1641842D03*
X438340Y1652266D03*
X441740D03*
X462620Y120948D03*
X462320Y115948D03*
X453346Y149864D03*
X461900Y215244D03*
X466300Y217803D03*
X461900Y222921D03*
X466300Y225480D03*
X468323Y254562D03*
X465236Y296973D03*
X461736Y301098D03*
Y306098D03*
X463198Y311587D03*
X465000Y340362D03*
X456660Y359172D03*
X460800Y358962D03*
X467211Y371902D03*
X459220Y393762D03*
X463500Y383562D03*
X455720Y404762D03*
X458600Y414262D03*
X465421Y428078D03*
X456520Y476337D03*
X461520D03*
X453727Y518036D03*
X457456Y522516D03*
X470880Y572692D03*
X467130Y600122D03*
X456818Y1256687D03*
X454388Y1254077D03*
X454152Y1256821D03*
X456998Y1251537D03*
X456758Y1259257D03*
X454152Y1259321D03*
X468258Y1249107D03*
X468018Y1256827D03*
X468138Y1254277D03*
X468198Y1251677D03*
X467958Y1259397D03*
X457058Y1248967D03*
X454508Y1248907D03*
X454448Y1251477D03*
X456938Y1254137D03*
X456705Y1267188D03*
X454155Y1267128D03*
X456748Y1261867D03*
X456740Y1264564D03*
X454152Y1261821D03*
X454164Y1264328D03*
X467905Y1267328D03*
X467910Y1264704D03*
X467898Y1261997D03*
X464191Y1317092D03*
Y1319592D03*
X453417Y1321177D03*
X455747Y1321927D03*
X458453Y1323091D03*
X460653Y1321691D03*
Y1324591D03*
X456387Y1324821D03*
X464191Y1327793D03*
X467307Y1325373D03*
X458553Y1326091D03*
X460653Y1327491D03*
X456387Y1327721D03*
X459550Y1401348D03*
X465947Y1398355D03*
X459321Y1393009D03*
Y1396409D03*
X458441Y1414893D03*
X468880Y1418400D03*
X456619Y1431189D03*
X463140Y1451562D03*
X463207Y1547543D03*
X453595Y1551470D03*
X459520Y1546962D03*
X466905Y1567847D03*
X467400Y1556700D03*
X460020Y1580412D03*
X457220Y1584020D03*
X466520Y1574862D03*
X457220Y1603562D03*
X460200Y1589900D03*
X456510Y1614472D03*
X469488Y1607362D03*
X460910Y1629172D03*
Y1625772D03*
X455681Y1622492D03*
X458978Y1634481D03*
X463344Y1637622D03*
X469580Y1640272D03*
X468040Y1651657D03*
X466460Y1672332D03*
X466180Y1678392D03*
X481880Y147069D03*
X481246Y161364D03*
X476220Y158772D03*
X470900Y234787D03*
X486800Y259162D03*
X478500Y258862D03*
X474736Y302098D03*
X478995Y293787D03*
X479736Y303598D03*
Y308598D03*
X486720Y360862D03*
X482720D03*
X475508Y359266D03*
X476585Y370727D03*
X472720Y391362D03*
X485020Y414162D03*
X471920Y416687D03*
X474169Y476196D03*
X479169D03*
X474044Y503725D03*
X478510Y602942D03*
X472960Y602152D03*
X482780Y607012D03*
X473698Y1161570D03*
X471198D03*
X473698Y1153370D03*
X471198D03*
X473698Y1170070D03*
X471198D03*
X473318Y1249137D03*
X470768Y1249077D03*
X473035Y1256866D03*
X470525Y1256896D03*
X473198Y1254307D03*
X470648Y1254247D03*
X473258Y1251707D03*
X470708Y1251647D03*
X473047Y1259373D03*
X470537Y1259403D03*
X484098Y1248997D03*
X483819Y1256851D03*
X483978Y1254167D03*
X484038Y1251567D03*
X483819Y1259351D03*
X472965Y1267358D03*
X470415Y1267298D03*
X470537Y1261903D03*
X473047Y1261873D03*
Y1264373D03*
X470537Y1264403D03*
X483819Y1261851D03*
X483831Y1264358D03*
X483745Y1267218D03*
X480885Y1321177D03*
X485545D03*
X483215Y1321927D03*
X474481Y1329329D03*
X470481Y1328591D03*
X478691Y1330819D03*
X477219Y1328361D03*
X470481Y1331647D03*
X483560Y1401712D03*
X474983Y1400385D03*
X485141Y1405430D03*
X481997Y1409955D03*
X470987Y1409965D03*
X484921Y1413246D03*
X470890Y1435838D03*
X478449Y1448158D03*
X482633Y1449091D03*
Y1446091D03*
X470111Y1548269D03*
X483348Y1548062D03*
X475110Y1548112D03*
X477968Y1548122D03*
X480848Y1548120D03*
X486210Y1547960D03*
X482400Y1558320D03*
X472220Y1626732D03*
X472210Y1622735D03*
X477905Y1663242D03*
Y1659242D03*
X475150Y1654302D03*
X477835Y1677462D03*
X488748Y72264D03*
X499580Y78442D03*
X489730Y76132D03*
X498330Y96112D03*
X498730Y128592D03*
X498700Y212685D03*
Y220362D03*
X503100Y215244D03*
X500925Y231262D03*
X503100Y222921D03*
X496028Y258590D03*
X499096Y252462D03*
X489091Y293787D03*
X498636Y296273D03*
X495136Y300398D03*
Y305398D03*
X486861D03*
X495036Y310398D03*
X486710Y313582D03*
X492150Y336810D03*
X498720Y360862D03*
X490720D03*
Y368862D03*
X489520Y411862D03*
X494020Y414262D03*
X492970Y409252D03*
X502070Y427937D03*
X488169Y475696D03*
X493169Y476196D03*
X498169D03*
X486500Y556212D03*
X491043Y550447D03*
X486608Y1248967D03*
X489158Y1249027D03*
X486329Y1256821D03*
X486488Y1254137D03*
X488918Y1256747D03*
X489038Y1254197D03*
X486548Y1251537D03*
X489098Y1251597D03*
X486329Y1259321D03*
X488858Y1259317D03*
X500228Y1259237D03*
X486329Y1261821D03*
X486341Y1264328D03*
X488840Y1264624D03*
X488848Y1261927D03*
X488805Y1267248D03*
X486255Y1267188D03*
X500138Y1269637D03*
X500150Y1272344D03*
X500198Y1267037D03*
Y1264467D03*
X500168Y1261807D03*
X500150Y1275224D03*
Y1278104D03*
X487875Y1321927D03*
X492878Y1322618D03*
X490678Y1324018D03*
X496319Y1330493D03*
Y1333043D03*
X499435Y1338799D03*
X488539Y1325772D03*
X492878Y1325518D03*
X488539Y1328672D03*
X490778Y1327018D03*
X492878Y1328418D03*
X496319Y1341264D03*
X491089Y1446091D03*
Y1449091D03*
X499489D03*
Y1446091D03*
X489230Y1643592D03*
X516236Y92948D03*
X513586Y92799D03*
X510600Y92782D03*
X517290Y104252D03*
X513700Y117862D03*
X510900Y111962D03*
X503270Y128592D03*
X507320D03*
X515690Y147852D03*
X519010Y147912D03*
X518186Y139821D03*
X519236Y202404D03*
X518670Y219192D03*
X512500Y209862D03*
Y223362D03*
X508500Y232862D03*
X508000Y241862D03*
X508502Y298813D03*
X503040Y287928D03*
X508500Y303362D03*
X508136Y309398D03*
X502239Y315404D03*
X507160Y332452D03*
X510720Y360862D03*
X514720D03*
X502720D03*
X506720Y368862D03*
X509720Y390362D03*
X513720D03*
X505720Y398362D03*
X502260Y397742D03*
X511320Y437962D03*
X513444Y457522D03*
X516970Y592942D03*
X504135Y615612D03*
X505398Y1259377D03*
X502858Y1259257D03*
X502718Y1271417D03*
X505218Y1271447D03*
X505290Y1267254D03*
X505338Y1261947D03*
X505278Y1264547D03*
X502750Y1267134D03*
X502798Y1261827D03*
X502738Y1264427D03*
X502718Y1274114D03*
X505218Y1274144D03*
X515898Y1271447D03*
X515950Y1274144D03*
X505220Y1280054D03*
X502718Y1276994D03*
X505218Y1277024D03*
X502680Y1280054D03*
X515960D03*
X515950Y1277024D03*
X513013Y1334603D03*
X517673D03*
X515343Y1335353D03*
X506609Y1342755D03*
X502609Y1342017D03*
X510819Y1344245D03*
X509347Y1341787D03*
X502609Y1345073D03*
X509246Y1420002D03*
X505777Y1425579D03*
X507964Y1448979D03*
Y1445979D03*
X529720Y30792D03*
Y43054D03*
X534720Y42922D03*
X533915Y59822D03*
X523978Y59074D03*
X529078Y59282D03*
X527520Y69633D03*
X528590Y72922D03*
X518450Y101602D03*
X527310Y98147D03*
Y94747D03*
X527160Y129243D03*
X523220Y170362D03*
X534765Y161067D03*
X526920Y161362D03*
X529507Y202448D03*
X522337Y202404D03*
X531298Y284280D03*
X536420Y309422D03*
X523682Y307541D03*
Y304541D03*
X526980Y322582D03*
X521820Y336762D03*
X531720Y360862D03*
X527720D03*
X523670Y368892D03*
X525720Y390362D03*
X529720D03*
X521720Y398362D03*
X532650Y446396D03*
Y442376D03*
X521885Y452442D03*
X532650Y450330D03*
Y454270D03*
X533410Y475932D03*
X525820Y473662D03*
X524425Y489112D03*
Y495112D03*
X519520Y484027D03*
X522805Y482155D03*
X531258Y505473D03*
X521561Y505969D03*
Y500469D03*
Y511469D03*
X524220Y505862D03*
Y500362D03*
Y511362D03*
X521561Y516969D03*
Y522469D03*
X536000Y520362D03*
X524220Y516862D03*
X524720Y525293D03*
Y519743D03*
X521561Y527969D03*
Y539819D03*
X524920D03*
X524820Y545319D03*
X523699Y571545D03*
X528500Y566722D03*
X523890Y592387D03*
X531472Y579750D03*
X521118Y1273097D03*
X518488Y1271477D03*
X521058Y1275667D03*
X518490Y1274144D03*
X521058Y1278277D03*
X521020Y1280974D03*
X518500Y1280054D03*
X518490Y1277024D03*
X530398Y1288557D03*
X530548Y1283377D03*
X530428Y1285947D03*
X530410Y1291254D03*
X532558Y1289967D03*
X532618Y1287367D03*
X532678Y1284797D03*
X530450Y1297014D03*
Y1294134D03*
X532570Y1295554D03*
Y1298434D03*
Y1292674D03*
X525008Y1336287D03*
X520643Y1338247D03*
X522809Y1339517D03*
X522783Y1334882D03*
X520643Y1341147D03*
X520003Y1335353D03*
X528447Y1353316D03*
Y1355816D03*
X524892Y1341462D03*
X522818Y1342930D03*
X528929Y1364212D03*
X531563Y1361597D03*
X539720Y30792D03*
X534720D03*
X542050Y47452D03*
X539720Y42862D03*
X550971Y42902D03*
X544720Y42892D03*
X548609Y48082D03*
X537315Y59822D03*
X541002Y71436D03*
X544402D03*
X548070Y79372D03*
X542460Y99172D03*
X539475Y118772D03*
X547395Y147302D03*
X543083Y146338D03*
X540460Y200392D03*
X544390Y236512D03*
X550390Y231742D03*
X548390Y236512D03*
X546390Y231742D03*
X542050Y231722D03*
X539639Y271972D03*
X539830Y274912D03*
X537720Y278212D03*
X547420Y306862D03*
X544920D03*
X549220Y339687D03*
X535720Y360862D03*
X546758Y360502D03*
X547810Y414472D03*
X549670Y419892D03*
X542870Y438320D03*
X548464Y456534D03*
X548780Y475932D03*
X548550Y480382D03*
X546210Y519642D03*
X541820Y575130D03*
X541722Y568054D03*
X537730Y577440D03*
X547020Y590332D03*
X550320Y583362D03*
X536626Y590500D03*
X537560Y598102D03*
X537648Y1290037D03*
X535058Y1290007D03*
X535148Y1287397D03*
X543660Y1302934D03*
X541100D03*
X538560D03*
X535110Y1292704D03*
Y1295584D03*
Y1298464D03*
X537650Y1292704D03*
X540210D03*
X537650Y1298464D03*
Y1295584D03*
X540210Y1298464D03*
Y1295584D03*
X536020Y1302904D03*
X545141Y1357401D03*
X549801D03*
X538737Y1365553D03*
X534737Y1364815D03*
X542947Y1367043D03*
X541475Y1364585D03*
X534737Y1367871D03*
X547471Y1358151D03*
X563482Y40826D03*
X554720Y32862D03*
X565184Y47982D03*
X558058Y46352D03*
X554983Y45312D03*
X553650Y48842D03*
X551470Y79372D03*
X567865Y92656D03*
X559000Y102862D03*
X561000Y98862D03*
X552395Y134340D03*
X566500Y125097D03*
X551231Y122671D03*
X564890Y142173D03*
X555220Y164787D03*
X555545Y156462D03*
X555195Y184862D03*
Y171862D03*
X554872Y196635D03*
X559400Y201162D03*
X557248Y198909D03*
X564600Y202662D03*
X552489Y212022D03*
X553402Y231292D03*
X552089Y253202D03*
Y257202D03*
X562461Y272161D03*
X561324Y301149D03*
X566730Y300992D03*
X555520Y309827D03*
X563790Y331846D03*
X561290D03*
X558790D03*
X562200Y419412D03*
X559300Y414112D03*
X559730Y434772D03*
X557829Y454479D03*
X558220Y459362D03*
X563281Y543113D03*
X563700Y538477D03*
X560640Y540613D03*
X566140Y554972D03*
Y551472D03*
X559927Y548457D03*
X556820Y570462D03*
X557430Y583572D03*
X566510Y1352217D03*
X554837Y1359315D03*
X557037Y1363715D03*
Y1357915D03*
Y1360815D03*
X554937Y1362315D03*
X552771Y1361045D03*
Y1363945D03*
X552131Y1358151D03*
X555057Y1449395D03*
X572500Y32862D03*
X568500D03*
X581500Y41862D03*
X573190Y42912D03*
X567507Y45869D03*
X575330Y47672D03*
X570208Y47982D03*
X579930Y72052D03*
X577300Y66682D03*
X577880Y75442D03*
X570150Y102862D03*
X579080Y119402D03*
X573360Y140532D03*
X573115Y161232D03*
X569470Y171702D03*
X581120Y155062D03*
X568245Y167112D03*
X579481Y198378D03*
X579170Y190092D03*
X579481Y194378D03*
Y206378D03*
X578450Y218562D03*
X579245Y221362D03*
X567730Y225362D03*
X578390D03*
X567730Y221362D03*
X581755Y236978D03*
X575359Y265132D03*
X582510Y296657D03*
X577676Y300268D03*
X577480Y303822D03*
X582510Y304052D03*
Y311571D03*
X570440Y331930D03*
X567630Y331958D03*
X574800Y322462D03*
X571830Y348772D03*
X572360Y351962D03*
X571720Y381862D03*
X575050Y383602D03*
X577720Y381862D03*
X574491Y376549D03*
X580370Y383670D03*
X581090Y426970D03*
X571930Y421232D03*
X571110Y442656D03*
X569490Y437600D03*
X571110Y446706D03*
X567320Y454962D03*
Y459962D03*
Y457462D03*
X577220Y449462D03*
X578920Y466462D03*
X583045Y488212D03*
X583220Y493212D03*
X568840Y501046D03*
X584173Y498422D03*
X568520Y504162D03*
Y506662D03*
X577470Y505592D03*
X578925Y516846D03*
X571627Y548124D03*
X569050Y578292D03*
X572057Y577242D03*
X571555Y1352487D03*
X570645Y1361358D03*
X576220Y1423862D03*
X571620Y1424492D03*
X584950Y54842D03*
X586260Y52222D03*
X599800Y43152D03*
X597955Y48047D03*
X593369Y45682D03*
X586600Y60602D03*
X590680Y83591D03*
X592307Y94262D03*
X597287D03*
X594720Y97220D03*
X588245Y132142D03*
X598410Y124102D03*
X598390Y126802D03*
X589690Y161732D03*
X592220Y173862D03*
X596795Y179287D03*
X590281Y180698D03*
X599720Y184887D03*
X593220D03*
X584795Y233362D03*
X591310Y219582D03*
X592220Y249362D03*
X595415Y246515D03*
X591727Y285862D03*
X593763Y293999D03*
X588850Y291622D03*
X599620Y314762D03*
X595520Y314862D03*
X583820Y314662D03*
X590820Y330962D03*
X590720Y327862D03*
Y324582D03*
X590470Y319192D03*
X593120Y342782D03*
X583685Y363271D03*
X586185D03*
X586070Y352302D03*
X591839Y426112D03*
X595380Y416660D03*
X591720Y433937D03*
X595520Y439762D03*
X597220Y458688D03*
X599080Y448062D03*
X584100Y477952D03*
X592520Y467662D03*
X590210Y484132D03*
X599645Y479862D03*
X598661Y486922D03*
X587100Y493842D03*
X592400Y479162D03*
X591070Y504900D03*
X594090Y501957D03*
X587100Y496342D03*
X591425Y522337D03*
X591500Y516862D03*
X596880Y534812D03*
X592340Y744624D03*
X598693Y742072D03*
X611810Y34400D03*
X612822Y43232D03*
X606880Y44682D03*
X614400Y46012D03*
X603063Y48023D03*
X606020Y84562D03*
X615220Y76862D03*
X615170Y73812D03*
X601220Y73862D03*
Y76862D03*
X603720Y98362D03*
X608620Y94162D03*
X617585Y97257D03*
X613020Y94162D03*
X617409D03*
X603880Y93902D03*
X600220Y96862D03*
X614384Y119342D03*
X606040Y153432D03*
X606190Y144002D03*
X602580Y151052D03*
X603019Y146399D03*
X615573Y179484D03*
X615572Y176442D03*
X611381Y200378D03*
Y209878D03*
X614200Y265792D03*
X605350Y293092D03*
X605870Y298172D03*
X605560Y303372D03*
X607590Y314732D03*
X609040Y317282D03*
X615635Y317637D03*
X614130Y328762D03*
X605305Y331162D03*
X615180Y336812D03*
X605898Y372984D03*
X609690Y402812D03*
X605220Y416362D03*
X610720Y436362D03*
X600800Y430900D03*
X614220Y436362D03*
X610720Y442862D03*
X614220D03*
Y447862D03*
X602910Y461862D03*
X610720Y457862D03*
X614220D03*
X610720Y452862D03*
X604360Y452120D03*
X614220Y467862D03*
Y472862D03*
Y477862D03*
X605469Y467562D03*
X610720Y462862D03*
X614220D03*
X601220Y486922D03*
X600645Y504362D03*
X606200Y510862D03*
X611870Y512560D03*
X606220Y517762D03*
X607328Y537481D03*
X610797Y537528D03*
X607720Y550862D03*
X610720D03*
X613220Y654662D03*
X603276Y741375D03*
X600460Y744912D03*
X613047Y741492D03*
X602768Y758385D03*
X616675Y31777D03*
X624633Y49193D03*
X629820Y42562D03*
Y45062D03*
X619562Y49193D03*
X624140Y46672D03*
X622271Y44782D03*
X629000Y67362D03*
X628590Y58622D03*
X622271Y57952D03*
X623300Y95762D03*
X620540Y100112D03*
X632300Y104472D03*
X626699Y119182D03*
X630951D03*
X631290Y153702D03*
X615970Y161522D03*
X628195Y175914D03*
X628194Y172872D03*
X628730Y216472D03*
X631730D03*
X628730Y220472D03*
Y224472D03*
X631730Y220472D03*
Y224472D03*
X622730Y230362D03*
X630795Y236862D03*
X618470Y265732D03*
X629564Y253127D03*
X621060Y271066D03*
X633150Y301457D03*
X627950Y298897D03*
X627600Y309134D03*
X632143Y306575D03*
X630220Y314362D03*
X623365Y316742D03*
X631146Y317768D03*
X619474Y331162D03*
X619100Y374638D03*
X621720Y373362D03*
X622490Y402162D03*
X628500Y402362D03*
X624220Y411362D03*
X629220D03*
X623220Y426362D03*
X625500Y421362D03*
X629220D03*
Y426362D03*
X628900Y431050D03*
X625620Y447862D03*
X625900Y431050D03*
X625620Y442862D03*
X629220D03*
X622220D03*
X617220Y436362D03*
X622220Y452862D03*
Y447862D03*
X629220Y457862D03*
X626400Y462812D03*
X625620Y457862D03*
X622220D03*
X629220Y452862D03*
X625620D03*
X629220Y447862D03*
X626390Y467882D03*
X626210Y478002D03*
X626310Y472902D03*
X629220Y462862D03*
X622220D03*
X622520Y467862D03*
X629220Y487310D03*
X622860D03*
X626720Y482880D03*
X623670Y507862D03*
X629480Y508862D03*
X633000Y508700D03*
X629920Y516652D03*
X623000Y546900D03*
X629220Y643462D03*
X626720D03*
X617252Y739354D03*
X623497Y748235D03*
X626017Y745083D03*
X620870Y762072D03*
X617940Y763552D03*
X630417Y757135D03*
X628970Y1670880D03*
X637220Y31462D03*
X643880Y42142D03*
X647447Y46322D03*
X641200Y46762D03*
X638500Y57362D03*
X635000D03*
X637000Y68142D03*
X634500Y73422D03*
X645330Y77132D03*
Y72972D03*
X640220Y85542D03*
X634690D03*
X647220Y96929D03*
X639901Y103462D03*
X640000Y108542D03*
X639970Y113892D03*
X640130Y166362D03*
X643170Y171362D03*
X649870Y181942D03*
X645263Y235689D03*
X640295Y234237D03*
X645109Y249202D03*
Y260202D03*
X643800Y294327D03*
Y298297D03*
Y306547D03*
Y302247D03*
X645990Y314482D03*
X643800Y310962D03*
X633350Y314362D03*
X647100Y357372D03*
X636075Y389862D03*
X649075Y389937D03*
X632620Y389862D03*
X645925Y389937D03*
X638700Y400962D03*
X647700Y399162D03*
X643500Y400962D03*
X643940Y411482D03*
X637220Y411362D03*
X644220Y426362D03*
X640720Y418862D03*
X644220Y421362D03*
X637220Y416362D03*
Y426362D03*
X637195Y421362D03*
X647420Y434162D03*
X640720Y431362D03*
X644000Y438862D03*
X644220Y431362D03*
X638250Y439250D03*
X637220Y431362D03*
X644220Y452862D03*
X640820Y457902D03*
X637220Y452862D03*
X640720D03*
X640920Y447862D03*
X644220D03*
X637195Y457862D03*
X637220Y467862D03*
Y472862D03*
Y477862D03*
X644220D03*
Y462862D03*
X641235Y477377D03*
X640798Y472934D03*
X637220Y462862D03*
X640820Y467862D03*
X640620Y483422D03*
X642580Y508172D03*
X645220Y504362D03*
X646815Y517974D03*
X648296Y528255D03*
X637020Y522362D03*
X642630Y517870D03*
X640130D03*
X633147Y758595D03*
X647725Y1643719D03*
X643725Y1643467D03*
X648225Y1658482D03*
X642725Y1658562D03*
X635410Y1664220D03*
X637540Y1669480D03*
X636702Y1677610D03*
X645725Y1691182D03*
X640725Y1691452D03*
X650725Y1690682D03*
X646225Y1708169D03*
X642225Y1708457D03*
X648220Y1716912D03*
X636160Y1710662D03*
X639745Y1722362D03*
Y1718362D03*
X648220Y1722921D03*
X651943Y33535D03*
X663543Y43328D03*
X656950Y59012D03*
X651680Y73812D03*
X656500Y69662D03*
X661587D03*
X661600Y75562D03*
X657165Y79131D03*
X656426Y75431D03*
X652320Y123362D03*
X662498Y124960D03*
X650790Y149871D03*
Y140699D03*
X662880Y149912D03*
Y146912D03*
X651730Y177212D03*
X662560Y214152D03*
X662780Y210362D03*
Y205362D03*
Y207862D03*
X659880Y210762D03*
Y205762D03*
Y208262D03*
X650705Y270947D03*
X662891Y357442D03*
X662680Y354362D03*
X651520Y378662D03*
X658720Y399862D03*
X652000Y402362D03*
X653100Y407862D03*
X655820Y452662D03*
X655800Y461432D03*
X652195Y457862D03*
X655820Y467662D03*
X663000Y489500D03*
X663014Y493860D03*
X655220Y486862D03*
X661865Y505334D03*
X663720Y523806D03*
X665990Y517131D03*
X661220Y526862D03*
X650794Y515039D03*
X652577Y1000775D03*
X653690Y1392362D03*
X653761Y1396300D03*
X663187Y1395170D03*
Y1397720D03*
X666303Y1403476D03*
X663687Y1407279D03*
X654540Y1427605D03*
Y1424205D03*
X661100Y1451012D03*
X662660Y1548120D03*
X663410Y1553982D03*
X664590Y1631620D03*
X663097Y1642667D03*
X651725Y1643397D03*
X656725Y1660769D03*
X663118Y1655557D03*
X663043Y1651557D03*
X663145Y1672862D03*
Y1668862D03*
X653420Y1698662D03*
X663645Y1722862D03*
X680200Y39062D03*
X677560Y40572D03*
X672250Y40812D03*
X666943Y43328D03*
X682290Y46822D03*
X670612Y47264D03*
X674012D03*
X674035Y74522D03*
X678050Y58157D03*
X673987Y87662D03*
X677820Y89462D03*
X680578Y75992D03*
X674540Y80652D03*
X670800Y85932D03*
X667940Y80142D03*
X671320Y91192D03*
X677790Y104880D03*
X673720Y110362D03*
X674145Y113487D03*
X677978Y119668D03*
Y115668D03*
X675560Y117120D03*
X668300Y132400D03*
X665650Y147692D03*
X673713Y237725D03*
X674731Y359924D03*
X680600Y364282D03*
X683100Y369550D03*
X673220Y388362D03*
X675295Y399862D03*
X670720D03*
X668695Y408362D03*
Y404262D03*
X665870Y433942D03*
X675220Y508862D03*
X680220Y495887D03*
X670220Y503837D03*
X680220Y508862D03*
X675220Y521862D03*
X670720D03*
Y516862D03*
X680220Y530362D03*
X673340Y530922D03*
X673617Y744735D03*
X669700Y746626D03*
X677887Y742121D03*
X669778Y759929D03*
X670037Y1336396D03*
X664987D03*
X667487D03*
X664987Y1338896D03*
X667487D03*
X670037D03*
Y1333896D03*
X664987D03*
X667487D03*
X664987Y1348896D03*
X667487D03*
X664987Y1346396D03*
X667487D03*
X664987Y1343896D03*
Y1341396D03*
X667487D03*
Y1343896D03*
X670037Y1341396D03*
Y1343896D03*
Y1346396D03*
Y1348896D03*
X679881Y1399280D03*
X673477Y1409386D03*
X669477Y1406694D03*
X677619Y1408887D03*
X675876Y1406619D03*
X669477Y1409415D03*
X674149Y1434149D03*
X671149D03*
X668649D03*
X674149Y1426149D03*
Y1431149D03*
Y1428649D03*
X671149Y1426149D03*
X668649D03*
X671149Y1431149D03*
X668649Y1428649D03*
Y1431149D03*
X671149Y1428649D03*
X677319Y1428359D03*
Y1433359D03*
Y1430859D03*
X682160Y1548040D03*
X665410Y1548180D03*
X679207Y1560482D03*
X678877Y1566798D03*
X678621Y1571072D03*
X678610Y1582154D03*
X666560Y1581000D03*
X678619Y1579070D03*
X666600Y1584900D03*
X678900Y1595400D03*
X678771Y1585945D03*
X666700Y1595500D03*
X678900Y1589800D03*
X666700Y1591900D03*
X678900Y1592600D03*
X666700Y1588500D03*
X679640Y1617520D03*
Y1614000D03*
X679270Y1604040D03*
X675710Y1620320D03*
X673420Y1650057D03*
X671290Y1646320D03*
X668695Y1662235D03*
X671610Y1673792D03*
X671620Y1668303D03*
X677940Y1670110D03*
X678490Y1695660D03*
X674195Y1712362D03*
X675120Y1716242D03*
X674195Y1728362D03*
X672270Y1721612D03*
X687120Y39632D03*
X692289Y40633D03*
X689940Y38952D03*
X696800Y42108D03*
X696838Y47940D03*
X683440Y42832D03*
X687344Y46940D03*
X692389Y46439D03*
X694751Y70212D03*
X690027Y70142D03*
X685780Y70022D03*
X699475Y69982D03*
X685968Y58157D03*
X694400D03*
X681980D03*
X690510Y59132D03*
X696700Y72462D03*
X692389Y72692D03*
X687664Y73202D03*
X696370Y78512D03*
X696727Y81552D03*
Y84052D03*
X681053Y104668D03*
X695720Y102162D03*
X694220Y104862D03*
X688019Y109845D03*
X687030Y113090D03*
X687034Y115896D03*
X697615Y123697D03*
X687238Y171071D03*
X685600Y364282D03*
X690600D03*
X695600D03*
X683500Y381200D03*
X685210Y388852D03*
X694920Y388797D03*
X687500Y399402D03*
X692330Y388751D03*
X685220Y391652D03*
X692402Y391250D03*
X695220Y399862D03*
X685270Y408362D03*
Y404262D03*
X692400Y404682D03*
X683320Y490662D03*
X685220Y495887D03*
X690580Y482992D03*
X694510Y482942D03*
X686120Y481862D03*
X695220Y495887D03*
X690220D03*
X695220Y508862D03*
X685220D03*
X690220Y506362D03*
X685220Y503837D03*
X690220Y508882D03*
X690330Y503530D03*
X695257Y503847D03*
X695220Y516852D03*
X685220D03*
X690220Y519662D03*
X695220D03*
X689720Y530862D03*
X695220Y530662D03*
X683457Y745175D03*
X696810Y1300162D03*
X692280Y1302532D03*
X684555Y1338896D03*
X689605Y1336396D03*
Y1338896D03*
X687105Y1336396D03*
X684555D03*
X687105Y1338896D03*
X689605Y1333896D03*
X687105D03*
X684555D03*
X689605Y1348896D03*
X687105D03*
X689605Y1346396D03*
X687105D03*
X684555Y1341396D03*
Y1343896D03*
Y1346396D03*
Y1348896D03*
X689605Y1341396D03*
Y1343896D03*
X687105Y1341396D03*
Y1343896D03*
X684541Y1399280D03*
X682211Y1400030D03*
X686871D03*
X691777Y1405594D03*
Y1399794D03*
X689577Y1401194D03*
X687511Y1402924D03*
X691777Y1402694D03*
X689677Y1404194D03*
X687511Y1405824D03*
X694596Y1396198D03*
X694129Y1420283D03*
X696754Y1419809D03*
X691129Y1420283D03*
X681899Y1434049D03*
Y1426049D03*
Y1431049D03*
Y1428549D03*
X694129Y1423303D03*
X691129D03*
X696694Y1427949D03*
Y1425449D03*
Y1430449D03*
X696784Y1422614D03*
X683930Y1552562D03*
Y1555062D03*
Y1557562D03*
X692100Y1567190D03*
X692026Y1580490D03*
X697197Y1640667D03*
X697122Y1636667D03*
X689200Y1648843D03*
X686220Y1640667D03*
X697595Y1666862D03*
X687045Y1673362D03*
X706370Y46782D03*
X701838Y42202D03*
Y47940D03*
X703900Y72112D03*
X701400D03*
X713000Y69662D03*
X697720Y58162D03*
X710200Y69662D03*
X706867Y58197D03*
X703100Y58157D03*
X712500Y79862D03*
X710486Y77695D03*
X700500Y74862D03*
X698710Y86035D03*
X705390Y85792D03*
X703000Y84862D03*
X706720Y100462D03*
X699220Y102162D03*
X702720D03*
X701220Y104862D03*
X697720D03*
X712733Y117488D03*
Y114588D03*
X712290Y106722D03*
X712340Y128093D03*
X700600Y125309D03*
X707008Y125804D03*
X705800Y167788D03*
Y171188D03*
X704770Y182999D03*
Y179599D03*
Y194810D03*
Y191410D03*
Y218432D03*
Y206621D03*
Y215032D03*
Y203221D03*
X700600Y364282D03*
X705600D03*
X710600D03*
X709000Y354000D03*
X715600Y363900D03*
X705700Y361400D03*
X709400Y378200D03*
X713220Y378362D03*
X711200Y396500D03*
X707220Y399362D03*
X709160Y386730D03*
X713220Y388362D03*
X707400Y396200D03*
X713220Y399862D03*
X705195Y408362D03*
Y404262D03*
X705780Y411022D03*
X712770Y406822D03*
X705720Y488862D03*
X703220Y490362D03*
X705720Y484862D03*
X711220Y503842D03*
X705220D03*
Y508862D03*
X711220Y508882D03*
X710720Y521362D03*
X705220D03*
X701757Y521324D03*
X705220Y530362D03*
X710940Y591172D03*
X698602Y580536D03*
X705240Y594020D03*
X702740D03*
X712060Y638542D03*
X708680Y638812D03*
X708310Y646032D03*
X704320Y645262D03*
X704000Y740862D03*
X700500Y745862D03*
X703545Y745907D03*
X711720Y1286162D03*
X707720Y1290162D03*
X705720Y1286662D03*
X704795Y1294559D03*
X707320Y1301162D03*
X708137Y1336396D03*
Y1338896D03*
X703087Y1336396D03*
X705587D03*
Y1338896D03*
X703087D03*
X708137Y1333896D03*
X705587D03*
X703087D03*
Y1346396D03*
X705587D03*
X703087Y1348896D03*
X705587D03*
X708137Y1341396D03*
Y1343896D03*
X705587Y1341396D03*
X703087D03*
Y1343896D03*
X705587D03*
X708137Y1348896D03*
Y1346396D03*
X701330Y1395195D03*
Y1397695D03*
X704446Y1403476D03*
X701830Y1407326D03*
X711620Y1409386D03*
X707620Y1406694D03*
Y1409660D03*
X699754Y1419809D03*
X699694Y1427949D03*
Y1425449D03*
Y1430449D03*
X699784Y1422614D03*
X712222Y1570703D03*
X702112Y1571683D03*
Y1575683D03*
Y1579683D03*
X711102Y1575683D03*
X714162Y1574333D03*
X713052Y1579683D03*
X712582Y1584843D03*
X704497Y1598927D03*
X702112Y1587683D03*
Y1591683D03*
X713102Y1601307D03*
X715775Y1599024D03*
X714380Y1589960D03*
X702112Y1595683D03*
X712512Y1596338D03*
X711350Y1590720D03*
X711780Y1614590D03*
X704370Y1604580D03*
X706103Y1617107D03*
X708857Y1613462D03*
X710570Y1629890D03*
X708830Y1623115D03*
X705516Y1620296D03*
X710540Y1636070D03*
X708999Y1646762D03*
X703719Y1646768D03*
X697595Y1662862D03*
X700460Y1660918D03*
X709678Y1658485D03*
X697730Y1677460D03*
X704759Y1677001D03*
X723041Y-19800D03*
Y-23200D03*
X724620Y40062D03*
X728720Y43562D03*
X719820Y45862D03*
X717320Y44062D03*
X729293Y58062D03*
X724644Y58362D03*
X719949Y58862D03*
X715990Y69662D03*
X725740Y69580D03*
X721990Y69762D03*
X718900Y69662D03*
X727700Y60562D03*
X728591Y71960D03*
X722415Y77862D03*
X718425Y77882D03*
X728090Y75132D03*
X719100Y85262D03*
X727518Y90984D03*
X715933Y117488D03*
Y114588D03*
X729933Y108388D03*
X728733Y132088D03*
Y129288D03*
X720433Y135088D03*
X717433D03*
X728733Y126388D03*
X719933Y124488D03*
X723133D03*
X715940Y157362D03*
X718213Y159241D03*
X720633Y160788D03*
X717020Y220862D03*
X719720Y220142D03*
X722500Y365500D03*
X724897Y353887D03*
X721989Y351234D03*
X727000Y365500D03*
X731400D03*
X722500Y374100D03*
X727000D03*
X731400Y375000D03*
X718720Y381892D03*
X728220Y388362D03*
X723195Y408362D03*
Y404262D03*
X725220Y399862D03*
X723220Y508882D03*
X717220D03*
X729220D03*
Y503842D03*
X723220D03*
X717220D03*
X714000Y496132D03*
X723120Y525362D03*
X728220Y521362D03*
X717220D03*
X717296Y525407D03*
X723220Y516852D03*
X729220D03*
X717220D03*
X729212Y531700D03*
X729328Y583076D03*
X729295Y586113D03*
X725207Y579371D03*
X722707D03*
X715860Y585540D03*
X714320Y597462D03*
X723450Y597072D03*
X720240Y598292D03*
X715420Y639162D03*
X719190Y646642D03*
X717720Y643262D03*
X715220D03*
X723340Y642922D03*
X714087Y745865D03*
X720697Y765862D03*
X723460Y1245632D03*
X714720Y1286162D03*
X723054Y1333896D03*
X725604D03*
X728104D03*
X725604Y1338896D03*
X723054Y1336396D03*
X725604D03*
X728104Y1338896D03*
Y1336396D03*
X723054Y1338896D03*
X725604Y1346396D03*
X728104D03*
X725604Y1348896D03*
X728104D03*
X725604Y1343896D03*
Y1341396D03*
X728104Y1343896D03*
Y1341396D03*
X723054Y1348896D03*
Y1346396D03*
Y1343896D03*
Y1341396D03*
X725654Y1405824D03*
Y1402924D03*
X727720Y1401194D03*
X727820Y1404194D03*
X718024Y1399280D03*
X722684D03*
X720354Y1400030D03*
X725014D03*
X715762Y1408887D03*
X714019Y1406619D03*
X717300Y1547370D03*
X715792Y1567461D03*
X720370Y1566910D03*
X723520Y1561604D03*
X724712Y1566820D03*
X716612Y1584635D03*
X717152Y1570093D03*
X728977Y1574453D03*
X717402Y1574433D03*
X724465Y1580092D03*
X722465Y1582092D03*
X726465D03*
X723942Y1574123D03*
X724465Y1590950D03*
X722465Y1588950D03*
X726465D03*
X729052Y1602518D03*
X726092Y1598483D03*
X720987Y1599568D03*
X723542Y1612702D03*
X721488Y1610945D03*
X725910Y1611900D03*
X716688Y1610055D03*
X719168Y1612016D03*
X718195Y1647300D03*
X714203Y1642926D03*
X729150Y1641690D03*
X726810Y1652430D03*
X714071Y1663842D03*
X722630Y1655740D03*
X724500Y1680400D03*
X718758Y1673800D03*
X745900Y40362D03*
X733314Y40862D03*
X740100Y41162D03*
X746100Y46262D03*
X736620Y45262D03*
X745474Y57932D03*
X733642Y58062D03*
X741377Y57932D03*
X737595D03*
X732793Y71436D03*
X736193D03*
X742620Y71762D03*
X735880Y60662D03*
X740819Y82362D03*
X736720Y101662D03*
X745035Y94632D03*
X735770Y94988D03*
X739823Y91052D03*
X741308Y108742D03*
X738600Y136600D03*
X736060Y145532D03*
X740220Y145362D03*
X745725Y167537D03*
X732720Y231362D03*
X734220Y238362D03*
X744247Y312598D03*
X741800Y363200D03*
X742090Y356082D03*
X735600Y351400D03*
X735800Y365500D03*
X732700Y351500D03*
X740200Y375100D03*
X736220Y380787D03*
X742720Y380262D03*
X735800Y375000D03*
X738220Y388362D03*
X742160Y396452D03*
X738220Y383862D03*
X745720Y399862D03*
X735220Y410842D03*
X735745Y408362D03*
Y404262D03*
X733720Y399862D03*
X743980Y443482D03*
X740740Y473822D03*
X741420Y494162D03*
X747600Y506592D03*
X735220Y508862D03*
X745220Y503842D03*
X735220D03*
X735430Y516862D03*
X745220Y522362D03*
Y516852D03*
X730220Y523362D03*
X740840Y521982D03*
X735173Y521362D03*
X736480Y531722D03*
X738980D03*
X733922Y531712D03*
X733117Y580071D03*
Y582571D03*
X733134Y585672D03*
X736710Y603842D03*
Y607242D03*
X735620Y613862D03*
X730690Y655532D03*
X744538Y746524D03*
X737609Y744282D03*
X730889Y746834D03*
X740820Y741762D03*
X729920Y1405594D03*
X732226Y1396212D03*
X729920Y1399794D03*
Y1402694D03*
X733336Y1568341D03*
Y1565341D03*
Y1559341D03*
Y1562341D03*
X730336Y1559341D03*
Y1562341D03*
X745336D03*
Y1559341D03*
Y1565341D03*
Y1568341D03*
X742336Y1562341D03*
Y1559341D03*
Y1565341D03*
Y1568341D03*
X739336Y1562341D03*
Y1559341D03*
Y1565341D03*
Y1568341D03*
X736336D03*
Y1565341D03*
Y1559341D03*
Y1562341D03*
X733336Y1574341D03*
Y1571341D03*
X745336Y1574341D03*
Y1571341D03*
X742336Y1574341D03*
Y1571341D03*
X739336Y1574341D03*
Y1571341D03*
X736336D03*
Y1574341D03*
X730282Y1580391D03*
X741382Y1585251D03*
Y1580121D03*
X735882Y1580391D03*
X730282Y1590651D03*
Y1585521D03*
X735882Y1590651D03*
X741382Y1590691D03*
X732504Y1600321D03*
Y1597321D03*
X744504D03*
Y1600321D03*
X741504Y1597321D03*
Y1600321D03*
X735504Y1597321D03*
Y1600321D03*
X738504Y1597321D03*
Y1600321D03*
X744504Y1609521D03*
Y1612521D03*
X741504Y1609521D03*
X738504D03*
X735504D03*
X741504Y1612521D03*
X738504D03*
X735504D03*
X732504Y1603321D03*
Y1606321D03*
X744504Y1603321D03*
Y1606321D03*
X741504Y1603321D03*
Y1606321D03*
X738504Y1603321D03*
X735504D03*
X738504Y1606321D03*
X735504D03*
X735300Y1648760D03*
X737080Y1655820D03*
X735080Y1662980D03*
X740840Y1655590D03*
X732705Y1669450D03*
X754620Y51602D03*
X758620D03*
X749477Y57932D03*
X755700Y59942D03*
Y62442D03*
X758200Y59942D03*
Y62442D03*
X760700Y59942D03*
Y62442D03*
X747487Y71429D03*
X757693Y100653D03*
Y96423D03*
X750700Y106642D03*
X754800Y97082D03*
X750033Y92888D03*
Y89988D03*
X757340Y92562D03*
X748033Y116288D03*
X747230Y108572D03*
X760390Y111810D03*
X751220Y137864D03*
X747200Y251500D03*
X757150Y280592D03*
X758720Y283262D03*
X759920Y280562D03*
X758412Y298790D03*
X755305Y298847D03*
X748820Y284562D03*
X758390Y295450D03*
X748498Y309640D03*
X759637Y311585D03*
X757936Y303908D03*
X760670Y317432D03*
X747554Y384962D03*
X757430Y408212D03*
X760469Y442647D03*
X750290Y462162D03*
X757365Y459862D03*
X752500Y495762D03*
X757238Y483862D03*
X756642Y496522D03*
Y501744D03*
X751220Y522362D03*
Y516852D03*
X759790Y525522D03*
X755940Y516862D03*
X756650Y526072D03*
X761710Y517651D03*
X757020Y530462D03*
X759820D03*
X754220D03*
X762345Y1284542D03*
Y1287542D03*
Y1290542D03*
X762205Y1293272D03*
X757720Y1375462D03*
Y1384062D03*
X758020Y1397862D03*
X758420Y1406862D03*
X758120Y1414762D03*
X755420Y1426262D03*
Y1422862D03*
X748336Y1562341D03*
Y1559341D03*
Y1565341D03*
Y1568341D03*
X751336D03*
Y1565341D03*
Y1559341D03*
Y1562341D03*
X748336Y1574341D03*
Y1571341D03*
X760112Y1579183D03*
X749612Y1579023D03*
X749652Y1586407D03*
X760152Y1583183D03*
X749612Y1583023D03*
X760112Y1592183D03*
Y1587183D03*
X747504Y1600321D03*
X749662Y1590733D03*
X749612Y1594683D03*
X758360Y1589661D03*
X747504Y1609521D03*
Y1612521D03*
X750504D03*
Y1609521D03*
X747504Y1603321D03*
Y1606321D03*
X761716Y1661194D03*
X751620Y1674312D03*
X759859Y1686090D03*
X759359Y1729520D03*
X752875Y1726670D03*
X774059Y68912D03*
X773420Y143462D03*
X772328Y153728D03*
X771426Y158026D03*
X766320Y264892D03*
X763320D03*
X771630Y258102D03*
X762420Y280562D03*
X777420Y277962D03*
X769789Y296231D03*
X777467Y296315D03*
X769860Y302462D03*
X771377Y314139D03*
X771490Y354942D03*
X768490D03*
X777420Y354962D03*
X774490Y354942D03*
X765000Y354862D03*
X771960Y375162D03*
X767960Y369662D03*
X776000D03*
X764000D03*
X766195Y393212D03*
X773245Y398212D03*
X766195Y403212D03*
Y413212D03*
X773245Y403212D03*
Y408212D03*
X768910Y403260D03*
X771050Y416940D03*
X766195Y423212D03*
Y428212D03*
X768701Y418662D03*
X774982Y446908D03*
X772365Y454862D03*
X768720Y459862D03*
X765315Y454862D03*
Y459862D03*
X772365D03*
X765360Y475412D03*
X765335Y469552D03*
X772364Y475062D03*
X772365Y469862D03*
X765315Y479862D03*
X772365Y488862D03*
X776170Y493422D03*
X766510Y493452D03*
X765386Y483572D03*
X773530Y507062D03*
X765810Y506342D03*
X769745Y502600D03*
X775378Y502502D03*
X765521Y525364D03*
X769220Y530362D03*
X765720D03*
X777020D03*
X772020Y746562D03*
X774384Y744088D03*
X762562Y746444D03*
X769921Y742095D03*
X767421D03*
X764921D03*
X769337Y760775D03*
X762617Y758885D03*
X765345Y1284542D03*
X768335Y1284612D03*
X765345Y1287542D03*
Y1290542D03*
X768335Y1287612D03*
Y1290612D03*
X765205Y1293272D03*
X768195Y1293342D03*
X778005Y1294092D03*
X768520Y1384062D03*
Y1375462D03*
X768620Y1397262D03*
X775375Y1403561D03*
X767820Y1414762D03*
X763152Y1581893D03*
Y1577893D03*
Y1573793D03*
X773952Y1580493D03*
X768714Y1571203D03*
X769452Y1584393D03*
X770252Y1587268D03*
X763152Y1590893D03*
Y1594893D03*
X774052Y1590293D03*
X776922Y1590444D03*
X776052Y1611893D03*
X764920Y1695347D03*
X766880Y1689020D03*
X766603Y1721797D03*
X785180Y120947D03*
X792680D03*
X790180D03*
X787680D03*
X783940Y118637D03*
X786440D03*
X788940D03*
X781440D03*
X782553Y150031D03*
Y152531D03*
X779893Y147521D03*
Y150021D03*
X780820Y278262D03*
X785135Y274822D03*
X785200Y271400D03*
X794057Y301569D03*
X794220Y296062D03*
X785220Y284762D03*
X792943Y312642D03*
X784415Y313734D03*
X793896Y309026D03*
X793820Y304962D03*
X779120Y303410D03*
Y308755D03*
X785000Y355000D03*
X779920Y354962D03*
X782420D03*
X790120Y354862D03*
X792620D03*
X787600Y354900D03*
X795520Y393462D03*
X791075Y388000D03*
X781195Y393212D03*
X781320Y398212D03*
X787720Y408362D03*
X781195Y413212D03*
Y423212D03*
X785560Y417902D03*
X788120Y422942D03*
X791040Y422892D03*
X793660Y422842D03*
X785720Y427862D03*
X789230Y414942D03*
X780020Y441437D03*
Y445287D03*
X784730Y432682D03*
X787320Y444862D03*
Y439862D03*
X791582Y435352D03*
X781205Y454402D03*
X780315Y459862D03*
X787320Y454862D03*
Y449862D03*
Y459862D03*
X787360Y469862D03*
X786220Y464862D03*
X796315Y469290D03*
X780315Y464862D03*
X783340Y474802D03*
X782690Y488862D03*
X793220Y493362D03*
X781170Y493422D03*
X785800Y482762D03*
X793875Y483262D03*
X778670Y493422D03*
X783600Y502462D03*
X783450Y522462D03*
X783400Y511902D03*
X789720Y589862D03*
X785220Y581362D03*
X789720Y587362D03*
X791720Y593862D03*
X793720Y595862D03*
X791969Y618384D03*
X794720Y617862D03*
X783507Y761875D03*
X794157Y761295D03*
X782515Y766702D03*
X791140Y761693D03*
X792045Y1284542D03*
Y1290542D03*
Y1287542D03*
X791905Y1293272D03*
X791260Y1388662D03*
X790380Y1432132D03*
X784352Y1568293D03*
Y1565293D03*
Y1559293D03*
Y1562293D03*
X781352Y1568293D03*
Y1565293D03*
Y1559293D03*
Y1562293D03*
X793352D03*
Y1559293D03*
Y1565293D03*
Y1568293D03*
X790352Y1562293D03*
Y1559293D03*
Y1565293D03*
Y1568293D03*
X787352D03*
Y1565293D03*
Y1559293D03*
Y1562293D03*
X784352Y1574293D03*
Y1571293D03*
X781352Y1574293D03*
Y1571293D03*
X793352Y1574293D03*
Y1571293D03*
X790352Y1574293D03*
Y1571293D03*
X787352D03*
Y1574293D03*
X788079Y1580393D03*
X782479D03*
X793579D03*
X788079Y1590653D03*
X782479D03*
Y1585523D03*
X793579Y1590653D03*
Y1585523D03*
X785052Y1600693D03*
Y1597693D03*
X782052D03*
Y1600693D03*
X794052D03*
X788052D03*
X791052D03*
X794052Y1597693D03*
X788052D03*
X791052D03*
X785052Y1607793D03*
X782052D03*
X779052D03*
X785052Y1611893D03*
X782052D03*
X779052D03*
X794052Y1607793D03*
X791052D03*
X788052D03*
X797052Y1611893D03*
X794052D03*
X788052D03*
X791052D03*
X785052Y1603693D03*
X782052D03*
X794052D03*
X788052D03*
X791052D03*
X808800Y267900D03*
X810920Y280062D03*
X798204Y279146D03*
X797924Y298358D03*
X806450Y310362D03*
X803620Y302962D03*
X805870Y304812D03*
X799720Y300462D03*
X795920Y312662D03*
X803280Y354982D03*
X800646Y354921D03*
X795220Y354862D03*
X806000Y360600D03*
X798400D03*
X805910Y355012D03*
X797900Y354800D03*
X795520Y398212D03*
X800352Y408389D03*
X803120Y428762D03*
X797720Y428412D03*
X798370Y439932D03*
X802010Y439940D03*
X802790Y433832D03*
X795320Y439862D03*
X805720Y432902D03*
X801750Y444330D03*
X795320Y444862D03*
X810860Y454862D03*
X802810D03*
X795320D03*
Y449862D03*
X802810Y464862D03*
Y449862D03*
X810860Y459862D03*
X802810D03*
X795320D03*
X810860Y449862D03*
X798990Y474862D03*
X802865D03*
X795320Y464862D03*
X810815Y474862D03*
X810860Y464862D03*
X810815Y469862D03*
X807220Y493362D03*
X801940Y485932D03*
X804510Y486122D03*
X809510D03*
X799230Y485922D03*
X812510Y486422D03*
X802790Y495652D03*
X805470Y510522D03*
X807640Y506672D03*
X808100Y509900D03*
X797420Y512503D03*
X805445Y587582D03*
X810720Y586862D03*
X811143Y605265D03*
X807945Y594362D03*
X803220D03*
X797200Y599883D03*
X795720Y614862D03*
X796702Y761195D03*
X810850Y770272D03*
X799577Y760985D03*
X807000Y757562D03*
X798035Y1284612D03*
X795045Y1284542D03*
X798035Y1290612D03*
Y1287612D03*
X795045Y1290542D03*
Y1287542D03*
X797895Y1293342D03*
X794905Y1293272D03*
X806323Y1343076D03*
X812130Y1343022D03*
X809210Y1343062D03*
X804100Y1435010D03*
X800000Y1431100D03*
X799352Y1562293D03*
Y1559293D03*
Y1565293D03*
Y1568293D03*
X796352Y1562293D03*
Y1559293D03*
Y1565293D03*
Y1568293D03*
X799352Y1574293D03*
Y1571293D03*
X796352Y1574293D03*
Y1571293D03*
X804652Y1581793D03*
Y1573793D03*
X812652Y1577793D03*
X801652Y1584539D03*
X812698Y1587047D03*
X804652Y1597793D03*
Y1585993D03*
X799152Y1586507D03*
X804652Y1589793D03*
X797052Y1607793D03*
X804652Y1609793D03*
X827114Y115223D03*
X823114D03*
X814570Y145952D03*
X814531Y139851D03*
X820900Y147112D03*
X815060Y280072D03*
X813490Y273862D03*
X816220Y277162D03*
X813293Y287062D03*
X826300Y311962D03*
X823800D03*
X818000Y378800D03*
X813210Y374292D03*
X815710D03*
X825003Y389012D03*
Y397276D03*
X819220Y397664D03*
X824980Y413260D03*
X819220Y412264D03*
X823600Y421194D03*
X815310Y440100D03*
X816810Y464862D03*
X825100Y468900D03*
X824860Y464862D03*
X816400Y472900D03*
X820720Y493862D03*
X822415Y479600D03*
X821720Y511082D03*
X814305Y499503D03*
X819320Y502347D03*
X821720Y527082D03*
X815650Y516807D03*
X821720Y515082D03*
Y523082D03*
X820220Y586862D03*
X814220Y582530D03*
X823720Y594862D03*
X820470Y595112D03*
X815120Y593582D03*
X820613Y744641D03*
X823589Y746924D03*
X822374Y757039D03*
X814770Y763874D03*
X815789Y1008845D03*
X826090Y1334362D03*
Y1339362D03*
Y1329362D03*
Y1344362D03*
X820920Y1344342D03*
X818420D03*
X823352Y1565293D03*
Y1562293D03*
Y1559293D03*
Y1568293D03*
X826352Y1565293D03*
Y1562293D03*
Y1559293D03*
Y1568293D03*
X823352Y1571293D03*
Y1574293D03*
X826352Y1571293D03*
Y1574293D03*
X824479Y1580393D03*
X815652Y1582570D03*
Y1573793D03*
X813352Y1590893D03*
X812652Y1593793D03*
X824479Y1590653D03*
Y1585523D03*
X824052Y1597693D03*
Y1600693D03*
X827052D03*
Y1597693D03*
X815551Y1593793D03*
X818652Y1590444D03*
X812652Y1605793D03*
X824052Y1611893D03*
Y1607793D03*
Y1603693D03*
X827052Y1611893D03*
Y1607793D03*
Y1603693D03*
X821052Y1611893D03*
Y1607793D03*
X818052Y1611893D03*
X812652Y1601793D03*
X840001Y6800D03*
Y10200D03*
X836779Y68008D03*
X828600Y61752D03*
X839898Y87248D03*
X841584Y94181D03*
X837250Y93221D03*
X839360Y114862D03*
X835114Y115223D03*
X845220Y135862D03*
Y129362D03*
X829114Y147123D03*
X828145Y160362D03*
X838220Y163862D03*
X835220D03*
X837320Y175112D03*
X842720Y181360D03*
X837160Y218212D03*
Y213207D03*
X844526Y204968D03*
X838820Y206872D03*
X837500Y229642D03*
X840063Y285022D03*
X839450Y272662D03*
X835400Y268800D03*
X829620Y280345D03*
X829820Y275045D03*
X840850Y278948D03*
X829720Y292762D03*
X839860Y294702D03*
X827620Y302962D03*
X830417Y311865D03*
X836300Y418800D03*
X832400Y427100D03*
X840400Y418900D03*
X831720Y457700D03*
X839640Y449612D03*
X832700Y446800D03*
X830600Y449200D03*
X838220Y459562D03*
X841200Y456500D03*
X832720Y494862D03*
X829720D03*
X838645Y492862D03*
X830870Y480010D03*
X832590Y512888D03*
X829745Y502082D03*
X832370Y525849D03*
X843287Y527817D03*
X841461Y525849D03*
X840990Y529786D03*
X828009Y587913D03*
X831705Y593877D03*
X829230Y582772D03*
X831530Y651932D03*
X830587Y741205D03*
X833120Y743392D03*
X838587Y766825D03*
X841827Y766795D03*
X837127Y758976D03*
X829420Y758422D03*
X841997Y773085D03*
X838020Y1232432D03*
X832090Y1326862D03*
Y1331862D03*
Y1336862D03*
Y1341862D03*
X829352Y1565293D03*
Y1562293D03*
Y1559293D03*
Y1568293D03*
X832352D03*
Y1565293D03*
Y1559293D03*
Y1562293D03*
X835352Y1568293D03*
Y1565293D03*
Y1559293D03*
Y1562293D03*
X838352Y1568293D03*
Y1565293D03*
Y1559293D03*
Y1562293D03*
X841352Y1568293D03*
Y1565293D03*
Y1559293D03*
Y1562293D03*
X829352Y1574293D03*
Y1571293D03*
X832352D03*
Y1574293D03*
X835352Y1571293D03*
Y1574293D03*
X838352Y1571293D03*
Y1574293D03*
X841352Y1571293D03*
Y1574293D03*
X830079Y1580393D03*
X835579D03*
X843652Y1584539D03*
X833052Y1597693D03*
X836052D03*
X830079Y1590653D03*
X835579D03*
X833052Y1600693D03*
X836052D03*
X835579Y1585523D03*
X830052Y1600693D03*
Y1597693D03*
X841152Y1586507D03*
X833052Y1603693D03*
X836052D03*
X839052Y1611893D03*
X833052Y1607793D03*
Y1611893D03*
X836052Y1607793D03*
Y1611893D03*
X830052D03*
Y1607793D03*
Y1603693D03*
X839052Y1607793D03*
X858629Y60293D03*
X850015Y87341D03*
X843855Y87711D03*
X847472Y94754D03*
X847660Y113962D03*
X853100Y113762D03*
X854100Y132972D03*
X854220Y135862D03*
Y129362D03*
X854200Y138562D03*
X848745Y160187D03*
X848709Y156752D03*
X848360Y182872D03*
X845720Y181362D03*
X855858Y212425D03*
X855933Y215375D03*
X860050Y215310D03*
X847580Y232222D03*
X853828Y269043D03*
X850133Y271049D03*
X861865Y273730D03*
X850093Y286625D03*
X855480Y299692D03*
X856243Y286447D03*
X859920Y308852D03*
X859740Y399081D03*
X846040Y399210D03*
X846490Y422131D03*
X850610Y444352D03*
X851606Y447927D03*
X844210Y455902D03*
X846700Y476900D03*
X855200D03*
X857620Y492862D03*
X858600Y511130D03*
X848620Y509752D03*
X853070Y515447D03*
X857195Y522162D03*
X859888Y593970D03*
X859054Y583752D03*
X845523Y582126D03*
X856520Y751262D03*
X859450Y750462D03*
X844957Y763065D03*
X854620Y1242125D03*
X854237Y1250358D03*
X846652Y1581793D03*
Y1573793D03*
X854652Y1577793D03*
X857652Y1582570D03*
Y1573793D03*
X854777Y1586968D03*
X846652Y1597793D03*
X855352Y1590893D03*
X854652Y1593793D03*
X846652Y1585993D03*
X857551Y1593793D03*
X846652Y1589793D03*
X854652Y1605793D03*
Y1601793D03*
X846652Y1609793D03*
X862930Y70072D03*
X866330D03*
X862452Y151590D03*
X867620Y154362D03*
X871145Y163862D03*
X871580Y183370D03*
X875169Y185113D03*
X864859Y187110D03*
X873200Y194262D03*
X871890Y196740D03*
X877971Y196652D03*
X867528Y231788D03*
X875543Y266447D03*
X867700Y268262D03*
X875543Y269347D03*
X863747Y280870D03*
X867237Y273325D03*
X868552Y285537D03*
X874243Y287047D03*
X877322Y296051D03*
X872320Y304936D03*
X869820D03*
X867320D03*
X864820D03*
X860531Y375826D03*
X870700Y386476D03*
Y398620D03*
Y402581D03*
X868113Y409372D03*
X870513Y414276D03*
X862320Y431462D03*
X863415Y445829D03*
X860574Y445404D03*
X861080Y459742D03*
X870360Y493042D03*
X862620Y507162D03*
X868110Y499142D03*
X865290Y499032D03*
X865810Y521862D03*
X866820Y736562D03*
X863925Y737697D03*
X864680Y751582D03*
X874155Y756993D03*
X864700Y778300D03*
X868352Y1568293D03*
Y1565293D03*
Y1559293D03*
Y1562293D03*
X865352Y1568293D03*
Y1565293D03*
Y1559293D03*
Y1562293D03*
X874352D03*
Y1559293D03*
Y1565293D03*
Y1568293D03*
X871352D03*
Y1565293D03*
Y1559293D03*
Y1562293D03*
X868352Y1574293D03*
Y1571293D03*
X865352Y1574293D03*
Y1571293D03*
X874352Y1574293D03*
Y1571293D03*
X871352D03*
Y1574293D03*
X866479Y1580393D03*
X872079D03*
X866052Y1597693D03*
X869052D03*
X866479Y1590653D03*
X869052Y1600693D03*
X866052D03*
X872052Y1597693D03*
X872079Y1590653D03*
X872052Y1600693D03*
X866479Y1585523D03*
X875052Y1597693D03*
Y1600693D03*
X860652Y1590444D03*
X869052Y1603693D03*
X866052D03*
X872052D03*
X869052Y1607793D03*
Y1611893D03*
X866052Y1607793D03*
X863052Y1611893D03*
X866052D03*
X872052Y1607793D03*
Y1611893D03*
X875052Y1603693D03*
Y1607793D03*
Y1611893D03*
X863052Y1607793D03*
X860052Y1611893D03*
X878327Y183169D03*
X876695Y171362D03*
Y176862D03*
X887520Y171362D03*
Y176862D03*
X877724Y200837D03*
X878220Y187449D03*
X888929Y209223D03*
X891620Y209662D03*
X888929Y206723D03*
X891620Y207162D03*
X884003Y278712D03*
X883870Y275802D03*
X883909Y281862D03*
X879587Y270004D03*
X883870Y272652D03*
X887338Y296760D03*
X882520Y327562D03*
X885020D03*
X887520D03*
X890422Y333879D03*
X893440Y336232D03*
X890820Y389362D03*
X890920Y386352D03*
X889453Y458926D03*
X887590Y471552D03*
X889439Y489599D03*
Y492999D03*
X881680Y504742D03*
Y508142D03*
X884512Y523800D03*
X882410Y526132D03*
X888130Y532612D03*
X891530D03*
X887810Y582442D03*
X889000Y737562D03*
X885310Y736442D03*
X886720Y741902D03*
X878192Y879910D03*
X884747Y871745D03*
X879100Y912608D03*
X884619Y916477D03*
X892317Y915872D03*
X880102Y923235D03*
X891560Y1435510D03*
X883352Y1562293D03*
Y1559293D03*
Y1565293D03*
Y1568293D03*
X880352Y1562293D03*
Y1559293D03*
Y1565293D03*
Y1568293D03*
X877352Y1562293D03*
Y1559293D03*
Y1565293D03*
Y1568293D03*
X883352Y1574293D03*
Y1571293D03*
X880352Y1574293D03*
Y1571293D03*
X877352Y1574293D03*
Y1571293D03*
X888652Y1581793D03*
Y1573793D03*
X877579Y1580393D03*
X885652Y1584539D03*
X888652Y1597793D03*
Y1585993D03*
X877579Y1585523D03*
X878052Y1597693D03*
Y1600693D03*
X877579Y1590653D03*
X883152Y1586507D03*
X888652Y1589793D03*
X878052Y1603693D03*
Y1607793D03*
X881052Y1611893D03*
X878052D03*
X881052Y1607793D03*
X888652Y1609793D03*
X908620Y188899D03*
X896620Y209662D03*
X894120D03*
Y207162D03*
X896620D03*
X906120Y261252D03*
X894770Y283062D03*
X896540Y341132D03*
X902260Y473153D03*
Y475653D03*
X903124Y470797D03*
X900020Y470672D03*
X896060Y481222D03*
Y484622D03*
X907678Y488177D03*
X895340Y497882D03*
Y501282D03*
X901829Y512730D03*
Y516130D03*
X893450Y516862D03*
X901230Y531612D03*
X904630D03*
X894897Y871745D03*
X894965Y917422D03*
X899830Y971484D03*
Y974884D03*
X907770Y1045242D03*
X894830Y1435970D03*
X907352Y1568293D03*
Y1565293D03*
Y1559293D03*
Y1562293D03*
Y1574293D03*
Y1571293D03*
X908479Y1580393D03*
X896652Y1577793D03*
X899652Y1582570D03*
Y1573793D03*
X896672Y1587073D03*
X897352Y1590893D03*
X896652Y1593793D03*
X908479Y1590653D03*
Y1585523D03*
X908052Y1600693D03*
Y1597693D03*
X899551Y1593793D03*
X902652Y1590444D03*
X896652Y1605793D03*
X908052Y1611893D03*
X905052D03*
X902052D03*
X908052Y1607793D03*
X905052D03*
X908052Y1603693D03*
X896652Y1601793D03*
X922726Y176302D03*
X922100Y181791D03*
X917386Y184114D03*
X924920Y196199D03*
X923836Y193563D03*
X923897Y445545D03*
X927034Y445594D03*
X912984Y458135D03*
X909584D03*
X924447Y463012D03*
X921047D03*
X909190Y473392D03*
X912288Y472430D03*
X918532Y492445D03*
X927154Y492103D03*
X924623Y492097D03*
X918078Y495177D03*
X921189Y492086D03*
X918212Y497677D03*
X918131Y503330D03*
X921060Y506086D03*
X923783Y506076D03*
X918212Y500777D03*
X909984Y496330D03*
X926173Y512391D03*
X913394Y521662D03*
X916794D03*
X909600Y521162D03*
X922879Y531976D03*
Y528576D03*
X918420Y804062D03*
X909720Y798861D03*
Y794862D03*
X913720Y799362D03*
X914152Y803294D03*
X921757Y962082D03*
X916974Y962108D03*
X923930Y976652D03*
X917980Y974952D03*
X924440Y996852D03*
X914838Y985989D03*
X918720Y1009937D03*
X910352Y1568293D03*
Y1565293D03*
Y1559293D03*
Y1562293D03*
X922352D03*
Y1559293D03*
Y1565293D03*
Y1568293D03*
X919352Y1562293D03*
Y1559293D03*
Y1565293D03*
Y1568293D03*
X916352Y1562293D03*
Y1559293D03*
Y1565293D03*
Y1568293D03*
X913352D03*
Y1565293D03*
Y1559293D03*
Y1562293D03*
X910352Y1574293D03*
Y1571293D03*
X922352Y1574293D03*
Y1571293D03*
X919352Y1574293D03*
Y1571293D03*
X916352Y1574293D03*
Y1571293D03*
X913352D03*
Y1574293D03*
X919579Y1580393D03*
X914079D03*
X919579Y1590653D03*
X914079D03*
X919579Y1585523D03*
X917052Y1600693D03*
Y1597693D03*
X914052Y1600693D03*
Y1597693D03*
X911052Y1600693D03*
Y1597693D03*
X920052Y1600693D03*
Y1597693D03*
X917052Y1611893D03*
X914052D03*
X911052D03*
X917052Y1607793D03*
X914052D03*
X911052D03*
X920052Y1611893D03*
X923052D03*
Y1607793D03*
X920052D03*
X917052Y1603693D03*
X914052D03*
X911052D03*
X920052D03*
X919488Y1660733D03*
X918020Y1672860D03*
X914500Y1671400D03*
X938160Y173389D03*
X935550Y173329D03*
X940720Y173389D03*
X938160Y176389D03*
X935550Y176329D03*
X940720Y176389D03*
X940424Y184190D03*
X936424D03*
X935770Y191419D03*
X939270D03*
X940410Y188852D03*
X930472Y246093D03*
X938603Y240063D03*
X933122Y246115D03*
X933686Y242922D03*
X935454Y241154D03*
X933217Y380693D03*
Y384693D03*
X941059Y427911D03*
Y424511D03*
X937447Y457862D03*
X934047D03*
X928394Y472201D03*
Y474701D03*
X932373Y495175D03*
X932089Y492691D03*
X929654Y492103D03*
X932218Y499314D03*
X939872Y495813D03*
X932089Y505986D03*
X932289Y502986D03*
X926637Y506069D03*
X929281Y506086D03*
X931720Y524862D03*
X940550Y517400D03*
X940140Y514925D03*
X933773Y530479D03*
X930731D03*
X941050Y532252D03*
Y528852D03*
X938742Y803831D03*
X931573Y816109D03*
X927470Y815112D03*
X935052Y812630D03*
X934260Y808312D03*
X938371Y809311D03*
X930786Y811785D03*
X925220Y817862D03*
X928237Y824844D03*
X926469Y826612D03*
X926823Y962082D03*
X940170Y962842D03*
X939740Y987762D03*
X936998Y985750D03*
X932310Y996812D03*
X927220Y1012362D03*
X931220D03*
X925352Y1562293D03*
Y1559293D03*
Y1565293D03*
Y1568293D03*
Y1574293D03*
Y1571293D03*
X938652Y1581393D03*
X928152Y1584539D03*
X938652Y1593393D03*
Y1585393D03*
X925152Y1586507D03*
X938652Y1589393D03*
X933979Y1661327D03*
X929979Y1661352D03*
X942100Y1671100D03*
X945720Y173389D03*
X943220D03*
X945720Y176389D03*
X943220D03*
X948400Y176499D03*
X949120Y184912D03*
X944250Y194489D03*
Y197889D03*
X957020Y193299D03*
X949550Y192819D03*
X957020Y264862D03*
X953046Y390103D03*
X951181Y391916D03*
X950660Y399472D03*
X956487Y394831D03*
X949920Y404602D03*
X944032Y437631D03*
Y434231D03*
X945447Y463012D03*
X942047D03*
X946727Y507952D03*
Y504552D03*
X954420Y511252D03*
Y500552D03*
Y497152D03*
Y514652D03*
X954390Y527596D03*
X945524Y515483D03*
X944261Y517871D03*
X941740Y512922D03*
X942610Y515350D03*
X945100Y534464D03*
X955123Y533642D03*
X948415Y534313D03*
X956518Y531567D03*
X957220Y582862D03*
X953594Y787477D03*
X954447Y791735D03*
X951043Y796140D03*
X950190Y791382D03*
X944272Y803410D03*
X943366Y798707D03*
X946786Y795287D03*
X947921Y799761D03*
X944170Y962842D03*
X949560Y981392D03*
X951560Y997422D03*
X956980Y1536260D03*
X953980D03*
X950980D03*
X947980D03*
X944980D03*
Y1551260D03*
X947980D03*
X950980D03*
X953980D03*
X956980D03*
X944980Y1548260D03*
X947980D03*
X950980D03*
X953980D03*
X956980D03*
X944980Y1545260D03*
X947980D03*
X950980D03*
X953980D03*
X956980D03*
X944980Y1542260D03*
X947980D03*
X950980D03*
X953980D03*
X956980D03*
Y1539260D03*
X953980D03*
X950980D03*
X947980D03*
X944980D03*
Y1554260D03*
X947980D03*
X950980D03*
X953980D03*
X956980D03*
X956800Y1663725D03*
X956600Y1666875D03*
X962604Y165313D03*
X962458Y162398D03*
X965150Y193412D03*
X966720Y198099D03*
X970720D03*
X961120Y193299D03*
X968384Y242051D03*
X965884D03*
X960020Y264862D03*
X963020D03*
X962570Y282812D03*
X962882Y314512D03*
X967239Y320073D03*
X963854Y320113D03*
X963300Y347962D03*
X962623Y350642D03*
X970730Y377872D03*
X972220Y386251D03*
Y390239D03*
X975670Y392063D03*
X963856Y398302D03*
X965890Y405967D03*
X963720Y439862D03*
X961320Y476242D03*
X968286Y483941D03*
Y480541D03*
X964347Y509462D03*
X970788Y501230D03*
X964347Y501262D03*
X969351Y512416D03*
X957790Y527596D03*
X963930Y533362D03*
X967330D03*
X959351Y533566D03*
X960920Y644762D03*
Y649762D03*
Y654762D03*
X963720Y647262D03*
Y657262D03*
Y652262D03*
X960820Y665062D03*
X960920Y659762D03*
X963720Y662262D03*
X967750Y1376460D03*
X969000Y1536262D03*
X971700D03*
X969000Y1548262D03*
X971700D03*
X969000Y1545262D03*
X971700D03*
X969000Y1551262D03*
X971700D03*
Y1542262D03*
X969000D03*
X971700Y1539262D03*
X969000D03*
X965904Y1554364D03*
X960904D03*
X969000Y1554262D03*
X971700D03*
X965622Y1579240D03*
Y1576240D03*
Y1573240D03*
X966852Y1585920D03*
X969852D03*
X960852D03*
X963852D03*
X957852D03*
X965086Y1603984D03*
X962086D03*
X980899Y-19800D03*
Y-23200D03*
Y6800D03*
Y10200D03*
X990501Y152397D03*
X986369Y155358D03*
X975690Y157220D03*
X983811Y156694D03*
X985499Y168753D03*
X985431Y181058D03*
X990115Y173039D03*
X987320Y194599D03*
Y198099D03*
Y201599D03*
X977220Y201399D03*
X986020Y191099D03*
X981795Y216623D03*
X978012Y276436D03*
X975512Y282096D03*
X978012D03*
X975512Y279266D03*
X978012D03*
X981470Y268532D03*
X979940Y292262D03*
Y289762D03*
X975512Y294996D03*
X978012D03*
X979940Y284762D03*
Y287262D03*
X988818Y346372D03*
X978000Y362462D03*
X988723Y369650D03*
X991934Y368443D03*
X988908Y373392D03*
X986400Y383123D03*
X983770Y373962D03*
X979766Y377507D03*
X977949Y384205D03*
X980916Y384286D03*
X980856Y392502D03*
X986955Y391939D03*
X983629Y397628D03*
X979559Y399362D03*
X983970Y392562D03*
X991369Y408252D03*
X979240Y425212D03*
X984254Y418379D03*
X987440Y431193D03*
X980720Y512362D03*
X986400Y503200D03*
X986273Y532996D03*
X980535Y532643D03*
X986418Y530019D03*
X975900Y1265062D03*
X987920Y1290662D03*
X985320Y1288762D03*
X992306Y1295049D03*
X979373Y1342724D03*
X974700Y1536262D03*
X980400D03*
X977700D03*
X974700Y1548262D03*
Y1545262D03*
Y1551262D03*
X980400Y1548262D03*
X977700D03*
X980400Y1545262D03*
X977700D03*
X980400Y1551262D03*
X977700D03*
Y1542262D03*
X980400D03*
X974700D03*
X977700Y1539262D03*
X980400D03*
X974700D03*
X984270Y1554364D03*
X974700Y1554262D03*
X980400D03*
X977700D03*
X989270Y1554364D03*
X988988Y1579240D03*
Y1573240D03*
Y1576240D03*
X995000Y150883D03*
X1001500D03*
X995180Y153689D03*
X1006220Y160799D03*
X1002720D03*
X1001101Y165510D03*
X999220Y185299D03*
X1002720D03*
X1006220D03*
X996415Y172579D03*
X1002920Y174799D03*
X990220Y195699D03*
Y199199D03*
X1008120Y198293D03*
X990195Y216823D03*
X990220Y202699D03*
X1000610Y211039D03*
X1005640Y210969D03*
X1001195Y219898D03*
X1005120Y230399D03*
X994743Y289843D03*
X1006232Y343983D03*
X1001440Y359702D03*
X994689Y379348D03*
X1006201Y370004D03*
X999440Y371782D03*
X996922Y367764D03*
X994322Y404090D03*
X1005123Y414662D03*
X997617Y412383D03*
X997394Y415578D03*
X993012Y421570D03*
X997225Y419162D03*
X990840Y431193D03*
X1005720Y498862D03*
X1003220Y512862D03*
X1005520Y510932D03*
X991237Y533043D03*
X1008560Y589682D03*
X1005960Y594682D03*
X1005373Y748826D03*
X995120Y773122D03*
X994942Y777055D03*
X996320Y1280683D03*
Y1284062D03*
X997920Y1278762D03*
X994574Y1297318D03*
X995066Y1536262D03*
X992466D03*
X1001066D03*
X1003766D03*
X998066D03*
X995066Y1551262D03*
X992466D03*
X995066Y1545262D03*
X992466D03*
X995066Y1548262D03*
X992466D03*
X1001066Y1551262D03*
X1003766D03*
X1001066Y1545262D03*
X1003766D03*
X1001066Y1548262D03*
X1003766D03*
X998066Y1551262D03*
Y1545262D03*
Y1548262D03*
Y1542262D03*
X1003766D03*
X1001066D03*
X992466D03*
X995066D03*
X998066Y1539262D03*
X1003766D03*
X1001066D03*
X992466D03*
X995066D03*
X1007636Y1554364D03*
X995066Y1554262D03*
X992466D03*
X1001066D03*
X1003766D03*
X998066D03*
X1002782Y1585920D03*
X999782D03*
X996782D03*
X990782D03*
X993782D03*
X996698Y1604000D03*
X993698D03*
X1008129Y150948D03*
X1009720Y160799D03*
X1013220D03*
X1012791Y157596D03*
X1012000Y185299D03*
X1014900D03*
X1017800D03*
X1017200Y175699D03*
X1014300D03*
X1019900Y175799D03*
X1020645Y190499D03*
X1011320Y202169D03*
X1019355Y218423D03*
X1019802Y214099D03*
X1010005Y208424D03*
X1011720Y229699D03*
X1019355Y222423D03*
X1019530Y226423D03*
X1007820Y229999D03*
X1021118Y294290D03*
X1020720Y310937D03*
X1015520Y302862D03*
X1009800Y343800D03*
X1021695Y364518D03*
X1006710Y372931D03*
X1015096Y373758D03*
X1017163Y367963D03*
X1009883Y367955D03*
X1010420Y416062D03*
X1015420Y410862D03*
X1009009Y419948D03*
X1021239Y416974D03*
X1016261Y432888D03*
X1012861D03*
X1024200Y510362D03*
X1018092Y520212D03*
X1020392Y521826D03*
X1016360Y594682D03*
X1016220Y590862D03*
X1019000Y601042D03*
X1021654Y606302D03*
X1011160Y594682D03*
X1007873Y748826D03*
X1007600Y1298250D03*
X1007610Y1295040D03*
X1021612Y1536262D03*
X1016012D03*
X1018612D03*
Y1551262D03*
X1016012D03*
X1018612Y1545262D03*
X1016012D03*
X1018612Y1548262D03*
X1016012D03*
X1021612Y1551262D03*
Y1545262D03*
Y1548262D03*
X1018612Y1542262D03*
X1016012D03*
X1021612D03*
Y1539262D03*
X1016012D03*
X1018612D03*
Y1554262D03*
X1016012D03*
X1021612D03*
X1012636Y1554364D03*
X1012354Y1579240D03*
Y1573240D03*
Y1576240D03*
X1021942Y1586090D03*
X1032433Y-29811D03*
Y-33211D03*
X1026620Y125662D03*
X1034229Y128953D03*
X1032894Y155185D03*
X1022800Y175799D03*
X1037618Y261200D03*
X1031702Y264130D03*
X1025862Y291727D03*
X1032317Y291284D03*
X1036278Y303993D03*
Y307393D03*
X1033285Y353627D03*
X1029395Y375844D03*
X1025004Y374662D03*
X1031950Y383771D03*
Y387171D03*
X1031153Y390152D03*
X1026820Y394362D03*
X1038320Y407062D03*
Y404462D03*
X1026548Y400571D03*
X1035920Y420062D03*
Y417462D03*
X1026370Y503562D03*
X1032155Y509737D03*
X1025530Y519627D03*
X1033040Y519852D03*
X1038130Y518417D03*
X1040720Y591862D03*
X1024154Y601152D03*
X1029630Y601252D03*
X1026654Y596152D03*
X1035760Y592952D03*
X1033260Y601272D03*
X1038260D03*
X1033817Y735612D03*
X1036954Y734669D03*
X1030660Y735082D03*
X1027212Y1536262D03*
X1024612D03*
Y1551262D03*
X1027212D03*
X1024612Y1545262D03*
X1027212D03*
X1024612Y1548262D03*
X1027212D03*
X1024612Y1542262D03*
X1027212D03*
Y1539262D03*
X1024612D03*
X1031002Y1554364D03*
X1024612Y1554262D03*
X1027212D03*
X1036002Y1554364D03*
X1035720Y1579240D03*
Y1573240D03*
Y1576240D03*
X1030942Y1586090D03*
X1033942D03*
X1024942D03*
X1027942D03*
X1028298Y1604000D03*
X1025298D03*
X1040970Y128332D03*
X1043720Y363462D03*
X1054820Y370162D03*
X1044120Y366362D03*
X1040120Y393962D03*
X1042720D03*
X1041420Y443962D03*
X1043920D03*
X1050470Y447062D03*
X1041444Y506504D03*
X1053690Y520760D03*
X1045720Y591672D03*
X1043260Y601272D03*
X1045760Y596272D03*
X1048260Y601272D03*
X1051680Y614772D03*
X1053745Y742341D03*
X1053354Y1286714D03*
Y1291714D03*
X1039510Y1296655D03*
X1049510D03*
X1044510D03*
X1039510Y1293155D03*
X1049510D03*
X1044510D03*
X1053354Y1296714D03*
X1041798Y1536262D03*
X1047798D03*
X1050498D03*
X1044798D03*
X1039298D03*
X1041798Y1551262D03*
X1039298D03*
X1041798Y1545262D03*
X1039298D03*
X1041798Y1548262D03*
X1039298D03*
X1047798Y1551262D03*
X1050498D03*
X1047798Y1545262D03*
X1050498D03*
X1047798Y1548262D03*
X1050498D03*
X1044798Y1551262D03*
Y1545262D03*
Y1548262D03*
X1039298Y1542262D03*
X1044798D03*
X1050498D03*
X1047798D03*
X1041798D03*
X1044798Y1539262D03*
X1050498D03*
X1047798D03*
X1039298D03*
X1041798D03*
X1054368Y1554364D03*
X1041798Y1554262D03*
X1039298D03*
X1047798D03*
X1050498D03*
X1044798D03*
X1053612Y1586010D03*
X1056898Y1604000D03*
X1067220Y145362D03*
Y142862D03*
Y148362D03*
X1059943Y435314D03*
X1062120Y477462D03*
X1056190Y520760D03*
X1058220Y585862D03*
X1061470D03*
X1056220Y605052D03*
X1055205Y744853D03*
X1063354Y1286714D03*
X1058354D03*
X1063354Y1291714D03*
X1058354D03*
X1063354Y1296714D03*
X1058290Y1296302D03*
X1071179Y1294669D03*
X1066462Y1520088D03*
X1065164Y1536262D03*
X1062464D03*
X1071164D03*
X1068164D03*
X1065164Y1551262D03*
X1062464D03*
X1065164Y1545262D03*
X1062464D03*
X1065164Y1548262D03*
X1062464D03*
X1071164Y1551262D03*
Y1545262D03*
Y1548262D03*
X1068164Y1551262D03*
Y1545262D03*
Y1548262D03*
Y1542262D03*
X1071164D03*
X1062464D03*
X1065164D03*
X1068164Y1539262D03*
X1071164D03*
X1062464D03*
X1065164D03*
Y1554262D03*
X1062464D03*
X1071164D03*
X1068164D03*
X1059368Y1554364D03*
X1059086Y1579240D03*
Y1573240D03*
Y1576240D03*
X1062612Y1586010D03*
X1065612D03*
X1056612D03*
X1059612D03*
X1059898Y1604000D03*
X1071920Y53862D03*
X1079114Y75775D03*
X1080168Y90721D03*
X1081282Y180937D03*
X1086756Y187540D03*
X1077973Y246362D03*
X1083973D03*
X1080973D03*
X1077883Y260842D03*
X1076823Y265438D03*
X1083823D03*
X1083883Y260842D03*
X1080883D03*
X1080323Y265438D03*
X1082853Y269492D03*
X1079853D03*
X1075400Y273762D03*
X1078400D03*
X1081400D03*
X1084400D03*
X1087400D03*
X1076018Y289400D03*
X1079018D03*
X1082018D03*
X1085018D03*
X1084130Y298342D03*
X1086630D03*
X1076353Y363966D03*
X1078853D03*
X1087330Y369061D03*
Y374131D03*
Y379251D03*
X1075462Y386723D03*
X1078151Y413911D03*
X1078120Y411262D03*
X1084245Y435437D03*
X1078545Y435637D03*
X1081045D03*
X1087280Y435437D03*
X1076598Y477087D03*
X1081930Y477132D03*
X1079320Y473892D03*
X1076820D03*
X1073589Y506461D03*
X1082220Y522362D03*
X1085720Y522422D03*
X1073250Y582332D03*
X1084637Y744635D03*
X1083714Y1285144D03*
Y1288144D03*
Y1291144D03*
X1077634Y1294869D03*
X1074387Y1294652D03*
X1074010Y1510650D03*
X1073864Y1536262D03*
X1085830D03*
X1073864Y1551262D03*
Y1545262D03*
Y1548262D03*
X1085830Y1551262D03*
Y1545262D03*
Y1548262D03*
Y1542262D03*
X1073864D03*
X1085830Y1539262D03*
X1073864D03*
X1077734Y1554364D03*
X1073864Y1554262D03*
X1085830D03*
X1082734Y1554364D03*
X1084000Y1647110D03*
X1094644Y67992D03*
X1090279Y126524D03*
X1105580Y132822D03*
X1100630Y130376D03*
X1099030Y245140D03*
X1088018Y289400D03*
X1089130Y298342D03*
X1091630D03*
X1094130D03*
X1089660Y408560D03*
X1095820Y420762D03*
X1090245Y435437D03*
X1093497Y744655D03*
X1089714Y1285144D03*
X1105480Y1517982D03*
X1088530Y1536262D03*
X1091530D03*
X1088530Y1551262D03*
Y1545262D03*
Y1548262D03*
X1094530Y1551262D03*
X1097230D03*
X1094530Y1545262D03*
X1097230D03*
X1094530Y1548262D03*
X1097230D03*
X1091530Y1551262D03*
Y1545262D03*
Y1548262D03*
Y1542262D03*
X1097230D03*
X1094530D03*
X1088530D03*
X1091530Y1539262D03*
X1094530D03*
X1088530D03*
X1101600Y1554364D03*
X1104750Y1549346D03*
X1088530Y1554262D03*
X1094530D03*
X1097230D03*
X1091530D03*
X1092302Y1585650D03*
X1089302D03*
X1098302D03*
X1095302D03*
X1095436Y1603944D03*
X1092436D03*
X1088790Y1641830D03*
X1094225Y1671710D03*
X1091880Y1673720D03*
X1110977Y55505D03*
X1110754Y60028D03*
X1113594Y69862D03*
X1109020Y80592D03*
X1118309Y111687D03*
X1115860Y113883D03*
X1118486Y208942D03*
X1111918Y234718D03*
X1109088Y234668D03*
X1111918Y237718D03*
Y240718D03*
X1109088Y237668D03*
Y240668D03*
X1120190Y255652D03*
X1117820Y456132D03*
X1113207Y744455D03*
X1115853Y1426342D03*
Y1435532D03*
X1114400Y1518237D03*
X1110725Y1518046D03*
X1113725Y1530935D03*
X1115802Y1615010D03*
X1117407Y1628495D03*
X1113990Y1631370D03*
X1113325Y1627975D03*
X1117182Y1625460D03*
X1106480Y1641275D03*
X1113110Y1666460D03*
X1108320Y1680200D03*
X1112130Y1711600D03*
X1112252Y1706170D03*
X1112200Y1709000D03*
X1114150Y1715726D03*
X1110663Y1719189D03*
X1119200Y1730300D03*
Y1727200D03*
X1114300Y1722700D03*
X1119300Y1724100D03*
X1132547Y64864D03*
X1129997Y69864D03*
X1122278Y107549D03*
X1120420Y109829D03*
X1124858Y197309D03*
X1128485Y198159D03*
X1133041Y194137D03*
X1124360Y259712D03*
X1125409Y305797D03*
X1122059Y305673D03*
X1124985Y302578D03*
X1127402Y456174D03*
X1136051Y503324D03*
X1124120Y643762D03*
X1136720Y641362D03*
X1133720Y642862D03*
X1129420Y644062D03*
X1122980Y741312D03*
X1127972Y747250D03*
X1135750Y1255672D03*
X1127179Y1372700D03*
X1124679D03*
Y1370200D03*
X1127179D03*
X1129729Y1372700D03*
Y1370200D03*
Y1375200D03*
X1127179D03*
X1124679D03*
X1129729Y1377700D03*
Y1380200D03*
Y1385200D03*
Y1382700D03*
X1127179D03*
X1124679D03*
X1127179Y1380200D03*
Y1377700D03*
X1124679D03*
Y1380200D03*
Y1385200D03*
X1127179D03*
X1122879Y1431474D03*
Y1434024D03*
X1125995Y1439780D03*
X1123379Y1443583D03*
X1133169Y1445690D03*
X1129169Y1442998D03*
X1135568Y1442923D03*
X1129169Y1445719D03*
X1130841Y1462953D03*
X1128341Y1465453D03*
Y1462953D03*
X1130841Y1465453D03*
X1133841Y1462953D03*
Y1465453D03*
X1128341Y1468453D03*
X1130841D03*
X1133841D03*
X1128341Y1460453D03*
X1130841D03*
X1133841D03*
Y1471453D03*
X1130841D03*
X1128341D03*
X1132187Y1582738D03*
X1135187D03*
X1132187Y1590738D03*
X1135187D03*
X1124862Y1615010D03*
X1140242Y101135D03*
X1152720Y180862D03*
X1148795Y213731D03*
X1141957Y227277D03*
X1144457D03*
X1139457D03*
X1146670Y230110D03*
X1147700Y362731D03*
X1137315Y379592D03*
X1147700Y368041D03*
X1138551Y503324D03*
X1144720Y501362D03*
Y498662D03*
X1142967Y592097D03*
X1138500Y586362D03*
X1142127Y586452D03*
X1140697Y608762D03*
X1150140Y610362D03*
X1144810Y613762D03*
X1142674Y1287608D03*
X1144247Y1372700D03*
Y1370200D03*
X1146797Y1372700D03*
X1149297D03*
X1146797Y1370200D03*
X1149297D03*
X1144247Y1375200D03*
X1146797D03*
X1149297D03*
X1144247Y1377700D03*
Y1380200D03*
Y1385200D03*
Y1382700D03*
X1146797D03*
X1149297D03*
X1146797Y1380200D03*
Y1377700D03*
X1149297Y1380200D03*
Y1377700D03*
Y1385200D03*
X1146797D03*
X1146563Y1436334D03*
X1141903D03*
X1144233Y1435584D03*
X1139573D03*
X1149469Y1437098D03*
X1151669Y1435698D03*
Y1438598D03*
X1137311Y1445191D03*
X1147203Y1441968D03*
X1149569Y1440098D03*
X1151669Y1441498D03*
X1147203Y1439068D03*
X1141591Y1462853D03*
Y1465353D03*
Y1468353D03*
Y1471353D03*
Y1460353D03*
X1150821Y1459607D03*
Y1456587D03*
X1138430Y1524150D03*
X1151497Y1524187D03*
X1153465Y1550301D03*
X1149528D03*
X1145410Y1540640D03*
X1143060Y1538380D03*
X1141654Y1550301D03*
X1137717Y1558020D03*
X1141690Y1552920D03*
X1152187Y1574738D03*
X1142187D03*
X1145187D03*
X1142187Y1582738D03*
X1145187D03*
X1152187D03*
X1141525Y1597630D03*
X1152187Y1590738D03*
X1142187D03*
X1145187D03*
X1140750Y1604330D03*
X1150380Y1602590D03*
X1146960Y1618960D03*
X1152257Y1628910D03*
X1155703Y73679D03*
X1165440Y176450D03*
X1168710Y176590D03*
X1159460Y194090D03*
X1160630Y213870D03*
X1159753Y361281D03*
X1159460Y366025D03*
X1156790Y363231D03*
X1161690Y374110D03*
X1164320Y451062D03*
X1156100Y456342D03*
X1167190Y526922D03*
X1158300Y585862D03*
X1170740Y602132D03*
X1155962Y746193D03*
X1156609Y1286685D03*
X1165279Y1372700D03*
X1162779D03*
X1167829D03*
X1162779Y1370200D03*
X1165279D03*
X1167829D03*
X1162779Y1375200D03*
X1165279D03*
X1167829D03*
Y1377700D03*
Y1380200D03*
Y1385200D03*
Y1382700D03*
X1165279D03*
X1162779D03*
X1165279Y1380200D03*
X1162779D03*
Y1377700D03*
X1165279D03*
X1162779Y1385200D03*
X1165279D03*
X1161022Y1431499D03*
Y1433999D03*
X1164138Y1439780D03*
X1154288Y1432502D03*
X1161522Y1443630D03*
X1167312Y1442998D03*
Y1445964D03*
X1159386Y1464253D03*
Y1466753D03*
X1156386Y1464253D03*
Y1466753D03*
X1159386Y1469253D03*
X1156386D03*
X1153821Y1459607D03*
Y1456587D03*
X1159386Y1461753D03*
X1159476Y1458918D03*
X1156386Y1461753D03*
X1156476Y1458918D03*
X1159446Y1456113D03*
X1156446D03*
X1167245Y1524187D03*
X1159371D03*
X1163308D03*
X1155433D03*
X1165276Y1550301D03*
X1169213D03*
X1157402D03*
X1161339D03*
X1161595Y1574738D03*
X1164595D03*
X1155187D03*
X1161595Y1582738D03*
X1164595D03*
X1155187D03*
X1163079Y1601479D03*
X1161595Y1590738D03*
X1164595D03*
X1155187D03*
X1169460Y1606630D03*
Y1616630D03*
Y1611630D03*
X1158030Y1619250D03*
X1164830Y1628830D03*
X1163970Y1620600D03*
X1169325Y1642600D03*
X1158325D03*
X1162383Y1652505D03*
X1164830Y1654632D03*
X1159930D03*
X1161076Y1680624D03*
X1157700Y1681100D03*
X1174120Y57111D03*
X1175926Y69151D03*
X1180676Y106858D03*
X1187413Y143132D03*
X1181420Y157962D03*
X1181700Y186962D03*
X1173314Y176452D03*
X1170595Y170056D03*
X1181476Y172247D03*
X1184510Y188962D03*
X1173100Y186962D03*
X1172925Y202174D03*
X1181369Y199234D03*
X1183460Y205342D03*
X1181470Y208802D03*
X1172835Y218174D03*
X1181500Y211962D03*
Y218462D03*
Y215962D03*
Y222162D03*
X1186653Y302242D03*
X1181450Y306052D03*
X1174120Y355362D03*
X1169690Y526922D03*
X1172310Y584562D03*
X1181300Y584762D03*
X1177570Y602052D03*
X1175217Y595762D03*
X1173020Y745972D03*
X1175573Y1286765D03*
X1172573D03*
X1182747Y1372700D03*
X1185297D03*
X1182747Y1370200D03*
X1185297D03*
X1182747Y1375200D03*
X1185297D03*
X1182747Y1380200D03*
Y1377700D03*
Y1385200D03*
Y1382700D03*
X1185297D03*
Y1377700D03*
Y1380200D03*
Y1385200D03*
X1184706Y1436334D03*
X1180046D03*
X1182376Y1435584D03*
X1177716D03*
X1171342Y1445650D03*
X1175454Y1445191D03*
X1173711Y1442923D03*
X1171182Y1524187D03*
X1184330Y1573260D03*
X1184290Y1570080D03*
X1171595Y1574738D03*
X1174595D03*
X1171595Y1582738D03*
X1174595D03*
X1183410Y1594450D03*
X1183440Y1591640D03*
X1171595Y1590738D03*
X1174595D03*
X1178140Y1601100D03*
X1184200Y1599900D03*
X1183320Y1597080D03*
X1169968Y1602370D03*
X1174550Y1615630D03*
X1178250Y1609100D03*
X1184200Y1602700D03*
X1185030Y1624660D03*
X1180325Y1642600D03*
X1173383Y1652505D03*
X1184383D03*
X1181930Y1654632D03*
X1175830D03*
X1170930D03*
X1183076Y1680624D03*
X1172076D03*
X1194478Y56986D03*
X1197520Y56962D03*
X1201158Y57130D03*
X1189393Y60183D03*
X1188700Y100700D03*
X1185400Y104000D03*
X1193532Y132644D03*
X1194800Y143112D03*
X1197414Y161592D03*
X1191020Y170862D03*
X1185420Y153762D03*
X1200720Y184862D03*
X1188300Y189062D03*
X1200720Y187862D03*
X1200963Y212648D03*
X1200830Y206002D03*
X1186340Y204492D03*
X1187300Y217862D03*
X1188500Y205772D03*
X1188600Y225962D03*
X1187013Y238972D03*
X1194840Y236592D03*
X1199720Y252362D03*
X1196720D03*
X1188810Y296088D03*
X1186280Y298972D03*
X1193198Y586172D03*
X1195698D03*
X1198198D03*
X1200698D03*
X1185687Y744475D03*
X1187797Y1372700D03*
Y1370200D03*
Y1375200D03*
Y1382700D03*
Y1377700D03*
Y1380200D03*
Y1385200D03*
X1187412Y1437498D03*
X1189612Y1436098D03*
X1191918Y1432516D03*
X1185346Y1442128D03*
X1187512Y1440498D03*
X1189612Y1441898D03*
X1185346Y1439228D03*
X1189612Y1438998D03*
X1187720Y1517688D03*
X1187830Y1522188D03*
X1198546Y1520188D03*
X1187830Y1526688D03*
X1198546Y1524688D03*
X1187720Y1536362D03*
X1198485Y1534313D03*
X1198436Y1529362D03*
X1187720Y1531862D03*
Y1553692D03*
X1198497Y1539667D03*
X1187720Y1548772D03*
X1198436Y1546492D03*
X1187720Y1544292D03*
X1198436Y1551192D03*
Y1556192D03*
Y1561062D03*
X1187720Y1558682D03*
Y1563182D03*
X1194510Y1563076D03*
X1187600Y1622064D03*
X1201600Y1633790D03*
X1199400Y1627800D03*
X1190895Y1642910D03*
X1186000Y1640000D03*
X1197400Y1654942D03*
X1192500D03*
X1186830Y1654632D03*
X1193646Y1680934D03*
X1201106Y1677873D03*
X1190735Y1688390D03*
X1194793Y1698295D03*
X1201505Y1688435D03*
X1192340Y1700422D03*
X1197240D03*
X1193174Y1726414D03*
X1216176Y56742D03*
X1202860Y120392D03*
X1215763Y114363D03*
X1215800Y111300D03*
X1201700Y110000D03*
X1202920Y117162D03*
X1210910Y129502D03*
X1206114Y132962D03*
X1206434Y129492D03*
X1206694Y139512D03*
X1214415Y153962D03*
X1206664Y158952D03*
X1214091Y164962D03*
X1214534Y157462D03*
X1214054Y186092D03*
X1214693Y174962D03*
X1214134Y180972D03*
X1213720Y200309D03*
Y189362D03*
X1204220D03*
X1213720Y195362D03*
X1215720Y204862D03*
X1203200Y202514D03*
X1219060Y213312D03*
X1206660Y224742D03*
X1213540Y224792D03*
X1207220Y243998D03*
X1210900Y265300D03*
X1204475Y350684D03*
X1205165Y380962D03*
X1218870Y418082D03*
X1214000Y599262D03*
X1208980Y598462D03*
X1207100Y600882D03*
X1211277Y744265D03*
X1206757Y744455D03*
X1210288Y754081D03*
X1202300Y753962D03*
X1207607Y754095D03*
X1215896Y756942D03*
X1206432Y758995D03*
X1202307Y757082D03*
X1205820Y1652910D03*
X1210830Y1676500D03*
X1217210Y1684520D03*
X1212305Y1688700D03*
X1216363Y1698605D03*
X1205563Y1698340D03*
X1207180Y1685680D03*
X1208010Y1700467D03*
X1213910Y1700732D03*
X1203110Y1700467D03*
X1203939Y1726459D03*
X1214834Y1726724D03*
X1228425Y91500D03*
X1222100Y91600D03*
X1225100Y91500D03*
X1225700Y108962D03*
X1232182Y110659D03*
X1224614Y116962D03*
X1219534Y116492D03*
X1223500Y111162D03*
X1226400Y125200D03*
X1226093Y134262D03*
X1229500Y125100D03*
X1223100Y130700D03*
X1234093Y144962D03*
X1226093Y140962D03*
X1222593D03*
X1222920Y144909D03*
Y148909D03*
X1222593Y168962D03*
X1222890Y157002D03*
X1226093Y156962D03*
X1222594Y154242D03*
X1226093Y168162D03*
X1225874Y163462D03*
X1222720Y163362D03*
X1226093Y177962D03*
X1222724Y176102D03*
X1226093Y172962D03*
X1223134Y190802D03*
X1225574Y188662D03*
X1228520Y202162D03*
X1229720Y197302D03*
X1226093Y193462D03*
X1225320Y200162D03*
X1233282Y201875D03*
X1223180Y210552D03*
X1233780Y214572D03*
X1231720Y217862D03*
Y209862D03*
X1219220Y243862D03*
Y247148D03*
X1230720Y380362D03*
X1221220D03*
X1232720Y377862D03*
X1224300Y380400D03*
X1223650Y520672D03*
X1230650D03*
X1227150D03*
X1219060Y757272D03*
X1223327Y757615D03*
X1228320Y758598D03*
X1218810Y1700732D03*
X1236620Y58862D03*
X1241010Y110782D03*
X1250010Y117121D03*
X1244200Y112862D03*
X1249362Y111600D03*
X1241035Y114399D03*
X1234746Y136040D03*
X1240728Y136198D03*
X1240904Y151592D03*
X1238604Y150062D03*
X1241100Y145842D03*
X1244120Y167462D03*
X1246272Y164889D03*
X1243100Y160181D03*
X1243184Y182422D03*
X1239874Y182322D03*
X1236410Y201462D03*
X1236220Y189362D03*
X1236593Y197462D03*
X1236584Y205762D03*
X1245486Y203000D03*
X1245593Y211762D03*
X1236620Y221562D03*
X1244720Y230362D03*
X1245514Y224302D03*
X1245593Y219662D03*
X1239045Y224062D03*
X1246878Y248615D03*
X1240500Y248332D03*
Y244332D03*
X1236720Y257362D03*
X1243589Y379595D03*
X1236720Y377862D03*
X1234720Y380362D03*
X1248150Y520672D03*
X1244650D03*
X1241150D03*
X1237650D03*
X1234150D03*
X1242260Y757602D03*
X1261227Y52061D03*
X1258727D03*
X1263454Y83060D03*
X1266464Y83090D03*
X1264098Y88787D03*
X1262320Y96012D03*
X1258539Y100900D03*
X1252520Y92022D03*
X1258539Y109263D03*
X1260641Y114399D03*
X1264220Y110462D03*
X1250424Y108943D03*
X1257581Y114579D03*
X1256093Y149462D03*
X1264663Y158946D03*
X1254994Y157382D03*
X1265010Y162222D03*
X1261899Y174648D03*
X1253624Y201362D03*
X1267315Y220701D03*
X1264874Y217462D03*
X1256504D03*
X1255613Y209568D03*
X1265207Y208442D03*
X1259703Y209808D03*
X1253440Y230552D03*
X1253860Y235622D03*
X1256070Y229512D03*
X1264584Y226592D03*
X1256593Y221462D03*
Y233972D03*
Y225972D03*
X1253950Y246692D03*
X1266715Y244692D03*
X1254370Y241302D03*
X1265065Y249982D03*
X1256494Y243177D03*
X1256574Y238662D03*
X1266518Y237042D03*
X1256584Y248002D03*
X1256454Y252122D03*
X1264854Y253996D03*
Y256496D03*
X1258883Y280558D03*
X1258250Y292986D03*
X1263150Y294726D03*
X1255150Y306211D03*
X1256220Y434362D03*
X1261220Y454362D03*
X1253220Y451362D03*
X1267220D03*
X1260220Y477362D03*
X1255920Y511362D03*
X1251650Y520672D03*
X1255150D03*
X1258667Y751405D03*
X1255520Y747362D03*
X1263486Y739949D03*
X1257672Y1351008D03*
X1276820Y58142D03*
X1282360Y58132D03*
X1279580D03*
X1279390Y87697D03*
X1275820Y87962D03*
X1270329Y101011D03*
X1266722Y101005D03*
X1278456Y96187D03*
X1279415Y90847D03*
X1281704Y95402D03*
X1282824Y108872D03*
X1271284Y108971D03*
X1282764Y135398D03*
X1277820Y140682D03*
X1281093Y144516D03*
X1271954Y159143D03*
X1271593Y165962D03*
X1278093Y184462D03*
X1278993Y193262D03*
X1273093Y200038D03*
X1278183Y201262D03*
X1275493Y193962D03*
X1267289Y192167D03*
X1269904Y192692D03*
X1272893Y191262D03*
X1271315Y220701D03*
X1267773Y208373D03*
X1273093Y213962D03*
X1275727Y209597D03*
X1267618Y225382D03*
X1277661Y225685D03*
X1267593Y229462D03*
X1278783Y221386D03*
X1282176Y221436D03*
X1282654Y226309D03*
X1278320Y239292D03*
X1279493Y248662D03*
X1282645Y255671D03*
Y252271D03*
X1277771Y255173D03*
X1273754Y256504D03*
X1276800Y276562D03*
X1269960Y294536D03*
X1271150Y305792D03*
X1272530Y429362D03*
X1284220D03*
X1280270Y434362D03*
X1272220D03*
X1278380Y463362D03*
X1276220Y477362D03*
X1283220D03*
X1269220D03*
X1274420Y463362D03*
X1275576Y730879D03*
X1266727Y752955D03*
X1279788Y1304042D03*
X1279812Y1353552D03*
X1279334Y1356089D03*
X1275856Y1358098D03*
X1271990Y1358079D03*
X1276891Y1362891D03*
X1282928Y1361833D03*
X1269012Y1371693D03*
Y1368293D03*
X1290291Y-29811D03*
Y-33211D03*
X1285201Y58121D03*
X1293454Y81232D03*
X1289210D03*
X1298640Y93062D03*
X1292880Y93162D03*
X1292899Y98519D03*
X1294354Y103166D03*
X1291704Y109427D03*
X1288093Y125962D03*
X1291478Y137745D03*
X1286150Y131092D03*
X1297605Y145824D03*
X1285710Y249182D03*
X1290293Y247562D03*
X1288637Y240448D03*
X1292630Y240462D03*
X1291071Y275543D03*
Y278543D03*
X1290005Y293768D03*
Y290268D03*
X1294500Y299692D03*
X1291100D03*
X1291500Y312862D03*
Y315362D03*
X1291420Y320662D03*
Y318162D03*
X1295540Y440902D03*
X1301310Y440862D03*
X1291220Y463362D03*
X1294440Y477267D03*
X1296630Y463462D03*
X1300220Y477362D03*
X1284220Y463362D03*
X1289936Y732539D03*
X1290520Y746562D03*
X1292572Y785575D03*
X1297298Y790982D03*
X1296719Y1290197D03*
X1299169Y1295467D03*
Y1297967D03*
X1296569D03*
Y1295467D03*
Y1292967D03*
X1299169D03*
X1296581Y1300474D03*
X1299181D03*
X1296576Y1303298D03*
X1299176D03*
X1290102Y1365789D03*
X1286102Y1365051D03*
X1294312Y1367279D03*
X1292840Y1364821D03*
X1286102Y1368107D03*
X1298836Y1358387D03*
X1296506Y1357637D03*
X1301820Y58672D03*
X1311424Y68652D03*
X1308174D03*
X1311960Y58152D03*
X1311260Y83032D03*
X1310857Y78542D03*
X1307120Y78562D03*
X1310906Y97807D03*
X1314406Y97756D03*
X1308274Y104162D03*
X1314059Y93877D03*
X1307244Y118452D03*
X1306836Y108242D03*
X1302080Y117032D03*
X1302060Y113852D03*
X1300990Y121812D03*
X1315156Y130656D03*
X1314920Y135361D03*
X1313117Y250605D03*
X1314685Y248651D03*
X1307431Y256099D03*
X1309283Y254162D03*
X1311275Y252297D03*
X1305552Y257974D03*
X1308736Y284948D03*
X1312136D03*
X1307042Y292636D03*
X1303642D03*
X1307442Y306998D03*
X1304042D03*
X1307677Y322996D03*
X1311077D03*
X1317100Y553900D03*
X1308600Y653500D03*
X1303576Y659671D03*
X1311420Y738262D03*
X1305187Y735630D03*
X1315020Y739862D03*
X1307469Y787772D03*
X1301034Y784165D03*
X1304260Y788265D03*
X1309930Y789852D03*
X1306701Y794779D03*
X1305117Y797125D03*
X1309210Y792802D03*
X1315169Y1274887D03*
X1315289Y1269717D03*
X1315229Y1272287D03*
X1304149Y1291317D03*
X1301889Y1284987D03*
X1301829Y1290167D03*
X1301859Y1287587D03*
X1304299Y1280967D03*
X1304269Y1283567D03*
X1304239Y1286147D03*
X1304209Y1288747D03*
X1315176Y1280218D03*
X1315181Y1277594D03*
X1299319Y1290197D03*
X1299349Y1287617D03*
X1301686Y1303268D03*
X1304196Y1299248D03*
X1304189Y1293917D03*
X1304201Y1296624D03*
X1301679Y1292937D03*
Y1295437D03*
Y1297937D03*
X1301691Y1300444D03*
X1311820Y1330518D03*
Y1333018D03*
X1314936Y1338799D03*
X1312650Y1342572D03*
X1308616Y1363345D03*
Y1360445D03*
X1306082Y1359315D03*
X1306182Y1362315D03*
X1304016Y1363945D03*
Y1361045D03*
X1308616Y1357945D03*
X1303496Y1358387D03*
X1301166Y1357637D03*
X1316459Y58697D03*
X1322248Y68487D03*
X1321279Y58767D03*
X1317831Y68652D03*
X1322415Y75480D03*
X1322906Y94212D03*
X1319968Y98266D03*
X1329891Y99455D03*
X1329646Y104954D03*
X1322906Y109733D03*
X1323912Y245111D03*
X1320387Y258901D03*
X1325769Y259001D03*
X1325414Y293556D03*
X1328814D03*
X1319903Y299176D03*
X1323303D03*
X1319618Y318073D03*
X1325080Y323902D03*
X1316218Y318073D03*
X1328480Y323902D03*
X1330101Y540049D03*
X1328530Y747702D03*
X1325210Y744322D03*
X1331519Y1262027D03*
X1331459Y1264597D03*
X1331399Y1267197D03*
X1317889Y1267147D03*
X1320399Y1267117D03*
X1317883Y1269978D03*
X1317895Y1272485D03*
X1320393Y1269948D03*
X1320405Y1272455D03*
X1331177Y1269933D03*
Y1272433D03*
X1317895Y1274985D03*
X1320405Y1274955D03*
X1331177Y1274933D03*
X1331166Y1280248D03*
X1317746D03*
X1320256Y1280218D03*
X1317895Y1277485D03*
X1320405Y1277455D03*
X1331189Y1277440D03*
X1328514Y1334603D03*
X1330844Y1335353D03*
X1322110Y1342755D03*
X1318110Y1342017D03*
X1326320Y1344245D03*
X1324848Y1341787D03*
X1318110Y1345073D03*
X1331288Y1372440D03*
X1327491Y1372358D03*
X1324491Y1372658D03*
X1327491Y1375858D03*
X1331288Y1375940D03*
X1324491Y1375858D03*
X1327491Y1381478D03*
Y1378478D03*
X1331288Y1378560D03*
X1324491Y1381478D03*
Y1378478D03*
X1331304Y1401986D03*
Y1404986D03*
X1327926D03*
X1322228Y1419890D03*
X1322186Y1411326D03*
Y1414326D03*
Y1417326D03*
X1322270Y1422454D03*
X1325084Y1420066D03*
X1325042Y1408502D03*
Y1411502D03*
Y1417502D03*
Y1414502D03*
X1331344Y1414456D03*
X1330804Y1411536D03*
Y1408536D03*
X1331386Y1420020D03*
X1328008D03*
X1331344Y1417456D03*
X1327966Y1408456D03*
Y1411456D03*
Y1417456D03*
Y1414456D03*
X1331428Y1422584D03*
X1328050D03*
X1322312Y1425018D03*
X1325126Y1422630D03*
X1325168Y1425194D03*
X1328092Y1425148D03*
X1331470D03*
X1341752Y-29811D03*
Y-33211D03*
X1333190Y58825D03*
X1347640Y101950D03*
X1345583Y91307D03*
X1336549Y105970D03*
X1344631Y127244D03*
X1332497Y133931D03*
X1343034Y141698D03*
X1336761Y293404D03*
X1340161D03*
X1335145Y332616D03*
X1341431Y322693D03*
X1331745Y332616D03*
X1338031Y322693D03*
X1345424Y328981D03*
X1344720Y423162D03*
X1337220D03*
X1342220D03*
X1339720D03*
X1333143Y540049D03*
X1340420Y538422D03*
Y541822D03*
X1347419Y1259257D03*
X1347379Y1256687D03*
X1336269Y1274957D03*
X1333969Y1264567D03*
X1334029Y1261997D03*
X1333909Y1267167D03*
X1336339Y1269777D03*
X1336279Y1272347D03*
X1347359Y1261857D03*
X1347371Y1264564D03*
X1336519Y1264627D03*
X1336579Y1262057D03*
X1347366Y1267188D03*
X1336459Y1267227D03*
X1333687Y1269903D03*
Y1272403D03*
Y1274903D03*
X1333676Y1280218D03*
X1336261Y1277654D03*
X1333699Y1277410D03*
X1343948Y1317092D03*
Y1319592D03*
X1344532Y1328161D03*
X1347397Y1325320D03*
X1336144Y1341147D03*
X1338288Y1339653D03*
X1340488Y1340853D03*
X1336144Y1338247D03*
X1340214Y1334853D03*
X1340410Y1338017D03*
X1338288Y1336553D03*
X1333174Y1334603D03*
X1335504Y1335353D03*
X1334288Y1372440D03*
X1340288D03*
X1346193Y1372523D03*
X1343193D03*
X1337288Y1372440D03*
Y1375940D03*
X1334288D03*
X1343193Y1376023D03*
X1346193D03*
X1340288Y1375940D03*
X1346304Y1401986D03*
X1343304D03*
X1340304D03*
X1337304D03*
X1334304D03*
Y1404986D03*
X1346304D03*
X1343304D03*
X1340304D03*
X1337304D03*
X1337344Y1414456D03*
X1346344D03*
X1343344D03*
X1340344D03*
X1346534Y1411496D03*
Y1408496D03*
X1334344Y1414456D03*
X1346344Y1417456D03*
X1340344D03*
X1337344D03*
X1334386Y1420020D03*
X1334344Y1417456D03*
X1346386Y1420020D03*
X1343386D03*
X1340386D03*
X1337386D03*
X1343344Y1417456D03*
X1337428Y1422584D03*
X1340428D03*
X1343428D03*
X1334428D03*
X1337328Y1425164D03*
X1340328D03*
X1343328D03*
X1346178Y1425254D03*
X1346278Y1422674D03*
X1334470Y1425148D03*
X1348610Y84712D03*
X1349480Y77072D03*
X1366369Y83820D03*
X1349570Y104147D03*
X1353394Y131812D03*
X1348620Y136162D03*
X1349220Y140362D03*
X1348824Y328981D03*
X1358371Y332275D03*
X1361771D03*
X1355200Y337843D03*
X1351800D03*
X1356220Y581862D03*
X1356047Y680000D03*
X1358907Y681262D03*
X1361727Y680665D03*
X1352474Y1256866D03*
X1349964Y1256896D03*
X1352486Y1259373D03*
X1349976Y1259403D03*
X1363258Y1256851D03*
Y1259351D03*
X1349876Y1267158D03*
X1352426Y1267218D03*
X1363266Y1267188D03*
X1349976Y1261903D03*
X1352486Y1261873D03*
Y1264373D03*
X1349976Y1264403D03*
X1363258Y1261851D03*
X1363270Y1264358D03*
X1360593Y1321872D03*
X1363098Y1320951D03*
X1354238Y1329329D03*
X1350238Y1328591D03*
X1358448Y1330819D03*
X1356976Y1328361D03*
X1350238Y1331647D03*
X1352666Y1378560D03*
X1349666D03*
X1352666Y1381560D03*
X1349666D03*
X1352666Y1375940D03*
X1349666D03*
X1352126Y1401986D03*
X1349426D03*
X1352126Y1404986D03*
X1349426D03*
X1349508Y1420020D03*
X1352166Y1420456D03*
Y1414456D03*
Y1411456D03*
Y1408456D03*
Y1417456D03*
X1349466Y1411456D03*
Y1408456D03*
Y1417456D03*
Y1414456D03*
X1349278Y1422674D03*
X1364860Y1455172D03*
X1362410Y1445272D03*
X1378839Y87626D03*
X1366369Y92450D03*
X1366714Y109506D03*
X1376991Y176430D03*
X1373591D03*
X1375619Y236261D03*
X1375257Y229756D03*
X1373493Y227762D03*
X1370207Y682245D03*
X1374938Y1161569D03*
Y1170069D03*
X1379579Y1259317D03*
X1368379Y1259287D03*
X1379639Y1256747D03*
X1368439Y1256717D03*
X1365768Y1256821D03*
Y1259321D03*
X1365776Y1267158D03*
X1368326Y1267218D03*
X1379519Y1261917D03*
X1379531Y1264624D03*
X1379526Y1267248D03*
X1368361Y1264594D03*
X1368369Y1261897D03*
X1365768Y1261821D03*
X1365780Y1264328D03*
X1376076Y1317092D03*
Y1319592D03*
X1379192Y1325373D03*
X1368272Y1324821D03*
X1372538Y1324591D03*
X1370338Y1323091D03*
X1372538Y1321691D03*
X1365376Y1321938D03*
X1367635Y1320904D03*
X1377214Y1327653D03*
X1368272Y1327721D03*
X1370438Y1326091D03*
X1372538Y1327491D03*
X1377054Y1394028D03*
X1367316Y1399053D03*
Y1403458D03*
X1370577Y1421899D03*
X1367436Y1414778D03*
X1370891Y1410306D03*
X1378417Y1415292D03*
X1367316Y1407458D03*
X1367889Y1419235D03*
X1377075Y1425014D03*
X1365235Y1428637D03*
X1370250Y1433715D03*
X1367620Y1431472D03*
X1367170Y1453142D03*
X1368842Y1449261D03*
X1364800Y1449231D03*
X1368980Y1457122D03*
X1370041Y1460374D03*
X1393250Y93802D03*
X1386684Y145017D03*
X1386404Y149008D03*
X1394182Y171470D03*
X1398182D03*
X1395960Y226422D03*
X1393460D03*
X1386868Y222937D03*
X1384017Y223697D03*
X1386138Y225411D03*
X1384895Y221346D03*
X1381951Y221420D03*
X1381235Y236020D03*
X1390600Y248262D03*
X1392685Y498992D03*
X1387550Y502922D03*
X1387600Y499182D03*
X1391260Y507082D03*
X1396081Y1161569D03*
Y1153369D03*
Y1170069D03*
X1384652Y1256866D03*
X1382142Y1256896D03*
X1384664Y1259373D03*
X1382154Y1259403D03*
X1395436Y1256851D03*
Y1259351D03*
X1384586Y1267278D03*
X1395426Y1267188D03*
X1382036Y1267218D03*
X1382154Y1261903D03*
X1384664Y1261873D03*
Y1264373D03*
X1382154Y1264403D03*
X1395436Y1261851D03*
X1395448Y1264358D03*
X1392770Y1321177D03*
X1395100Y1321927D03*
X1386366Y1329329D03*
X1382366Y1328591D03*
X1390576Y1330819D03*
X1389104Y1328361D03*
X1382366Y1331647D03*
X1396311Y1385712D03*
X1398680Y1380582D03*
X1390474Y1385142D03*
X1387074Y1384272D03*
X1390513Y1395452D03*
X1387066Y1401734D03*
X1387291Y1408163D03*
X1387470Y1418302D03*
X1385109Y1410427D03*
X1390170Y1423942D03*
X1387068Y1413991D03*
X1381066Y1425008D03*
X1393630Y1426562D03*
X1388557Y1431645D03*
X1395907Y1430227D03*
X1395443Y1434700D03*
X1398569Y1437860D03*
X1383429Y1427652D03*
X1392620Y1446708D03*
X1389220D03*
X1382600Y1563480D03*
X1391655Y1570037D03*
X1391055Y1565037D03*
X1384840Y1565640D03*
X1386790Y1563610D03*
X1396600Y1590200D03*
Y1586400D03*
X1393000Y1590300D03*
X1395325Y1606862D03*
X1386200Y1645700D03*
X1386600Y1641400D03*
X1407029Y152732D03*
X1410370Y138742D03*
X1406970D03*
X1407029Y156132D03*
X1401341Y177159D03*
X1404829Y184263D03*
X1404741Y177159D03*
X1408229Y184263D03*
X1407178Y171684D03*
X1403778D03*
X1413900Y225212D03*
X1396900Y228932D03*
X1398831Y1161569D03*
Y1153369D03*
Y1170069D03*
X1411909Y1259257D03*
X1400599Y1256717D03*
X1411969Y1256687D03*
X1397946Y1256821D03*
Y1259321D03*
X1400539Y1259287D03*
X1400521Y1264594D03*
X1400529Y1261897D03*
X1397936Y1267158D03*
X1400486Y1267218D03*
X1411849Y1261857D03*
X1411861Y1264564D03*
X1411856Y1267188D03*
X1397946Y1261821D03*
X1397958Y1264328D03*
X1408204Y1317092D03*
Y1319592D03*
X1411320Y1325373D03*
X1400400Y1324821D03*
X1404666Y1324591D03*
X1402466Y1323091D03*
X1404666Y1321691D03*
X1397430Y1321177D03*
X1399760Y1321927D03*
X1408969Y1327645D03*
X1402566Y1326091D03*
X1400400Y1327721D03*
X1404666Y1327491D03*
X1401655Y1384676D03*
X1406461Y1383862D03*
X1415171Y1383692D03*
X1412961Y1387387D03*
X1412608Y1391687D03*
X1414362Y1402191D03*
X1414786Y1426890D03*
X1413440Y1436774D03*
X1409680Y1430613D03*
X1401371Y1434592D03*
X1410477Y1440117D03*
X1410038Y1434670D03*
X1403687Y1444711D03*
X1400287D03*
X1400220Y1518862D03*
X1409248Y1528862D03*
X1400160Y1543342D03*
X1404433Y1565037D03*
X1400695Y1570037D03*
X1400715Y1565037D03*
X1407440Y1557552D03*
X1404433Y1570037D03*
X1402536Y1576097D03*
X1402680Y1597700D03*
X1401300Y1619917D03*
X1410900Y1624800D03*
X1400000Y1626362D03*
Y1634362D03*
Y1638362D03*
X1410500Y1638862D03*
X1396900Y1642100D03*
X1413950Y184263D03*
X1423110D03*
X1417350D03*
X1426510D03*
X1428336Y232762D03*
X1415340Y231812D03*
X1418630Y220018D03*
X1422030D03*
X1413847Y239528D03*
X1426020Y261501D03*
X1431430Y256383D03*
Y264060D03*
X1426647Y329050D03*
X1417022Y621419D03*
X1424119Y1161520D03*
X1426619D03*
X1424119Y1153369D03*
X1426619D03*
Y1169570D03*
X1424119D03*
X1416999Y1256866D03*
X1414489Y1256896D03*
X1417011Y1259373D03*
X1414501Y1259403D03*
X1427783Y1256851D03*
Y1259351D03*
X1414366Y1267158D03*
X1416916Y1267218D03*
X1427786Y1267158D03*
X1414501Y1261903D03*
X1417011Y1261873D03*
Y1264373D03*
X1414501Y1264403D03*
X1427783Y1261851D03*
X1427795Y1264358D03*
X1424898Y1321177D03*
X1427228Y1321927D03*
X1418494Y1329329D03*
X1414494Y1328591D03*
X1422704Y1330819D03*
X1421232Y1328361D03*
X1414494Y1331647D03*
X1418990Y1387452D03*
X1422594Y1383301D03*
X1419995Y1397492D03*
X1415620Y1396652D03*
X1419055Y1392497D03*
X1426872Y1405811D03*
X1423256Y1403728D03*
X1424255Y1396612D03*
X1421480Y1415731D03*
X1422371Y1407722D03*
X1421371Y1411719D03*
X1421864Y1419730D03*
X1419991Y1423404D03*
X1424930Y1433850D03*
X1416272Y1433949D03*
X1421435Y1430415D03*
X1419746Y1435932D03*
X1414350Y1516435D03*
X1426020Y1521535D03*
X1414590Y1532255D03*
X1414350Y1521335D03*
X1427120Y1537355D03*
X1414590Y1537155D03*
X1414740Y1543475D03*
Y1548375D03*
X1427320Y1548575D03*
X1425620Y1556662D03*
X1416060Y1574922D03*
X1422680Y1582100D03*
X1419450Y1596150D03*
X1423700Y1600400D03*
X1434600Y59262D03*
X1444275Y57262D03*
X1432220Y61862D03*
X1440800Y66862D03*
X1447340Y157402D03*
X1442434Y210757D03*
X1430120Y225182D03*
X1431636Y230448D03*
X1444570Y238372D03*
X1431933Y238125D03*
X1431431Y267378D03*
X1436120Y315772D03*
X1436270Y312592D03*
X1436335Y309407D03*
X1436320Y305862D03*
Y303362D03*
X1436050Y321352D03*
X1436120Y318272D03*
X1436232Y344176D03*
X1433418Y729104D03*
X1444099Y1259397D03*
X1432899Y1259257D03*
X1444159Y1256827D03*
X1432959Y1256687D03*
X1430293Y1256821D03*
Y1259321D03*
X1444051Y1264704D03*
X1444039Y1261997D03*
X1444046Y1267328D03*
X1432889Y1261867D03*
X1432881Y1264564D03*
X1432846Y1267188D03*
X1430296Y1267128D03*
X1430293Y1261821D03*
X1430305Y1264328D03*
X1440332Y1317092D03*
Y1319592D03*
X1443448Y1325373D03*
X1432528Y1324821D03*
X1436794Y1324591D03*
X1434594Y1323091D03*
X1436794Y1321691D03*
X1429558Y1321177D03*
X1431888Y1321927D03*
X1441332Y1327793D03*
X1434694Y1326091D03*
X1432528Y1327721D03*
X1436794Y1327491D03*
X1437443Y1406289D03*
X1444997Y1392885D03*
X1435462Y1393009D03*
Y1396409D03*
X1434312Y1415197D03*
X1443112Y1417929D03*
X1445020Y1412672D03*
X1443676Y1432624D03*
X1433750Y1429208D03*
X1439742Y1436924D03*
X1434720Y1454862D03*
X1440440Y1454892D03*
X1444468Y1570610D03*
X1433720Y1569762D03*
X1440105Y1593352D03*
X1446700Y1598400D03*
X1438300Y1606800D03*
Y1602600D03*
X1430250Y1612812D03*
X1441800Y1628700D03*
Y1624500D03*
X1438547Y1638212D03*
X1443617D03*
X1431575Y1634842D03*
X1442573Y1649862D03*
X1442587Y1659242D03*
X1438320Y1668292D03*
X1438220Y1673955D03*
X1446715Y1679957D03*
X1446000Y67802D03*
X1458720Y145362D03*
X1450270Y143022D03*
X1450720Y153362D03*
X1448820Y148092D03*
X1450720Y169862D03*
Y161862D03*
X1449740Y166912D03*
X1450720Y181862D03*
Y177862D03*
Y173862D03*
X1462561Y205982D03*
X1457361D03*
X1459961Y210432D03*
X1456150Y214382D03*
X1449110Y233742D03*
X1455600Y297200D03*
X1456770Y342942D03*
X1460849Y343327D03*
X1462790Y359042D03*
X1462870Y355012D03*
X1449777Y362021D03*
X1459900Y370823D03*
X1455920Y373941D03*
X1463600Y374462D03*
X1449777Y371039D03*
X1455642Y409646D03*
X1449296Y407347D03*
X1449600Y402322D03*
X1456777Y418596D03*
Y426546D03*
X1456237Y726945D03*
X1457620Y736195D03*
X1460187Y729805D03*
X1455692Y731401D03*
X1457714Y741622D03*
X1447149Y1161569D03*
X1449649D03*
X1447299Y1153369D03*
X1449799D03*
X1447149Y1170069D03*
X1449649D03*
X1449176Y1256866D03*
X1446666Y1256896D03*
X1449188Y1259373D03*
X1446678Y1259403D03*
X1459960Y1259351D03*
Y1256851D03*
X1449106Y1267358D03*
X1459886Y1267218D03*
X1446556Y1267298D03*
X1446678Y1261903D03*
X1449188Y1261873D03*
Y1264373D03*
X1446678Y1264403D03*
X1459960Y1261851D03*
X1459972Y1264358D03*
X1457026Y1321177D03*
X1461686D03*
X1459356Y1321927D03*
X1450622Y1329329D03*
X1446622Y1328591D03*
X1454832Y1330819D03*
X1453360Y1328361D03*
X1446622Y1331647D03*
X1459968Y1402765D03*
X1451176Y1399026D03*
X1451198Y1403047D03*
X1460224Y1407545D03*
X1458138Y1409955D03*
X1461062Y1413246D03*
X1455006Y1447938D03*
X1459111Y1445669D03*
Y1448669D03*
X1457577Y1526689D03*
X1457817Y1542509D03*
X1457967Y1553729D03*
X1458200Y1565037D03*
Y1560037D03*
X1448620Y1556162D03*
X1456030Y1590302D03*
X1456120Y1586262D03*
X1453600Y1595662D03*
X1451500Y1612800D03*
X1454167Y1638302D03*
X1459127D03*
X1448507Y1638212D03*
X1448920Y1675062D03*
X1474142Y61767D03*
X1462000Y153362D03*
X1470220Y169862D03*
X1473090Y204502D03*
X1472335Y209362D03*
X1467761Y205982D03*
X1471308Y230640D03*
X1463833Y230448D03*
X1474660Y252878D03*
X1463808Y244948D03*
X1463833Y235566D03*
X1473820Y265962D03*
X1471510Y252878D03*
X1471690Y259862D03*
X1463950Y258172D03*
X1463330Y264060D03*
X1463510Y273878D03*
X1475452Y289708D03*
X1475352Y306308D03*
X1476826Y312177D03*
X1467700Y370953D03*
X1472758Y370817D03*
X1465836Y408668D03*
X1470942Y409718D03*
X1475250Y401812D03*
X1469777Y418396D03*
X1469951Y429251D03*
X1469720Y434542D03*
X1469760Y452622D03*
X1471460Y633402D03*
X1468060D03*
X1465171Y647132D03*
X1469020Y647102D03*
X1470841Y721493D03*
X1464999Y1259317D03*
X1476369Y1259237D03*
X1465059Y1256747D03*
X1462470Y1259321D03*
Y1256821D03*
X1476291Y1275224D03*
X1464946Y1267248D03*
X1464989Y1261927D03*
X1464981Y1264624D03*
X1476339Y1264467D03*
Y1267037D03*
X1476309Y1261807D03*
X1476279Y1269637D03*
X1476291Y1272344D03*
X1462396Y1267188D03*
X1462470Y1261821D03*
X1462482Y1264328D03*
X1476291Y1278104D03*
X1464016Y1321927D03*
X1466819Y1324018D03*
X1469019Y1322618D03*
X1473956Y1341068D03*
X1472460Y1330493D03*
Y1333043D03*
X1475576Y1338799D03*
X1469019Y1325518D03*
X1464680Y1325772D03*
X1469019Y1328418D03*
X1466919Y1327018D03*
X1464680Y1328672D03*
X1467567Y1445669D03*
Y1448669D03*
X1475967Y1445669D03*
Y1448669D03*
X1478320Y1522962D03*
X1472565Y1623635D03*
X1478061Y1633864D03*
X1463767Y1638302D03*
X1476570Y1661124D03*
X1482650Y-29811D03*
Y-33211D03*
X1493120Y240412D03*
X1487958Y236062D03*
X1490060Y255378D03*
X1485320Y260362D03*
X1478745Y281508D03*
X1493289Y280027D03*
X1478526Y289677D03*
X1481445Y289708D03*
X1479745Y312208D03*
X1478426Y306277D03*
X1481345Y306308D03*
X1481484Y361688D03*
X1481766Y372288D03*
X1489443D03*
X1494784Y374188D03*
X1486040Y368392D03*
X1481766Y406238D03*
X1490384Y407292D03*
X1493384Y411313D03*
X1482650Y411190D03*
X1495527Y406215D03*
X1486880Y416863D03*
X1484805Y427577D03*
X1489310Y426822D03*
X1481539Y1259377D03*
X1478999Y1259257D03*
X1481479Y1261947D03*
X1481419Y1264547D03*
X1481431Y1267254D03*
X1478939Y1261827D03*
X1478879Y1264427D03*
X1478891Y1267134D03*
X1481359Y1271447D03*
X1492039D03*
X1481359Y1274144D03*
X1492091D03*
X1478859Y1271417D03*
Y1274114D03*
X1481361Y1280054D03*
X1492101D03*
X1478821D03*
X1481359Y1277024D03*
X1492091D03*
X1478859Y1276994D03*
X1489154Y1334603D03*
X1493814D03*
X1491484Y1335353D03*
X1482750Y1342755D03*
X1478750Y1342017D03*
X1486960Y1344245D03*
X1485488Y1341787D03*
X1478750Y1345073D03*
X1485387Y1420002D03*
X1481918Y1425579D03*
X1484442Y1445557D03*
Y1448557D03*
X1482830Y1525162D03*
X1480800Y1663600D03*
X1510500Y125992D03*
X1508959Y215802D03*
X1503020D03*
X1499922Y211240D03*
X1496720Y225292D03*
X1504484Y234562D03*
X1508410Y230842D03*
X1510017Y225516D03*
X1501840Y225502D03*
X1512420Y239116D03*
X1510810Y249742D03*
X1509040Y243362D03*
X1504890Y249862D03*
X1506600Y239092D03*
X1504650Y254392D03*
X1508049Y280056D03*
X1498984Y282797D03*
X1508558Y291175D03*
X1512244Y311522D03*
X1505922Y304583D03*
X1509539Y308467D03*
X1498184Y361723D03*
Y369798D03*
X1495150Y369842D03*
X1503450Y385843D03*
X1509638Y738627D03*
X1509350Y741315D03*
X1504747Y747293D03*
X1503514Y801361D03*
Y797961D03*
X1497199Y1275667D03*
X1497259Y1273097D03*
X1494629Y1271477D03*
X1494631Y1274144D03*
X1506569Y1285947D03*
X1508819Y1284797D03*
X1506539Y1288557D03*
X1508759Y1287367D03*
X1508699Y1289967D03*
X1494641Y1280054D03*
X1494631Y1277024D03*
X1506551Y1291254D03*
X1497199Y1278277D03*
X1497161Y1280974D03*
X1506689Y1283377D03*
X1506591Y1297014D03*
Y1294134D03*
X1508711Y1295554D03*
Y1298434D03*
Y1292674D03*
X1496784Y1341147D03*
X1498924Y1334882D03*
X1498950Y1339517D03*
X1501149Y1336287D03*
X1496784Y1338247D03*
X1496144Y1335353D03*
X1504588Y1353316D03*
Y1355816D03*
X1501033Y1341462D03*
X1498959Y1342930D03*
X1505570Y1364212D03*
X1507704Y1361597D03*
X1510027Y1425825D03*
X1507617Y1424045D03*
X1522920Y116180D03*
X1513900Y117762D03*
X1518575Y138662D03*
X1521115Y193262D03*
X1524539Y215551D03*
X1522009Y210825D03*
X1518110Y215551D03*
X1526998Y209645D03*
X1527732Y219488D03*
X1514520Y231116D03*
X1526152Y225114D03*
X1514593Y249698D03*
Y235116D03*
X1519758Y265161D03*
X1522786Y262558D03*
X1522258Y265161D03*
X1519833Y277297D03*
X1522258Y288956D03*
X1517669Y291516D03*
X1515940Y795815D03*
Y799215D03*
X1513789Y1290037D03*
X1511289Y1287397D03*
X1511199Y1290007D03*
X1513791Y1292704D03*
X1516351D03*
X1513791Y1298464D03*
Y1295584D03*
X1516351D03*
Y1298464D03*
X1511251Y1292704D03*
Y1298464D03*
Y1295584D03*
X1521282Y1357401D03*
X1525942D03*
X1514878Y1365553D03*
X1510878Y1364815D03*
X1519088Y1367043D03*
X1517616Y1364585D03*
X1510878Y1367871D03*
X1523612Y1358151D03*
X1512177Y1427795D03*
X1516137Y1432135D03*
X1513657Y1429985D03*
X1544010Y27552D03*
X1536310Y47492D03*
X1534060Y100162D03*
X1530660D03*
X1533520Y110662D03*
X1529500Y122122D03*
X1535575Y118862D03*
X1540090Y122782D03*
X1536925Y129937D03*
X1529500Y125862D03*
X1535520Y151562D03*
X1529233Y153162D03*
X1535450Y155262D03*
X1542401Y141561D03*
X1534720Y199803D03*
X1528720Y199862D03*
X1533385Y193108D03*
X1533148Y211614D03*
X1531824Y207677D03*
X1534194Y217519D03*
X1529670Y225522D03*
X1535561Y225393D03*
X1531110Y264862D03*
X1539150Y267132D03*
X1540958Y307756D03*
X1539720Y589862D03*
Y581862D03*
X1540377Y634165D03*
X1541211Y646178D03*
X1533178Y1360815D03*
X1530978Y1359315D03*
X1528912Y1361045D03*
X1531078Y1362315D03*
X1533178Y1363715D03*
X1528912Y1363945D03*
X1533178Y1357915D03*
X1528272Y1358151D03*
X1552960Y124359D03*
X1553189Y127781D03*
X1556049Y147711D03*
X1545763Y159305D03*
X1551160Y189342D03*
X1557900Y220362D03*
X1557760Y214792D03*
X1550353Y217352D03*
X1557320Y203297D03*
X1559400Y229832D03*
X1545668Y305266D03*
X1545768Y302766D03*
X1543958Y307556D03*
X1546458Y307856D03*
X1543858Y310056D03*
X1543720Y581862D03*
X1548720D03*
X1552720Y589862D03*
Y581862D03*
X1554753Y628860D03*
X1553312Y636815D03*
X1559354Y655716D03*
Y659116D03*
X1550487Y681565D03*
X1550320Y696562D03*
X1550917Y704332D03*
X1550390Y709885D03*
X1573560Y245078D03*
X1574760Y251032D03*
X1559722Y243110D03*
X1570675Y267857D03*
X1573246Y306650D03*
X1572396Y309450D03*
X1563714Y572792D03*
X1567114D03*
X1559557Y593290D03*
X1564768Y708159D03*
X1562871Y732316D03*
Y735716D03*
X1571577Y747145D03*
X1567547Y755485D03*
X1571920Y762662D03*
X1568490Y758162D03*
X1570374Y760093D03*
X1576589Y300927D03*
X1588314Y592553D03*
X1585714D03*
X1583114D03*
X1590914D03*
X1588254Y595103D03*
X1588284Y597613D03*
X1585654Y595103D03*
X1585684Y597613D03*
X1583084D03*
X1583054Y595103D03*
X1588284Y608655D03*
X1585684D03*
X1583084D03*
X1590854Y595103D03*
X1590884Y597613D03*
Y608655D03*
X1588254Y613715D03*
X1588224Y611205D03*
X1585654Y613715D03*
X1585624Y611205D03*
X1583024D03*
X1583054Y613715D03*
X1590854D03*
X1590824Y611205D03*
X1591368Y628727D03*
X1591428Y626177D03*
X1588928D03*
X1588868Y628727D03*
X1591398Y631237D03*
X1588898D03*
X1591368Y650877D03*
X1591338Y648367D03*
X1591398Y645817D03*
X1588868Y650877D03*
X1588838Y648367D03*
X1588898Y645817D03*
X1591368Y653377D03*
X1588868D03*
X1591448Y657677D03*
X1588948D03*
Y660177D03*
X1591448D03*
X1588968Y665237D03*
X1591468D03*
X1588938Y662727D03*
X1591438D03*
X1588938Y679807D03*
X1588878Y682357D03*
X1588908Y684867D03*
X1591438Y679807D03*
X1591378Y682357D03*
X1591408Y684867D03*
X1591328Y696727D03*
X1591388Y694177D03*
X1588888D03*
X1588828Y696727D03*
X1591358Y699277D03*
X1588858D03*
X1591358Y718837D03*
X1591328Y716327D03*
X1591388Y713777D03*
X1588858Y718837D03*
X1588828Y716327D03*
X1588888Y713777D03*
X1590915Y755793D03*
X1603747Y192951D03*
X1603530Y202402D03*
X1603706Y211526D03*
X1603580Y206902D03*
X1604200Y234642D03*
X1604240Y227892D03*
X1603920Y222922D03*
X1604270Y231490D03*
X1604240Y238242D03*
X1602980Y560002D03*
X1593514Y592553D03*
X1601830Y590685D03*
X1604430D03*
X1607200Y583962D03*
X1593484Y597613D03*
X1593454Y595103D03*
X1593484Y608655D03*
X1593424Y611205D03*
X1593454Y613715D03*
X1601830Y615201D03*
X1604430D03*
X1598868Y628727D03*
X1598928Y626177D03*
X1593868Y628727D03*
X1593928Y626177D03*
X1596428D03*
X1596368Y628727D03*
X1598898Y631237D03*
X1593898D03*
X1596398D03*
X1598868Y650877D03*
X1598838Y648367D03*
X1596368Y650877D03*
X1593868D03*
X1596338Y648367D03*
X1593838D03*
X1598898Y645817D03*
X1596398D03*
X1593898D03*
X1598868Y653377D03*
X1596368D03*
X1593868D03*
X1598948Y657677D03*
X1593948D03*
X1596448D03*
Y660177D03*
X1593948D03*
X1598948D03*
X1596468Y665237D03*
X1593968D03*
X1598968D03*
X1596438Y662727D03*
X1593938D03*
X1598938D03*
X1593938Y679807D03*
X1596438D03*
X1593878Y682357D03*
X1596378D03*
X1593908Y684867D03*
X1596408D03*
X1598878Y682357D03*
X1598908Y684867D03*
X1598938Y679807D03*
X1596288Y688902D03*
X1598888D03*
X1598828Y696727D03*
X1593828D03*
X1593888Y694177D03*
X1596388D03*
X1596328Y696727D03*
X1593858Y699277D03*
X1596358D03*
X1598888Y694177D03*
X1596288Y691502D03*
X1598858Y699277D03*
X1598888Y691502D03*
X1598858Y718837D03*
X1598828Y716327D03*
X1596358Y718837D03*
X1593858D03*
X1596328Y716327D03*
X1593828D03*
X1596388Y713777D03*
X1593888D03*
X1598888D03*
X1596250Y721452D03*
X1598850D03*
X1599010Y724002D03*
X1598440Y736692D03*
X1592760Y736652D03*
X1595600D03*
X1606788Y756199D03*
X1602788D03*
X1621920Y25962D03*
X1622220Y49862D03*
X1623881Y129627D03*
X1610788Y756199D03*
X1614788D03*
X1618788D03*
X1615062Y1421241D03*
X1613047Y1415669D03*
X1614927Y1426076D03*
Y1429896D03*
X1624353Y1428766D03*
Y1431316D03*
X1617215Y1440822D03*
X1633111Y206693D03*
X1632342Y216015D03*
X1635835Y343002D03*
X1636800Y429982D03*
X1639800D03*
X1636800Y426982D03*
X1639800D03*
X1636800Y438982D03*
X1639800D03*
X1636800Y435982D03*
X1639800D03*
X1636800Y432982D03*
X1639800D03*
X1638928Y756199D03*
X1630928D03*
X1634928D03*
X1638277Y1269065D03*
X1640812Y1270020D03*
X1631203Y1367492D03*
X1628653D03*
X1626153D03*
X1628653Y1372492D03*
X1631203D03*
X1626153D03*
X1631203Y1369992D03*
X1628653D03*
X1626153D03*
X1628653Y1379992D03*
Y1382492D03*
Y1377492D03*
Y1374992D03*
X1631203Y1377492D03*
Y1374992D03*
Y1379992D03*
Y1382492D03*
X1626153Y1379992D03*
Y1382492D03*
Y1374992D03*
Y1377492D03*
X1630643Y1440290D03*
X1627469Y1437072D03*
X1624853Y1440875D03*
X1634643Y1442982D03*
X1638785Y1442483D03*
X1637042Y1440215D03*
X1630643Y1443090D03*
X1635315Y1465745D03*
Y1462745D03*
X1632315Y1468745D03*
X1629815D03*
X1632315Y1465745D03*
X1629815D03*
X1632315Y1462745D03*
X1629815D03*
X1635315Y1468745D03*
Y1460245D03*
X1629815D03*
X1632315D03*
X1629815Y1457745D03*
X1632315D03*
X1635315D03*
X1639645Y1473645D03*
X1650020Y408952D03*
X1647310Y408922D03*
X1650020Y411452D03*
X1647310Y411422D03*
X1654110Y434177D03*
X1657755Y517910D03*
X1651851Y532057D03*
X1651112Y545572D03*
X1645530Y549160D03*
X1653230Y549322D03*
X1642720Y560862D03*
X1656238Y592113D03*
X1649833Y594946D03*
X1653794Y594956D03*
X1653774Y598576D03*
X1649844Y598555D03*
X1656955Y611090D03*
X1645300Y612202D03*
X1653220Y620662D03*
X1645681Y624011D03*
X1648581D03*
X1651481D03*
X1654809Y638101D03*
X1653319Y642311D03*
X1652351Y639573D03*
X1648811Y628277D03*
X1647081Y626211D03*
X1645917Y628917D03*
Y633577D03*
X1645167Y631247D03*
Y635907D03*
X1650081Y626111D03*
X1651711Y628277D03*
X1651635Y651836D03*
X1652581Y646311D03*
X1643582Y652601D03*
X1655637Y646311D03*
X1641082Y652601D03*
X1649363Y649485D03*
X1654809Y672101D03*
X1652351Y673573D03*
X1645681Y658011D03*
X1648581D03*
X1648811Y662277D03*
X1647081Y660211D03*
X1645917Y662917D03*
Y667577D03*
X1645167Y665247D03*
Y669907D03*
X1650081Y660111D03*
X1651481Y658011D03*
X1651711Y662277D03*
X1641082Y686601D03*
X1651635Y685836D03*
X1652581Y680311D03*
X1653319Y676311D03*
X1643582Y686601D03*
X1655113Y680835D03*
X1649363Y683485D03*
X1654809Y706101D03*
X1648811Y696277D03*
X1645167Y703907D03*
X1645917Y701577D03*
X1645167Y699247D03*
X1645917Y696917D03*
X1650081Y694111D03*
X1645681Y692011D03*
X1647081Y694211D03*
X1648581Y692011D03*
X1651711Y696277D03*
X1651481Y692011D03*
X1641082Y720601D03*
X1651635Y719836D03*
X1652581Y714311D03*
X1653319Y710311D03*
X1652351Y707573D03*
X1643582Y720601D03*
X1655637Y714311D03*
X1649363Y717485D03*
X1651509Y756492D03*
X1650771Y1367492D03*
X1648271D03*
X1645721D03*
X1648271Y1372492D03*
X1650771D03*
X1645721D03*
X1650771Y1369992D03*
X1648271D03*
X1645721D03*
X1648271Y1379992D03*
Y1382492D03*
X1650771Y1379992D03*
Y1382492D03*
X1648271Y1377492D03*
Y1374992D03*
X1650771Y1377492D03*
Y1374992D03*
X1645721Y1377492D03*
Y1374992D03*
Y1379992D03*
Y1382492D03*
X1641047Y1432876D03*
X1645707D03*
X1643377Y1433626D03*
X1648037D03*
X1655762Y1429794D03*
X1648677Y1436220D03*
X1653243Y1435690D03*
X1651043Y1434190D03*
X1653243Y1432790D03*
X1651143Y1437190D03*
X1653243Y1438590D03*
X1648677Y1439120D03*
X1655295Y1453879D03*
X1652295D03*
X1643065Y1462645D03*
Y1465645D03*
Y1468645D03*
Y1460145D03*
Y1457645D03*
X1655295Y1456899D03*
X1652295D03*
X1642645Y1473645D03*
X1646958Y1501553D03*
X1668100Y180852D03*
X1667739Y187187D03*
X1666690Y193290D03*
X1674432Y216981D03*
X1672596Y220541D03*
X1668426Y222432D03*
X1664866Y225162D03*
X1660861Y227548D03*
X1664970Y472112D03*
X1662447Y480619D03*
X1665790Y523417D03*
X1662262Y537334D03*
X1659740Y542222D03*
X1661872Y534703D03*
X1660243Y532071D03*
X1668917Y549992D03*
X1666902Y555115D03*
X1663502D03*
X1658738Y592113D03*
X1661238D03*
X1664197Y602191D03*
X1669222Y604490D03*
X1670700Y594562D03*
X1672500Y596462D03*
X1660660Y602273D03*
X1664410Y617953D03*
X1668920Y617637D03*
X1660754Y609837D03*
X1669397Y614064D03*
X1663471Y609837D03*
X1666686Y757162D03*
X1669303Y1372492D03*
X1664253D03*
X1666753D03*
X1669303Y1367492D03*
Y1369992D03*
X1666753Y1367492D03*
X1664253D03*
Y1369992D03*
X1666753D03*
X1669303Y1379992D03*
Y1382492D03*
Y1377492D03*
Y1374992D03*
X1666753Y1379992D03*
X1664253D03*
X1666753Y1382492D03*
X1664253D03*
X1666753Y1377492D03*
X1664253D03*
Y1374992D03*
X1666753D03*
X1662496Y1428791D03*
Y1431291D03*
X1665612Y1437072D03*
X1662996Y1440922D03*
X1672786Y1442982D03*
X1668786Y1440290D03*
Y1443256D03*
X1657920Y1453405D03*
X1660920D03*
X1657860Y1466545D03*
Y1464045D03*
X1657950Y1456210D03*
X1657860Y1459045D03*
Y1461545D03*
X1660950Y1456210D03*
X1660860Y1466545D03*
Y1464045D03*
Y1459045D03*
Y1461545D03*
X1666123Y1493362D03*
Y1501362D03*
Y1533862D03*
Y1520862D03*
Y1545862D03*
X1671673Y1550815D03*
X1666123Y1557557D03*
X1666198Y1561557D03*
X1671660Y1569412D03*
X1666198Y1581321D03*
X1678994Y217231D03*
X1690208Y421855D03*
X1689095Y462640D03*
X1684940Y463030D03*
X1685779Y491230D03*
X1690229Y481845D03*
X1687238Y485496D03*
X1681817Y495290D03*
X1675664Y513802D03*
X1690999Y513107D03*
X1683702Y514687D03*
X1676600Y523902D03*
X1688768Y518107D03*
X1689544Y543874D03*
X1689506Y539882D03*
X1679941Y552222D03*
X1678860Y556752D03*
X1683369Y562698D03*
Y566098D03*
X1676644Y655345D03*
Y652745D03*
X1679244Y655345D03*
X1681864Y655286D03*
X1679244Y652745D03*
X1676624Y642404D03*
X1676644Y644945D03*
Y647545D03*
Y650145D03*
X1679244Y642345D03*
X1681864Y642286D03*
X1679244Y644945D03*
Y647545D03*
X1681864Y644886D03*
Y647486D03*
Y650086D03*
Y652686D03*
X1679244Y650145D03*
X1673860Y726522D03*
X1681810Y752955D03*
X1688912Y1372492D03*
X1686362D03*
Y1367492D03*
Y1369992D03*
X1688912Y1367492D03*
Y1369992D03*
Y1377492D03*
Y1374992D03*
Y1382492D03*
Y1379992D03*
X1686362D03*
Y1382492D03*
Y1374992D03*
Y1377492D03*
X1679190Y1432876D03*
X1683850D03*
X1681520Y1433626D03*
X1686180D03*
X1686820Y1436520D03*
X1688886Y1434790D03*
X1688986Y1437790D03*
X1676928Y1442483D03*
X1675185Y1440215D03*
X1686820Y1439420D03*
X1680720Y1487062D03*
X1679508Y1498303D03*
X1678340Y1500862D03*
X1679508Y1517803D03*
X1677930Y1520362D03*
X1679508Y1538803D03*
X1678340Y1541362D03*
X1678230Y1590542D03*
X1674220Y1585321D03*
X1703617Y26459D03*
X1700217D03*
X1703570Y50649D03*
X1700170D03*
X1702490Y204780D03*
X1704223Y209707D03*
Y212207D03*
X1701164Y209758D03*
X1698566Y214904D03*
X1696066D03*
X1693725Y217409D03*
X1698566Y212404D03*
X1696066D03*
X1698725Y217409D03*
X1696225D03*
X1701164Y212258D03*
X1704264Y217458D03*
X1701264D03*
X1704264Y214958D03*
X1701264D03*
X1698566Y209704D03*
X1696066D03*
X1693466Y209504D03*
Y214704D03*
Y212204D03*
X1693725Y219909D03*
X1698725D03*
X1696225D03*
X1704264Y219958D03*
X1701264D03*
X1704185Y222710D03*
X1698220Y369652D03*
X1699809Y403985D03*
X1695579D03*
X1702959Y404243D03*
X1707780Y410738D03*
X1697161Y406602D03*
X1692429Y403985D03*
X1701124Y423802D03*
X1694050Y416643D03*
X1695455Y422287D03*
X1707544Y431745D03*
X1707568Y420370D03*
X1690140Y434160D03*
X1693720Y455862D03*
X1697220D03*
X1702127Y468719D03*
X1693236Y472650D03*
X1691151Y493678D03*
X1689943Y479304D03*
X1701811Y501318D03*
X1701635Y497177D03*
X1699300Y498632D03*
X1697210Y500802D03*
X1694050Y501422D03*
X1693711Y498527D03*
X1691129Y501697D03*
X1707200Y498962D03*
X1699553Y513107D03*
X1707552Y506731D03*
X1707716Y513562D03*
X1702930Y526102D03*
X1699265Y521507D03*
X1690999Y525507D03*
X1701726Y518107D03*
X1699666Y541507D03*
X1699251Y533642D03*
X1691104Y530503D03*
X1691445Y535011D03*
X1704886Y534564D03*
X1689769Y537339D03*
X1699107Y555783D03*
X1703306Y550064D03*
X1703452Y639381D03*
X1700852D03*
X1698232Y639440D03*
X1700852Y655141D03*
X1703452Y647341D03*
Y649941D03*
Y652541D03*
Y644741D03*
X1700852Y647341D03*
Y649941D03*
Y652541D03*
Y644741D03*
X1698232Y655200D03*
Y644800D03*
Y647400D03*
Y650000D03*
Y652600D03*
X1703452Y641981D03*
X1700852D03*
X1698232Y642040D03*
X1700922Y657781D03*
X1698302Y657840D03*
X1698048Y705662D03*
X1701320Y705678D03*
X1698020Y702962D03*
X1696402Y709533D03*
X1699110Y727452D03*
X1705035Y729210D03*
X1704973Y753019D03*
X1703310Y749455D03*
X1690620Y760702D03*
X1691412Y1372492D03*
Y1367492D03*
Y1369992D03*
Y1377492D03*
Y1374992D03*
Y1382492D03*
Y1379992D03*
X1691086Y1436290D03*
Y1433390D03*
X1693392Y1429808D03*
X1691086Y1439190D03*
X1704723Y1500862D03*
Y1520362D03*
Y1541362D03*
X1705003Y1564057D03*
X1707220Y15662D03*
X1715210Y18282D03*
X1714589Y21562D03*
X1709589Y26062D03*
X1719589Y25862D03*
X1717089D03*
X1710106Y48720D03*
Y40020D03*
X1720895Y68062D03*
X1716875D03*
X1712520Y117862D03*
X1712720Y111862D03*
X1719943Y112667D03*
Y116667D03*
X1713418Y130862D03*
X1721418Y135327D03*
X1717418D03*
X1714490Y142920D03*
X1717140Y148910D03*
X1711700Y140200D03*
X1717619Y165909D03*
X1718110Y159040D03*
X1719530Y162950D03*
X1722078Y189483D03*
X1720310Y191252D03*
X1707159Y217580D03*
Y215080D03*
Y210080D03*
Y222580D03*
Y225080D03*
Y220080D03*
X1713720Y381152D03*
X1717220D03*
X1719200Y371162D03*
X1713720Y391652D03*
Y384652D03*
Y388152D03*
X1717220Y391652D03*
Y388152D03*
Y384652D03*
X1709000Y413362D03*
X1706500D03*
X1709000Y415862D03*
X1706500D03*
X1721220Y458362D03*
X1713977Y457137D03*
X1708977Y458542D03*
X1721936Y469263D03*
X1716134Y478443D03*
X1715711Y474399D03*
X1713977Y470804D03*
X1708977D03*
X1716148Y483720D03*
X1716087Y495665D03*
X1716156Y487685D03*
X1716278Y491676D03*
X1707552Y503331D03*
X1709844Y516106D03*
X1707610Y534113D03*
X1709356Y541144D03*
X1709680Y545432D03*
X1716110Y532632D03*
X1707346Y547504D03*
X1717987Y569705D03*
X1716480Y691410D03*
X1710550Y691327D03*
X1712824Y696476D03*
X1710122Y703509D03*
X1713920Y700962D03*
X1709828Y719283D03*
X1713450Y728222D03*
X1719727Y1472088D03*
X1726720Y49862D03*
X1733720D03*
X1730220D03*
X1736040Y41792D03*
X1732810Y52482D03*
X1736040Y44292D03*
X1730140Y52552D03*
X1727600Y52582D03*
X1725320Y67962D03*
X1723018Y101667D03*
X1723218Y93267D03*
X1738220Y98862D03*
X1736720Y101862D03*
X1729080Y118132D03*
X1739720Y120892D03*
X1728999Y112895D03*
X1730765Y151362D03*
X1733920D03*
X1723670Y149102D03*
X1728320Y169862D03*
X1723090Y173072D03*
Y177072D03*
X1734857Y184865D03*
X1737470Y177147D03*
X1737500Y217962D03*
Y214962D03*
Y211962D03*
Y208962D03*
Y226962D03*
Y223962D03*
Y220962D03*
X1725344Y359334D03*
X1728300Y377787D03*
X1733780Y390620D03*
X1729810D03*
X1737660D03*
X1734290Y423820D03*
X1727700Y417265D03*
X1739316Y480939D03*
X1730954Y478062D03*
X1725522Y482869D03*
X1733354Y490869D03*
Y486869D03*
X1738014Y1287344D03*
X1724431Y1336311D03*
X1734717Y1404340D03*
X1729700Y1462932D03*
X1733200D03*
X1736700D03*
X1736400Y1458942D03*
Y1455442D03*
X1731600Y1457230D03*
X1726120Y1490262D03*
X1726149Y1496270D03*
X1724649Y1513945D03*
X1727674D03*
X1729310Y1520951D03*
X1735310D03*
X1724649Y1505895D03*
X1727674D03*
X1726310Y1530445D03*
X1732310D03*
X1729310D03*
X1735310D03*
X1726310Y1520951D03*
X1732310D03*
X1751065Y39017D03*
X1754620Y39062D03*
X1747720Y31862D03*
Y34362D03*
X1740858Y72330D03*
Y79830D03*
Y74830D03*
Y82330D03*
X1745220Y98862D03*
X1741720D03*
X1743720Y101862D03*
X1740220D03*
X1748720Y97362D03*
X1745010Y122952D03*
X1750820Y119972D03*
X1738520Y151362D03*
X1751220Y147562D03*
X1748465D03*
X1754120Y171562D03*
X1750920Y171662D03*
X1754234Y190836D03*
X1752078Y216728D03*
X1740500Y217962D03*
Y214962D03*
Y211962D03*
Y208962D03*
X1747600Y209062D03*
X1744600D03*
X1751800Y206762D03*
X1752078Y226728D03*
Y224228D03*
Y221728D03*
Y219228D03*
X1740500Y226962D03*
Y223962D03*
Y220962D03*
X1746484Y279682D03*
X1749450Y293862D03*
X1756204Y301695D03*
X1752000Y306562D03*
X1756933Y372452D03*
X1744380Y382892D03*
X1744510Y377452D03*
X1747080Y435870D03*
X1746720Y464862D03*
X1752316Y703969D03*
Y695669D03*
X1752217Y692988D03*
X1752276Y720529D03*
X1752316Y712269D03*
X1747814Y1287344D03*
X1742714Y1287244D03*
X1754165Y1304422D03*
Y1307422D03*
Y1301422D03*
Y1295422D03*
Y1298422D03*
Y1310422D03*
X1738740Y1451742D03*
X1740200Y1462932D03*
X1745111Y1463262D03*
X1747677Y1507388D03*
X1744677D03*
X1747304Y1524976D03*
X1744304D03*
X1762420Y21562D03*
X1765238Y22062D03*
X1768026Y24165D03*
X1769669Y15244D03*
X1761998Y15187D03*
X1765260Y18262D03*
X1757320Y15872D03*
X1758672Y26431D03*
X1755272D03*
X1767220Y26962D03*
X1758669Y50649D03*
X1755269D03*
X1762738Y53262D03*
X1767220Y53342D03*
X1767185Y48817D03*
X1767400Y39915D03*
X1769274Y50742D03*
X1771774Y53682D03*
X1758063Y72623D03*
X1767170Y83607D03*
X1767990Y76797D03*
X1760478Y90027D03*
X1770368Y72691D03*
X1757978Y116727D03*
X1760978D03*
X1763678Y106127D03*
X1769278Y108027D03*
Y110927D03*
Y113727D03*
X1755978Y108427D03*
Y111027D03*
X1760478Y106127D03*
X1758300Y128242D03*
X1763435Y166862D03*
X1765820Y182282D03*
X1767300Y174587D03*
X1755078Y216928D03*
X1761500Y214062D03*
X1765000D03*
X1768500D03*
X1755078Y219428D03*
Y221928D03*
Y224428D03*
X1760104Y301648D03*
X1761936Y310709D03*
X1769230Y310478D03*
X1756800Y364048D03*
Y368048D03*
X1770280Y372452D03*
X1770220Y377452D03*
Y382952D03*
X1757066Y435721D03*
X1757650Y461393D03*
X1768560Y539042D03*
X1766060D03*
X1768317Y686375D03*
X1755112Y703948D03*
Y695648D03*
X1755013Y692967D03*
X1757612Y703948D03*
Y695648D03*
X1755072Y720508D03*
X1755112Y712248D03*
X1757572Y720508D03*
X1757612Y712248D03*
X1757165Y1304422D03*
X1760165D03*
Y1307422D03*
X1757165D03*
X1769165Y1301422D03*
X1766165D03*
X1763165D03*
X1757165D03*
X1760165D03*
X1769165Y1295422D03*
X1766165D03*
X1763165D03*
X1760165D03*
X1757165D03*
X1760165Y1298422D03*
X1757165D03*
X1763165D03*
X1766165D03*
X1769165D03*
X1758352Y1317368D03*
Y1322168D03*
X1757165Y1310422D03*
X1760165D03*
X1759987Y1325375D03*
Y1328275D03*
X1763829Y1337548D03*
X1766829D03*
Y1340448D03*
X1769829Y1337548D03*
Y1340448D03*
X1766829Y1343348D03*
X1769829Y1346248D03*
Y1343348D03*
Y1349148D03*
Y1351858D03*
X1782305Y13647D03*
X1775556Y21471D03*
X1775830Y26522D03*
X1777754Y37746D03*
X1781774Y54462D03*
X1774274Y50742D03*
X1776710Y53562D03*
X1779411Y50692D03*
X1774328Y60087D03*
X1779778Y70027D03*
X1774328Y62987D03*
X1775580Y73330D03*
X1779778Y72927D03*
X1787790Y85132D03*
X1781485Y88192D03*
X1785142Y76032D03*
X1773611Y88293D03*
X1778578Y97927D03*
X1778478Y90627D03*
X1784178Y108227D03*
Y111127D03*
Y113927D03*
X1780320Y153162D03*
X1774950Y167392D03*
X1779500Y171692D03*
X1777520Y178403D03*
Y173903D03*
X1782600Y175932D03*
X1778778Y216928D03*
X1783878D03*
X1772000Y214062D03*
X1778778Y219428D03*
Y221928D03*
X1783878Y224428D03*
Y226928D03*
Y219428D03*
Y221928D03*
X1786089Y287641D03*
X1783563D03*
X1777354Y295489D03*
X1783018Y301729D03*
X1782324Y410432D03*
Y403932D03*
Y425432D03*
Y418932D03*
X1782420Y447137D03*
X1781470Y452065D03*
X1778310Y591152D03*
X1781720Y592742D03*
X1778165Y1307422D03*
Y1304422D03*
Y1301422D03*
X1775165D03*
X1772165D03*
X1778165Y1295422D03*
X1775165D03*
X1772165D03*
Y1298422D03*
X1775165D03*
X1778165D03*
X1784165Y1307422D03*
Y1304422D03*
X1781165Y1307422D03*
Y1304422D03*
X1784165Y1301422D03*
Y1295422D03*
Y1298422D03*
X1781165Y1301422D03*
Y1295422D03*
Y1298422D03*
X1781829Y1324448D03*
X1784829D03*
X1778829D03*
X1778165Y1310422D03*
Y1312922D03*
X1784165Y1310422D03*
Y1312922D03*
X1781165Y1310422D03*
Y1312922D03*
X1781829Y1333148D03*
Y1330248D03*
Y1327348D03*
X1784829Y1333148D03*
Y1330248D03*
Y1327348D03*
X1781829Y1337548D03*
Y1340448D03*
X1784829Y1337548D03*
Y1340448D03*
X1778829Y1333148D03*
Y1330248D03*
Y1327348D03*
Y1337548D03*
X1772829D03*
X1775829D03*
X1778829Y1340448D03*
X1775829D03*
X1772829D03*
X1781829Y1346248D03*
Y1343348D03*
Y1349148D03*
Y1351858D03*
Y1354758D03*
X1772829Y1346248D03*
X1775829D03*
X1778829D03*
X1772829Y1343348D03*
X1775829D03*
X1778829D03*
X1772829Y1349148D03*
X1775829D03*
X1778829D03*
X1772829Y1351858D03*
X1775829D03*
X1778829D03*
X1772829Y1354758D03*
X1775829D03*
X1778829D03*
X1799920Y52594D03*
X1788238Y82292D03*
Y78062D03*
Y74912D03*
X1803215Y154032D03*
X1793269Y287641D03*
X1790743D03*
X1791619Y294441D03*
X1789093D03*
X1800160Y362542D03*
X1800340Y387062D03*
X1791494Y386536D03*
X1792450Y410615D03*
X1792507Y403932D03*
X1792220Y425432D03*
X1792335Y418775D03*
X1796020Y451162D03*
X1791888Y683805D03*
X1800450Y1505230D03*
X1795561Y1524729D03*
X1806920Y150862D03*
X1808910Y143902D03*
X1813335Y155435D03*
X1813325Y177257D03*
X1807220Y179897D03*
X1817157Y373829D03*
X1816224Y410432D03*
X1816994Y398052D03*
X1815724Y423932D03*
X1810792Y417432D03*
X1812161Y472521D03*
X1814537Y1322105D03*
X1813700Y1494762D03*
X1807150Y1505675D03*
X1818289Y1501591D03*
X1811494Y1505349D03*
X1813994Y1507891D03*
X1825762Y167662D03*
X1835760Y185772D03*
X1829695Y226333D03*
X1832295D03*
X1827095D03*
X1824095D03*
X1834895D03*
Y223733D03*
X1824095D03*
X1827095D03*
X1832295D03*
X1829695D03*
X1832295Y233933D03*
X1829695D03*
X1827095D03*
X1824095D03*
X1829695Y231433D03*
X1832295D03*
X1829695Y228933D03*
X1832295D03*
X1827095Y231433D03*
X1824095D03*
X1827095Y228933D03*
X1824095D03*
X1834895Y233933D03*
Y231433D03*
Y228933D03*
X1828204Y328654D03*
X1829189Y363731D03*
X1829434Y406348D03*
X1834005Y401421D03*
X1821280Y413432D03*
X1834600Y406442D03*
X1826914Y431718D03*
X1829514Y1498198D03*
Y1500807D03*
X1832114Y1498198D03*
Y1500807D03*
X1824995Y1502201D03*
X1846691Y166450D03*
X1844157Y182210D03*
X1848435Y172187D03*
X1838880Y195162D03*
X1837895Y226333D03*
Y223733D03*
Y233933D03*
Y231433D03*
Y228933D03*
X1836294Y383592D03*
X1838379Y453921D03*
G54D31*
X174685Y647210D03*
X174393Y678354D03*
X195316Y1430034D03*
X383224Y1354446D03*
X412990D03*
X443326D03*
X458600Y1379662D03*
X472700Y1353962D03*
X526478Y1449795D03*
X708795Y1429579D03*
X1131715Y1532913D03*
X1168627Y1466363D03*
X1175215Y1532913D03*
X1359365Y1353946D03*
X1389131D03*
X1419467D03*
X1434200Y1379362D03*
X1449233Y1353946D03*
X1502956Y1449373D03*
X1670101Y1463655D03*
X1682882Y628017D03*
Y678952D03*
X1769790Y204632D03*
X1799350D03*
X1826405Y269763D03*
Y299056D03*
G54D27*
X70472Y173228D03*
Y236220D03*
G54D46*
X450000Y278543D03*
X470000D03*
X483500Y246362D03*
X473500D03*
X480000Y278543D03*
X490000D03*
X500000D03*
X498563Y607067D03*
X510000Y278543D03*
X520000D03*
X518563Y607067D03*
X508563D03*
X549236Y1441207D03*
X569236D03*
X688500Y1611900D03*
Y1621900D03*
X1041435Y143357D03*
X1056225Y143131D03*
X1041435Y163357D03*
X1056225Y163131D03*
X1099970Y1712570D03*
Y1722570D03*
X1689646Y115669D03*
X1679646D03*
X1689646Y125669D03*
Y135669D03*
X1679646Y125669D03*
Y135669D03*
X1689646Y145669D03*
Y155669D03*
X1679646Y145669D03*
Y155669D03*
X1689646Y165669D03*
X1679646D03*
X1689646Y175669D03*
X1679646D03*
X1771457Y1624646D03*
Y1644646D03*
G54D17*
X27699Y1258727D03*
Y1255381D03*
Y1265420D03*
Y1262074D03*
X43841Y994357D03*
Y1255381D03*
Y1258727D03*
Y1252034D03*
Y1262074D03*
Y1265420D03*
X57299Y766798D03*
X52541Y957546D03*
Y954200D03*
X57399Y1258727D03*
X52820Y1253862D03*
X57399Y1265420D03*
Y1262074D03*
X66099Y1061286D03*
X73541Y1255381D03*
Y1258727D03*
Y1252034D03*
Y1265420D03*
Y1262074D03*
X86999Y766798D03*
X82241Y957546D03*
Y954200D03*
Y994357D03*
X87099Y1258727D03*
X82241Y1248688D03*
X84334Y1254263D03*
X87099Y1265420D03*
Y1262074D03*
X103241Y994357D03*
Y1255381D03*
Y1258727D03*
Y1252034D03*
Y1265420D03*
Y1262074D03*
X116567Y766775D03*
X111941Y957546D03*
Y954200D03*
X125499Y1061286D03*
X116799Y1258727D03*
X111941Y1248688D03*
X114191Y1254604D03*
X116799Y1265420D03*
Y1262074D03*
X141641Y957546D03*
Y954200D03*
Y994357D03*
Y1057940D03*
X129933Y1238461D03*
X132941Y1255381D03*
Y1258727D03*
Y1252034D03*
X141641Y1248688D03*
X143675Y1255567D03*
X132941Y1265420D03*
Y1262074D03*
X146367Y766775D03*
X160130Y1251847D03*
X146499Y1258727D03*
Y1265420D03*
Y1262074D03*
X176099Y766798D03*
X171341Y957546D03*
Y954200D03*
X162641Y994357D03*
X176199Y1258727D03*
X162641Y1255381D03*
Y1258727D03*
Y1252034D03*
X171341Y1248688D03*
X171947Y1255837D03*
X176199Y1265420D03*
X162641D03*
Y1262074D03*
X176199D03*
X184899Y1061286D03*
X192341Y1255381D03*
Y1258727D03*
Y1252034D03*
Y1265420D03*
Y1262074D03*
X188897Y1578182D03*
X192297D03*
X205799Y766798D03*
X201041Y957546D03*
Y954200D03*
Y994357D03*
X205899Y1258727D03*
X201041Y1248688D03*
X201193Y1257900D03*
X205899Y1265420D03*
Y1262074D03*
X200957Y1578182D03*
X204357D03*
X222041Y957546D03*
Y954200D03*
Y994357D03*
Y1255381D03*
X219660Y1260492D03*
X222041Y1252034D03*
Y1265420D03*
Y1262074D03*
X225077Y1578182D03*
X213017D03*
X216417D03*
X235499Y766798D03*
X236391Y1002557D03*
X240521Y1000395D03*
X237841Y1000437D03*
X233891Y1002557D03*
X231391D03*
X228891D03*
X235599Y1258727D03*
X230741Y1248688D03*
X235480Y1265406D03*
X235599Y1262074D03*
X237137Y1578182D03*
X240537D03*
X228477D03*
X251741Y957546D03*
Y954200D03*
Y994357D03*
X254881Y999650D03*
X257561Y999608D03*
X244299Y1061286D03*
X248047Y1259155D03*
X250467Y1259175D03*
X251707Y1252034D03*
X249603Y1266204D03*
X251699Y1265254D03*
X249197Y1578182D03*
X252597D03*
X272529Y111053D03*
X265442D03*
X261899D03*
Y108553D03*
X265442D03*
X268985Y111053D03*
Y108553D03*
X272529D03*
X260441Y1057940D03*
Y1248688D03*
X273317Y1578182D03*
X261257D03*
X264657D03*
X285377D03*
X288777D03*
X276717D03*
X297437D03*
X300837D03*
X321557D03*
X309497D03*
X312897D03*
X333617D03*
X337017D03*
X324957D03*
X345677D03*
X349077D03*
X369797D03*
X357737D03*
X361137D03*
X373197D03*
X476451D03*
X485111D03*
X473051D03*
X500571D03*
X488511D03*
X497171D03*
X512631D03*
X509231D03*
X524691D03*
X533351D03*
X521291D03*
X536751D03*
X548811D03*
X545411D03*
X560871D03*
X557471D03*
X572931D03*
X581591D03*
X569531D03*
X597051D03*
X584991D03*
X593651D03*
X609111D03*
X605711D03*
X629658Y766478D03*
X623347Y999665D03*
X625780Y1000198D03*
X620899Y1061286D03*
X629931Y1258727D03*
X632080Y1262074D03*
X629699Y1255381D03*
X631270Y1264942D03*
X621171Y1578182D03*
X629831D03*
X617771D03*
X636941Y957546D03*
Y954200D03*
X644347Y1003135D03*
X640327D03*
X640467Y1000735D03*
X647447Y1002865D03*
X647397Y1000135D03*
X644257Y1000325D03*
X636946Y1258414D03*
X647690Y1260812D03*
X637041Y1252034D03*
X645897Y1248785D03*
X647877Y1254076D03*
X636877Y1261235D03*
X645291Y1578182D03*
X633231D03*
X641891D03*
X667677Y441636D03*
X650107Y1002825D03*
X650599Y1258727D03*
X666741Y1255381D03*
X664630Y1259442D03*
X649587Y1266766D03*
X661400Y1263522D03*
X657351Y1578182D03*
X653951D03*
X674628Y424313D03*
X671479Y421163D03*
X667660Y429037D03*
X674628Y427462D03*
X677778Y414864D03*
Y424313D03*
X671479Y414864D03*
X674628Y421163D03*
Y418013D03*
X677778D03*
Y421163D03*
X668329D03*
X677778Y427462D03*
Y430612D03*
X674628Y436911D03*
X671479D03*
X677778Y433761D03*
X668329Y436911D03*
X677778Y440061D03*
X674628D03*
X677778Y436911D03*
Y443210D03*
X680928Y440061D03*
X674628Y430612D03*
X671479Y443211D03*
X677778Y449510D03*
X668329Y452659D03*
X674628D03*
X671479D03*
X677778D03*
X668329Y455809D03*
X671479Y458959D03*
X674628D03*
X668329D03*
X677778D03*
Y455809D03*
X674628D03*
X668067Y462090D03*
X677778Y462108D03*
X671479Y455809D03*
X680928Y458959D03*
X674628Y449510D03*
Y462108D03*
X677778Y477856D03*
Y471557D03*
Y474707D03*
X671479Y465258D03*
X674628D03*
X668329D03*
X677778D03*
Y468407D03*
X671479Y481006D03*
X667350Y470680D03*
X671479Y474707D03*
X674628Y484006D03*
X680299Y766798D03*
X666641Y957546D03*
Y954200D03*
X672063Y998632D03*
X680299Y1061286D03*
Y1258727D03*
X666741Y1252034D03*
X675537Y1248885D03*
X677980Y1262074D03*
X666741D03*
X666646Y1264464D03*
X680046Y1264964D03*
X695055Y112678D03*
Y115178D03*
X687227Y414864D03*
X690376Y421163D03*
Y418013D03*
Y414864D03*
X693526Y427462D03*
X687227Y424313D03*
X690376Y427462D03*
X680928Y414864D03*
Y418013D03*
X684077Y421163D03*
X680928Y427462D03*
X684077Y418013D03*
Y427462D03*
X680928Y421163D03*
X684077Y424313D03*
X687227Y427462D03*
X696676D03*
X693526Y421163D03*
Y424313D03*
X690376D03*
X696676Y421163D03*
Y424313D03*
Y418013D03*
X680928Y436911D03*
Y433761D03*
X693526Y430612D03*
X696676Y440061D03*
Y443210D03*
X684077Y430612D03*
Y440061D03*
X687227Y436911D03*
Y443210D03*
X684077D03*
Y436911D03*
X680928Y443210D03*
X690376Y436911D03*
Y443210D03*
X687227Y440061D03*
X693526Y433761D03*
X696676D03*
X684077D03*
X687227Y430612D03*
X690376D03*
X696676D03*
X687227Y433761D03*
X680928Y430612D03*
X687227Y462108D03*
X680928Y455809D03*
X693526Y462108D03*
X680928Y449510D03*
X687227D03*
X690376Y462108D03*
X684077Y449510D03*
X680928Y452659D03*
X684077D03*
X687227Y455809D03*
X684077D03*
X680928Y462108D03*
X696676Y449510D03*
Y452659D03*
X690376Y449510D03*
Y455809D03*
X687227Y452659D03*
X693526Y458959D03*
X696676D03*
Y462108D03*
X687227Y458959D03*
X684077D03*
Y468407D03*
X687227Y471557D03*
Y474707D03*
Y477856D03*
X684077Y471557D03*
X690376Y465258D03*
X684077D03*
X680928Y471557D03*
Y474707D03*
Y477856D03*
X693526Y465258D03*
Y471557D03*
X690376Y468407D03*
Y477856D03*
Y471557D03*
X687227Y465258D03*
X690376Y474707D03*
X687227Y468407D03*
X693526D03*
X684077Y474707D03*
X696676Y465258D03*
Y474707D03*
Y468407D03*
X693526Y474707D03*
X696676Y471557D03*
X693526Y477856D03*
X696441Y957546D03*
Y954200D03*
Y994357D03*
Y1255381D03*
X694100Y1261562D03*
X696441Y1248688D03*
X692233Y1252480D03*
X696046Y1263764D03*
X698598Y115178D03*
X705685D03*
X702141D03*
X698598Y112678D03*
X705685D03*
X702141D03*
X706125Y418013D03*
X712424Y424313D03*
X699825Y427462D03*
X699826Y414864D03*
X699825Y424313D03*
X712424Y430612D03*
X709274Y440061D03*
Y443210D03*
X706125D03*
X699825D03*
X709274Y433761D03*
X712424D03*
X699825D03*
X706125D03*
X699825Y430612D03*
X706125Y462108D03*
X709274D03*
X712424D03*
X709274Y449510D03*
X699825D03*
X706125D03*
X709274Y452659D03*
X699825Y458959D03*
X706125D03*
X709274D03*
X712424D03*
X699825Y462108D03*
X709274Y474707D03*
Y471557D03*
Y465258D03*
Y468407D03*
X712424Y474707D03*
Y468407D03*
Y465258D03*
X706125Y471557D03*
Y468407D03*
X699825Y471557D03*
Y474707D03*
X706125Y477856D03*
X699825Y465258D03*
X712424Y471557D03*
X706125Y481006D03*
X709899Y766798D03*
X709999Y1258727D03*
X708090Y1262074D03*
X705037Y1252034D03*
X706493Y1256563D03*
X705167Y1262074D03*
X709977Y1264985D03*
X721873Y427462D03*
X725022D03*
X728172Y418013D03*
X718723D03*
X715574Y427462D03*
X728172Y421163D03*
X718723Y414864D03*
X725022Y424313D03*
X721873D03*
X725022Y421163D03*
X728172Y427462D03*
X731322Y421163D03*
X725022Y418013D03*
X718723Y427462D03*
Y424313D03*
Y421163D03*
X715574Y424313D03*
Y421163D03*
Y418013D03*
X728172Y424313D03*
X718723Y436911D03*
X721873Y433761D03*
Y436911D03*
Y440061D03*
Y430612D03*
X718723Y433761D03*
Y440061D03*
X725022Y436911D03*
Y433761D03*
X728172D03*
X718723Y430612D03*
X715574D03*
X725022D03*
X728172Y436911D03*
X715574D03*
Y440061D03*
Y443210D03*
X728172D03*
Y430612D03*
X725022Y440061D03*
X718723Y443210D03*
X721873D03*
X725022D03*
X728172Y440061D03*
X731322D03*
X728172Y455809D03*
Y458959D03*
X718723Y455809D03*
X721873Y458959D03*
Y452659D03*
X725022D03*
X728172D03*
X715574Y462108D03*
X725022Y458959D03*
X721873Y455809D03*
X725022Y462108D03*
X718723Y452659D03*
X715574Y449510D03*
Y452659D03*
Y455809D03*
X728172Y462108D03*
X718723Y449510D03*
X721873D03*
X725022D03*
X718723Y458959D03*
X721873Y462108D03*
X718723D03*
X725022Y468407D03*
X721873Y465258D03*
Y477856D03*
X718723Y468407D03*
X715574Y474707D03*
Y471557D03*
Y468407D03*
Y465258D03*
X718723Y474707D03*
Y471557D03*
X728172Y477856D03*
X721873Y471557D03*
X725022D03*
X718723Y465258D03*
X728172D03*
X725022Y474707D03*
X728172Y468407D03*
X721873Y474707D03*
Y468407D03*
X728172Y474707D03*
Y471557D03*
X725022Y465258D03*
X718723Y477856D03*
X725132Y481116D03*
X728272Y481006D03*
X726041Y957546D03*
Y954200D03*
Y994357D03*
X726141Y1057940D03*
Y1255381D03*
X723700Y1258727D03*
X726141Y1248688D03*
Y1262074D03*
X726107Y1265420D03*
X734471Y418013D03*
X731322Y427462D03*
Y418013D03*
X734471Y421163D03*
X731322Y424313D03*
X734471D03*
X737621D03*
X731322Y414864D03*
Y433761D03*
X734471Y436911D03*
X731322D03*
X734471Y443210D03*
X737621D03*
X731322D03*
Y455809D03*
X737621Y458959D03*
X731322D03*
X734471Y452659D03*
X731322D03*
Y449510D03*
X734471Y458959D03*
X731322Y465258D03*
Y477856D03*
X737621Y471557D03*
X734471Y468407D03*
X731322D03*
X731321Y474707D03*
X731322Y471557D03*
X734471Y481006D03*
X739699Y766798D03*
Y1061286D03*
Y1258727D03*
X734967Y1252034D03*
X737580Y1262074D03*
X739697Y1265420D03*
X755841Y957546D03*
Y954200D03*
Y994357D03*
X755541Y1057940D03*
X750890Y1248500D03*
X755890Y1255381D03*
X753000Y1261352D03*
X755841Y1252034D03*
Y1248688D03*
X750040Y1254179D03*
X755841Y1262074D03*
X755797Y1265420D03*
X769399Y766798D03*
Y1258727D03*
X767080Y1262074D03*
X766148Y1255882D03*
X769399Y1265420D03*
X785541Y957546D03*
Y954200D03*
Y994357D03*
Y1255381D03*
X783130Y1259372D03*
X794157Y1252034D03*
X785541Y1248688D03*
X796880Y1262074D03*
X796280Y1254402D03*
X785541Y1265420D03*
Y1262074D03*
X797417Y767345D03*
X799099Y1061286D03*
Y1258727D03*
X812440D03*
X799099Y1265420D03*
X815241Y957546D03*
Y954200D03*
Y994357D03*
Y1255381D03*
X826750Y1262074D03*
X823877Y1252034D03*
X815241Y1248688D03*
X826501Y1254553D03*
X815241Y1265420D03*
Y1262074D03*
X828699Y766798D03*
X828799Y1258727D03*
X842630Y1256912D03*
X828799Y1265420D03*
X844841Y957546D03*
Y954200D03*
Y994357D03*
X844941Y1258727D03*
Y1252034D03*
X844997Y1248155D03*
X844941Y1265420D03*
Y1262074D03*
X998205Y195735D03*
Y192191D03*
X1000705Y195735D03*
Y192191D03*
X998205Y199278D03*
X1000705D03*
X998205Y202821D03*
X1000705D03*
X1001970Y1251522D03*
X1003831Y1259077D03*
X1002070Y1256942D03*
X1003841Y1265420D03*
Y1262074D03*
X1012769Y766798D03*
X1019983Y994357D03*
X1017900Y1247632D03*
X1019983Y1255381D03*
Y1252034D03*
Y1248688D03*
Y1262074D03*
Y1265420D03*
X1033441Y766798D03*
X1028683Y957546D03*
Y954200D03*
X1033541Y1258727D03*
X1030830Y1261302D03*
X1030270Y1256042D03*
X1033541Y1265420D03*
X1042241Y1061286D03*
X1047010Y1259222D03*
X1049683Y1258727D03*
Y1265420D03*
Y1262074D03*
X1044930Y1263492D03*
X1063141Y766798D03*
X1058383Y957546D03*
Y954200D03*
Y994357D03*
X1063241Y1258727D03*
X1061330Y1262074D03*
X1058383Y1248688D03*
X1059410Y1252272D03*
X1063241Y1265420D03*
X1079383Y994357D03*
X1076520Y1259072D03*
X1079383Y1258727D03*
X1088262Y1252293D03*
X1079383Y1265420D03*
Y1262074D03*
X1092709Y766775D03*
X1088083Y957546D03*
Y954200D03*
X1101641Y1061286D03*
X1090273Y1246800D03*
X1092941Y1258727D03*
X1088083Y1248688D03*
X1091000Y1262074D03*
X1106200Y1250162D03*
X1092941Y1265420D03*
X1103530Y1263602D03*
X1117783Y957546D03*
Y954200D03*
Y994357D03*
Y1057940D03*
X1120800Y1262074D03*
X1117783Y1248688D03*
X1109083Y1265420D03*
X1109050Y1262972D03*
X1106740Y1267902D03*
X1122541Y766798D03*
X1122641Y1258727D03*
X1133200Y1255702D03*
X1122620Y1264622D03*
X1152241Y766798D03*
X1147483Y957546D03*
Y954200D03*
X1138783Y994357D03*
X1152341Y1258727D03*
X1138783Y1255381D03*
Y1258727D03*
Y1252034D03*
X1147483Y1248688D03*
X1150400Y1262074D03*
X1148563Y1257097D03*
X1152341Y1265420D03*
X1138783Y1262027D03*
X1137980Y1264212D03*
X1161041Y1061286D03*
X1168483Y1255381D03*
Y1258727D03*
Y1252034D03*
Y1265420D03*
Y1262074D03*
X1177183Y957546D03*
Y954200D03*
Y994357D03*
X1177120Y1248688D03*
X1177222Y1255567D03*
X1182041Y1265420D03*
X1181850Y1260192D03*
X1179180Y1265872D03*
X1198183Y957546D03*
Y954200D03*
Y994357D03*
Y1252034D03*
X1198180Y1262112D03*
X1196470Y1265382D03*
X1193590Y1267912D03*
X1195470Y1262802D03*
X1211641Y766798D03*
X1213983Y1000437D03*
X1216663Y1000395D03*
X1212533Y1002557D03*
X1205033D03*
X1207533D03*
X1210033D03*
X1208830Y1256692D03*
X1206883Y1248688D03*
X1207048Y1255174D03*
X1211240Y1265502D03*
X1208750Y1266546D03*
X1214132Y1602380D03*
X1202072D03*
X1217532D03*
X1205472D03*
X1227883Y957546D03*
Y954200D03*
Y994357D03*
X1233703Y999608D03*
X1231023Y999650D03*
X1220441Y1061286D03*
X1224189Y1259155D03*
X1226899Y1257968D03*
X1227847Y1251715D03*
X1227670Y1265162D03*
X1225540Y1266402D03*
X1226192Y1602380D03*
X1229592D03*
X1236583Y1057940D03*
Y1248688D03*
X1238252Y1602380D03*
X1241652D03*
X1262372D03*
X1250312D03*
X1265772D03*
X1253712D03*
X1274432D03*
X1277832D03*
X1298552D03*
X1286492D03*
X1289892D03*
X1310612D03*
X1314012D03*
X1301952D03*
X1322672D03*
X1326072D03*
X1346792D03*
X1334732D03*
X1338132D03*
X1358852D03*
X1362252D03*
X1350192D03*
X1370912D03*
X1374312D03*
X1382972D03*
X1386372D03*
X1477755Y1578182D03*
X1462295D03*
X1474355D03*
X1465695D03*
X1489815D03*
X1486415D03*
X1501875D03*
X1498475D03*
X1525995D03*
X1513935D03*
X1522595D03*
X1510535D03*
X1538055D03*
X1534655D03*
X1550115D03*
X1558775D03*
X1546715D03*
X1574235D03*
X1562175D03*
X1570835D03*
X1586295D03*
X1582895D03*
X1605800Y766478D03*
X1601922Y1000198D03*
X1599489Y999665D03*
X1597041Y1061286D03*
X1606481Y1258649D03*
X1608000Y1261662D03*
X1607897Y1264445D03*
X1598355Y1578182D03*
X1607015D03*
X1594955D03*
X1613083Y957546D03*
Y954200D03*
X1616609Y1000735D03*
X1616469Y1003135D03*
X1623539Y1000135D03*
X1620489Y1003135D03*
X1623589Y1002865D03*
X1620399Y1000325D03*
X1621983Y1258727D03*
X1624600Y1262074D03*
X1613183Y1252034D03*
X1613027Y1248805D03*
X1609056Y1250602D03*
X1623930Y1252242D03*
X1613019Y1261235D03*
X1622475Y1578182D03*
X1610415D03*
X1619075D03*
X1626741Y766798D03*
X1626249Y1002825D03*
X1626741Y1258727D03*
X1634535Y1578182D03*
X1631135D03*
X1656441Y766798D03*
X1642783Y957546D03*
Y954200D03*
X1648205Y998632D03*
X1656441Y1061286D03*
X1642883Y1255381D03*
Y1258727D03*
Y1252034D03*
X1651679Y1248885D03*
X1653140Y1257862D03*
X1656188Y1264964D03*
X1642788Y1264464D03*
X1642883Y1262074D03*
X1656170Y1260352D03*
X1654600Y1262742D03*
X1646595Y1578182D03*
X1643195D03*
X1672583Y957546D03*
Y954200D03*
Y994357D03*
Y1255381D03*
Y1258727D03*
Y1248688D03*
X1672188Y1263764D03*
X1686041Y766798D03*
X1686141Y1258727D03*
X1681179Y1252034D03*
X1683578Y1253780D03*
X1686119Y1264985D03*
X1681309Y1262074D03*
X1683500Y1264312D03*
X1702183Y957546D03*
Y954200D03*
Y994357D03*
X1702283Y1057940D03*
X1699852Y1245418D03*
X1699089Y1258842D03*
X1702283Y1248688D03*
X1702249Y1265420D03*
X1702283Y1262074D03*
X1699030Y1263912D03*
X1715841Y766798D03*
Y1061286D03*
X1713620Y1258512D03*
X1711109Y1252034D03*
X1713930Y1262074D03*
X1715839Y1265420D03*
X1737020Y112177D03*
Y109677D03*
X1731983Y957546D03*
Y954200D03*
Y994357D03*
X1731683Y1057940D03*
X1727041Y1248688D03*
X1731983Y1255381D03*
Y1258727D03*
Y1252034D03*
Y1248688D03*
X1731939Y1265420D03*
X1731983Y1262074D03*
X1747650Y109677D03*
Y112177D03*
X1744106Y109677D03*
Y112177D03*
X1740563Y109677D03*
Y112177D03*
X1745541Y766798D03*
Y1258727D03*
X1743710Y1262074D03*
X1742337Y1252300D03*
X1745541Y1265420D03*
X1761683Y957546D03*
Y954200D03*
Y994357D03*
X1756922Y1247632D03*
X1761683Y1255381D03*
Y1258727D03*
X1770299Y1252034D03*
X1761683Y1248688D03*
Y1262074D03*
Y1265420D03*
X1773559Y767345D03*
X1775241Y1061286D03*
Y1258727D03*
X1788219Y1259312D03*
X1773390Y1262074D03*
X1773480Y1253692D03*
X1775241Y1265420D03*
X1788360Y1264522D03*
X1791383Y957546D03*
Y954200D03*
Y994357D03*
X1788373Y1241769D03*
X1800427Y1248125D03*
X1803100Y1262074D03*
X1800019Y1252034D03*
X1791383Y1248688D03*
Y1265420D03*
Y1262074D03*
X1804841Y766798D03*
X1815063Y1233103D03*
X1804941Y1258727D03*
X1813814Y1254693D03*
X1804941Y1265420D03*
X1820983Y957546D03*
Y954200D03*
Y994357D03*
X1830379Y1250358D03*
X1829920Y1258322D03*
X1821139Y1248155D03*
X1821083Y1262074D03*
Y1265420D03*
X1829940Y1263662D03*
G54D29*
X159474Y1328627D03*
X183847Y1328652D03*
X208247D03*
X275289Y583576D03*
Y607735D03*
Y631889D03*
Y656043D03*
X270252Y676260D03*
Y700414D03*
X387897Y1242785D03*
X412297D03*
X436619D03*
X461019D03*
X485419D03*
X673093Y1328652D03*
X697466Y1328677D03*
X721866D03*
X1100800Y259362D03*
X1100700Y283662D03*
X1131100Y1364962D03*
X1155500D03*
X1179900D03*
X1364038Y1242785D03*
X1388438D03*
X1412760D03*
X1437160D03*
X1461560D03*
X1577000Y599762D03*
Y624262D03*
Y648762D03*
Y673162D03*
Y697662D03*
Y722162D03*
X1634259Y1362248D03*
X1658632Y1362273D03*
X1683032D03*
G54D52*
X705760Y-26500D03*
Y-16500D03*
D03*
Y-6500D03*
X730760Y-26500D03*
Y-16500D03*
D03*
Y-6500D03*
X822720Y3500D03*
Y13500D03*
D03*
Y23500D03*
X847720Y3500D03*
Y13500D03*
D03*
Y23500D03*
X973180Y-26500D03*
Y-16500D03*
D03*
Y-6500D03*
Y3500D03*
Y13500D03*
Y23500D03*
Y13500D03*
X998180Y-26500D03*
Y-16500D03*
D03*
Y-6500D03*
Y3500D03*
Y13500D03*
Y23500D03*
Y13500D03*
X1015152Y-26511D03*
Y-36511D03*
Y-26511D03*
Y-16511D03*
D03*
Y-6511D03*
D03*
Y3489D03*
D03*
Y13489D03*
D03*
Y23489D03*
X1040152Y-26511D03*
Y-36511D03*
Y-26511D03*
Y-16511D03*
D03*
Y-6511D03*
D03*
Y3489D03*
D03*
Y13489D03*
D03*
Y23489D03*
X1282572Y-36511D03*
Y-26511D03*
D03*
Y-16511D03*
D03*
Y-6511D03*
Y3489D03*
Y-6511D03*
Y3489D03*
Y13489D03*
Y23489D03*
Y13489D03*
X1307572Y-36511D03*
Y-26511D03*
D03*
Y-16511D03*
D03*
Y-6511D03*
Y3489D03*
Y-6511D03*
Y3489D03*
Y13489D03*
Y23489D03*
Y13489D03*
X1324471Y-26511D03*
Y-36511D03*
Y-26511D03*
Y-16511D03*
D03*
Y-6511D03*
D03*
Y3489D03*
D03*
Y13489D03*
D03*
Y23489D03*
X1349471Y-26511D03*
Y-36511D03*
Y-26511D03*
Y-16511D03*
D03*
Y-6511D03*
D03*
Y3489D03*
D03*
Y13489D03*
D03*
Y23489D03*
X1474931Y-36511D03*
Y-26511D03*
D03*
Y-16511D03*
D03*
Y-6511D03*
Y3489D03*
Y-6511D03*
Y3489D03*
Y13489D03*
Y23489D03*
Y13489D03*
X1499931Y-36511D03*
Y-26511D03*
D03*
Y-16511D03*
D03*
Y-6511D03*
Y3489D03*
Y-6511D03*
Y3489D03*
Y13489D03*
Y23489D03*
Y13489D03*
X1565236Y184783D03*
Y264035D03*
G54D55*
X793879Y194881D03*
X789942Y204724D03*
X793879Y214567D03*
X805690Y188976D03*
Y220472D03*
X817501Y194881D03*
Y214567D03*
X821438Y204724D03*
X841240Y1407480D03*
X832154Y1411244D03*
X828390Y1420330D03*
X832154Y1429416D03*
X841240Y1433180D03*
X850326Y1411244D03*
X854090Y1420330D03*
X850326Y1429416D03*
X1003390Y1420330D03*
X1016240Y1407480D03*
X1007154Y1411244D03*
Y1429416D03*
X1016240Y1433180D03*
X1025326Y1411244D03*
X1029090Y1420330D03*
X1025326Y1429416D03*
X1045847Y194881D03*
X1041910Y204724D03*
X1045847Y214567D03*
X1069469Y194881D03*
X1057658Y188976D03*
X1069469Y214567D03*
X1057658Y220472D03*
X1073406Y204724D03*
G54D11*
X3010Y63308D03*
Y123308D03*
Y163308D03*
Y183308D03*
Y203308D03*
Y223308D03*
Y243308D03*
Y263308D03*
Y283308D03*
Y303308D03*
X10884Y321693D03*
Y341693D03*
Y361693D03*
Y381693D03*
Y401693D03*
Y421693D03*
Y441693D03*
Y461693D03*
Y481693D03*
Y501693D03*
Y521693D03*
Y661693D03*
Y681693D03*
Y701693D03*
Y721693D03*
Y741693D03*
Y781693D03*
Y801693D03*
Y821693D03*
Y841693D03*
Y861693D03*
Y881693D03*
Y901693D03*
Y921693D03*
Y941693D03*
Y961693D03*
Y981693D03*
Y1001693D03*
Y1021693D03*
Y1041693D03*
Y1061693D03*
Y1081693D03*
Y1101693D03*
Y1121693D03*
Y1141693D03*
Y1161693D03*
Y1181693D03*
Y1201693D03*
Y1221693D03*
Y1241693D03*
Y1401693D03*
Y1421693D03*
Y1441693D03*
Y1461693D03*
Y1481693D03*
Y1501693D03*
Y1521693D03*
Y1541693D03*
Y1561693D03*
Y1581693D03*
X26615Y670036D03*
X28601Y1617541D03*
Y1637541D03*
Y1657541D03*
Y1677541D03*
X38220Y595862D03*
X54593Y19183D03*
X87565Y670441D03*
X94473Y698926D03*
X127313Y649765D03*
X114021Y669409D03*
X118021D03*
X127738Y659226D03*
X117220Y1680287D03*
X130067Y650213D03*
X134205Y643603D03*
X128193Y662015D03*
X128275Y665515D03*
X190800Y675662D03*
X219752Y1405499D03*
Y1401999D03*
Y1398599D03*
X259845Y461117D03*
X282640Y214102D03*
X301751Y127466D03*
Y124466D03*
Y121466D03*
X311758Y124469D03*
Y121469D03*
Y127469D03*
X313995Y237724D03*
X335285Y210609D03*
X332285D03*
X325755Y230719D03*
X338985Y229509D03*
X325855Y227619D03*
X325055Y237219D03*
X328965Y237214D03*
X332465D03*
X381068Y1674824D03*
X373320Y1688202D03*
X388220Y1631404D03*
X445944Y359053D03*
X446730Y382432D03*
X443744Y429553D03*
X451421D03*
X443744Y452462D03*
X437520Y484837D03*
X447520D03*
X442520D03*
X451520D03*
X448079Y1562177D03*
X443910Y1555602D03*
X450020Y1570412D03*
X453621Y359053D03*
X462720Y404762D03*
X465421Y424928D03*
X466520Y475812D03*
X456520Y484837D03*
X461520D03*
X456961Y1559697D03*
X456020Y1580412D03*
X464020D03*
X462079Y1572177D03*
X454661Y1596755D03*
X459779Y1609235D03*
X480393Y429412D03*
X479169Y484696D03*
X474169D03*
X484169D03*
X478308Y1439986D03*
X502070Y424787D03*
X488070Y429412D03*
X498169Y484696D03*
X493169D03*
X488169D03*
X513444Y473281D03*
X503169Y475671D03*
X550024Y369123D03*
Y401023D03*
X557701Y369123D03*
X649218Y504277D03*
X641386Y1687283D03*
X661534Y41748D03*
X656877Y514716D03*
X661743Y521166D03*
X657734Y528255D03*
X656725Y1657619D03*
X669004Y41698D03*
X694720Y491962D03*
X690720D03*
X702462Y1673258D03*
X725537Y-23978D03*
Y-19022D03*
Y-13978D03*
Y-9022D03*
X719194Y172909D03*
X714202D03*
X719194Y177865D03*
X714202D03*
X719194Y184909D03*
X714202D03*
X719194Y189865D03*
X714202D03*
X719194Y196409D03*
X714202D03*
X719194Y201365D03*
X714202D03*
X719194Y208243D03*
X714202D03*
X719194Y213199D03*
X714202D03*
X714203Y1639776D03*
X745685Y265322D03*
Y269322D03*
X742655Y1682362D03*
Y1678362D03*
X761720Y283262D03*
X748085Y278942D03*
X758360Y276122D03*
X755859Y1686090D03*
X755183Y1709850D03*
X764850Y249792D03*
X763359Y1729520D03*
X785135Y281822D03*
Y267822D03*
X842497Y6022D03*
Y16022D03*
Y20978D03*
Y10978D03*
X908675Y455386D03*
X913913Y455396D03*
X957420Y153699D03*
X960420D03*
X968022Y1620730D03*
X965022D03*
X971022D03*
X965022Y1632730D03*
X968022Y1629730D03*
X965022D03*
X968022Y1626730D03*
X965022D03*
Y1623730D03*
X968022D03*
X971022Y1626730D03*
Y1623730D03*
Y1629730D03*
Y1632730D03*
X968022D03*
X981445Y181058D03*
X1002735Y153943D03*
X999735D03*
X999915Y180548D03*
X996415D03*
X992505Y180553D03*
X993205Y174053D03*
X993305Y170953D03*
X990495Y212923D03*
X1001065Y304622D03*
Y307122D03*
Y309622D03*
X996662Y1620870D03*
X999662D03*
X1002662D03*
Y1626870D03*
Y1623870D03*
X996662Y1629870D03*
X999662Y1626870D03*
X996662D03*
Y1623870D03*
X999662D03*
X996662Y1632870D03*
X1021908Y60392D03*
Y120392D03*
X1015300Y148736D03*
X1012187Y148749D03*
X1006435Y172843D03*
X1009895Y192359D03*
X1008067Y194356D03*
X1019935Y206463D03*
Y203333D03*
X1010828Y304822D03*
Y307322D03*
Y309822D03*
X1034929Y-33989D03*
Y-29033D03*
Y-13989D03*
Y-9033D03*
Y-23989D03*
Y-19033D03*
Y-3989D03*
Y967D03*
X1036915Y290969D03*
X1035920Y428962D03*
X1034252Y1623870D03*
Y1626870D03*
X1031252Y1623870D03*
Y1626870D03*
X1028252Y1623870D03*
Y1626870D03*
X1031252Y1620870D03*
X1034252D03*
X1028252D03*
X1065721Y1633043D03*
X1068721D03*
Y1624043D03*
Y1627043D03*
Y1630043D03*
X1065721Y1624043D03*
Y1627043D03*
Y1630043D03*
X1062721Y1633043D03*
Y1624043D03*
Y1627043D03*
Y1630043D03*
X1059721Y1633043D03*
Y1624043D03*
Y1627043D03*
Y1630043D03*
X1068721Y1621043D03*
X1065721D03*
X1062721D03*
X1059721D03*
X1099901Y1633203D03*
Y1624203D03*
Y1627203D03*
Y1630203D03*
Y1621203D03*
X1093901Y1633203D03*
X1096901D03*
Y1624203D03*
Y1627203D03*
Y1630203D03*
X1093901Y1624203D03*
Y1627203D03*
Y1630203D03*
X1090901Y1633203D03*
X1087901D03*
X1090901Y1624203D03*
X1087901D03*
Y1627203D03*
X1090901D03*
X1087901Y1630203D03*
X1090901D03*
X1096901Y1621203D03*
X1093901D03*
X1087901D03*
X1090901D03*
X1132142Y1555301D03*
X1120472Y1615010D03*
X1127377Y1628485D03*
X1131632Y1625969D03*
X1148220Y501362D03*
X1139392Y1620851D03*
X1172720Y527862D03*
X1202600Y759662D03*
X1245574Y234042D03*
X1245593Y241462D03*
Y237462D03*
X1280223Y256841D03*
X1279841Y253052D03*
X1344248Y-33989D03*
Y-29033D03*
Y-13989D03*
Y-9033D03*
Y-23989D03*
Y-19033D03*
Y-3989D03*
Y967D03*
X1412954Y138742D03*
X1404402D03*
X1409716Y171696D03*
X1418268D03*
X1454829Y1439732D03*
X1465179Y213102D03*
X1477700Y236522D03*
X1466292Y631634D03*
X1473228D03*
X1486884Y374338D03*
X1479207D03*
X1478203Y406207D03*
X1493384Y419263D03*
X1481384Y419392D03*
X1505378Y225502D03*
X1509571Y239053D03*
X1507860Y249792D03*
X1513110Y247412D03*
X1522883Y305187D03*
X1526216Y306909D03*
X1529002Y32290D03*
X1528716Y306909D03*
X1533716D03*
X1536216D03*
X1534899Y310447D03*
X1559387Y589340D03*
X1564690Y663302D03*
X1619980Y590685D03*
X1615800Y584062D03*
X1620170Y623762D03*
X1622770D03*
X1612980D03*
X1620170Y626362D03*
X1622770D03*
X1612980D03*
X1615580Y650092D03*
Y657762D03*
X1620170D03*
X1622770D03*
X1622109Y652469D03*
X1619509D03*
X1612980Y657762D03*
Y650092D03*
X1615580Y660362D03*
X1620170D03*
X1622770D03*
X1612980D03*
X1622109Y686469D03*
X1619509D03*
X1615580Y684092D03*
X1612980D03*
X1622770Y691762D03*
Y694362D03*
X1620170Y691762D03*
Y694362D03*
X1615580D03*
X1612980D03*
X1615580Y691762D03*
X1612980D03*
X1619509Y720469D03*
X1622109D03*
X1612980Y718092D03*
X1615580D03*
X1610100Y725152D03*
X1637667Y587844D03*
Y590444D03*
X1629867D03*
Y587844D03*
X1632467Y590444D03*
Y587844D03*
X1635067Y590444D03*
Y587844D03*
X1626606Y616576D03*
X1629206D03*
X1631806D03*
X1634406D03*
X1637006D03*
X1639606D03*
X1630570Y623762D03*
X1627970D03*
X1625370D03*
X1636412Y638451D03*
X1636417Y630007D03*
X1640061Y639497D03*
X1636412Y641051D03*
X1630570Y626362D03*
X1627970D03*
X1625370D03*
X1630198Y638651D03*
Y636051D03*
Y641251D03*
X1633305Y638651D03*
Y641251D03*
X1630198Y632851D03*
X1630214Y629907D03*
X1633321D03*
X1640061Y644457D03*
Y641977D03*
X1630570Y657762D03*
X1627970D03*
X1625370D03*
X1629909Y652469D03*
X1632509D03*
X1624709D03*
X1627309D03*
X1630198Y643851D03*
X1633305Y646451D03*
Y643851D03*
X1630198Y646451D03*
X1636412Y672451D03*
X1636417Y664007D03*
X1640061Y673497D03*
X1630570Y660362D03*
X1627970D03*
X1625370D03*
X1630198Y672651D03*
Y670051D03*
X1633305Y672651D03*
X1630198Y666851D03*
X1630214Y663907D03*
X1633321D03*
X1629909Y686469D03*
X1632509D03*
X1624709D03*
X1627309D03*
X1640061Y678457D03*
Y675977D03*
X1636412Y675051D03*
X1630198Y677851D03*
Y675251D03*
X1633305Y680451D03*
Y675251D03*
Y677851D03*
X1630198Y680451D03*
X1636417Y698007D03*
X1636412Y706451D03*
X1630214Y697907D03*
X1633321D03*
X1630198Y704051D03*
Y706651D03*
X1633305D03*
X1630198Y700851D03*
X1625370Y691762D03*
Y694362D03*
X1630570D03*
Y691762D03*
X1627970D03*
Y694362D03*
X1640061Y707497D03*
Y712457D03*
Y709977D03*
X1636412Y709051D03*
X1632509Y720469D03*
X1627309D03*
X1629909D03*
X1624709D03*
X1633305Y711851D03*
Y709251D03*
X1630198D03*
Y711851D03*
X1633305Y714451D03*
X1630198D03*
X1642873Y604206D03*
Y607206D03*
X1645625Y600495D03*
Y603295D03*
X1642873Y601206D03*
Y598206D03*
X1645625Y597795D03*
Y594995D03*
X1642873Y595006D03*
X1642340Y618546D03*
X1642873Y610206D03*
X1645661Y639497D03*
X1656550Y653086D03*
X1645661Y644457D03*
Y641977D03*
Y673497D03*
X1656550Y687086D03*
X1645661Y678457D03*
Y675977D03*
Y707497D03*
Y709977D03*
Y712457D03*
X1665700Y583462D03*
X1661510Y583442D03*
X1672770Y580512D03*
X1669770D03*
X1663720Y620434D03*
X1659914Y649681D03*
Y683681D03*
Y717681D03*
X1686154Y434160D03*
X1704444Y407045D03*
X1697914Y427155D03*
X1698014Y424055D03*
X1701124Y433650D03*
X1697214Y433655D03*
X1704624Y433650D03*
X1717280Y174970D03*
X1707444Y407045D03*
X1711144Y425945D03*
X1765870Y179392D03*
X1780320Y177602D03*
G54D14*
X26054Y195148D03*
X25752Y203274D03*
X24754Y220220D03*
X24814Y236472D03*
X35600Y227380D03*
X45182Y426310D03*
X45034Y449106D03*
X62833Y410047D03*
X62808Y418425D03*
X50138Y426310D03*
X60393D03*
X49990Y449106D03*
X73020Y28406D03*
Y40020D03*
X65349Y426310D03*
X75516Y436519D03*
X73865Y763164D03*
X94279Y28406D03*
X87193D03*
X80106D03*
X94279Y40020D03*
X87193D03*
X80106D03*
X85826Y424319D03*
Y420319D03*
X82661Y449604D03*
X79451Y699517D03*
X92895Y1737108D03*
X108453Y28406D03*
X101366D03*
X108453Y40020D03*
X101366D03*
X104220Y400862D03*
X101720D03*
X113597Y488434D03*
X102152Y509374D03*
X102334Y500628D03*
X102359Y497374D03*
X102152Y513374D03*
X108909Y654926D03*
X102909Y648926D03*
Y642926D03*
Y655102D03*
X108909Y642926D03*
X122626Y28406D03*
X115539D03*
X122626Y40020D03*
X115539D03*
X125007Y392071D03*
Y388071D03*
Y384071D03*
Y396071D03*
X114507Y404571D03*
X117597Y488434D03*
X114909Y654926D03*
Y648926D03*
Y642926D03*
X116798Y1617262D03*
X112895Y1737108D03*
X129713Y28406D03*
Y40020D03*
X136301Y179095D03*
X143340Y204622D03*
X140974Y396885D03*
Y401885D03*
Y399385D03*
X142166Y490835D03*
X144263Y1412275D03*
X138492Y1717592D03*
X132895Y1737108D03*
X158492Y28406D03*
X151405D03*
X158492Y40020D03*
X151405D03*
X147901Y188852D03*
X159125Y448664D03*
X152171Y490615D03*
X149472Y502810D03*
X149486Y498810D03*
X149518Y522810D03*
X159898Y1360790D03*
X152895Y1737108D03*
X172665Y28406D03*
X165579D03*
X172665Y40020D03*
X165579D03*
X175640Y453779D03*
X162398Y1360790D03*
X164898D03*
X172895Y1737108D03*
X166761Y1732967D03*
X179752Y28406D03*
Y40020D03*
X184490Y402203D03*
X191305Y430216D03*
X188221Y454048D03*
X184147Y447078D03*
X192895Y1737108D03*
X202626Y28406D03*
X195539D03*
X202626Y40020D03*
X195539D03*
X199047Y428626D03*
X199139Y422882D03*
X196215Y447565D03*
X194858Y684348D03*
X203441Y1360790D03*
X198041D03*
X200941D03*
X223886Y28406D03*
X216799D03*
X209713D03*
X223886Y40020D03*
X216799D03*
X209713D03*
X223330Y426467D03*
X220843Y430004D03*
X220874Y442079D03*
X224137Y1414345D03*
X224077Y1416975D03*
X224350Y1432032D03*
X212895Y1737108D03*
X230972Y28406D03*
Y40020D03*
X242215Y151788D03*
X253000Y28362D03*
X256500D03*
X249500D03*
X252195Y144320D03*
X257434Y415896D03*
X252895Y1737108D03*
X260000Y28362D03*
X258746Y407842D03*
X260807Y424403D03*
X270322Y740207D03*
X272895Y1737108D03*
X286071Y28406D03*
X278984D03*
X279277Y99183D03*
X289557Y121803D03*
X280687Y140746D03*
X284482Y569548D03*
X286582Y630757D03*
X305025Y144202D03*
X302891Y141811D03*
X292895Y1737108D03*
X324733Y148598D03*
X321119Y1313108D03*
X317119D03*
X313119D03*
X330417Y380482D03*
X336370Y406302D03*
X325119Y1313108D03*
X328915Y1326704D03*
X331515D03*
X332895Y1737108D03*
X344776Y148462D03*
X343411Y363143D03*
Y375364D03*
X343354Y387988D03*
X343720Y400628D03*
X339769Y1299868D03*
X342769D03*
X352895Y1737108D03*
X366675Y158702D03*
X364179Y394596D03*
X371066Y400628D03*
X369690Y431812D03*
X365970Y444662D03*
X361769Y1300008D03*
X364769D03*
X383140Y119822D03*
X375330Y121182D03*
X374981Y131433D03*
X376770Y387272D03*
X385520Y429262D03*
X373190Y438342D03*
X384510Y438662D03*
X385730Y460922D03*
X382860Y471122D03*
X383239Y1286578D03*
X378069Y1286568D03*
X375069D03*
X386239Y1286578D03*
X372895Y1737108D03*
X403700Y402422D03*
X390892Y406863D03*
X403260Y439352D03*
X391150Y445302D03*
X396570Y472602D03*
X391360Y495712D03*
X402780Y499372D03*
X394860Y518812D03*
X403200Y572622D03*
X396139Y1286708D03*
X399139D03*
X400926Y1402207D03*
X391249Y1401048D03*
X396921Y1549810D03*
X396946Y1560810D03*
X419012Y368762D03*
X418602Y394722D03*
X417010Y439352D03*
X415130Y480202D03*
X410532Y1153341D03*
X407948Y1153370D03*
Y1161570D03*
X410532Y1161541D03*
X407948Y1169597D03*
X410532D03*
X429050Y117491D03*
X430980Y132672D03*
X432006Y363644D03*
X431596Y389604D03*
X424980Y439462D03*
X427790Y500862D03*
X427880Y506442D03*
X428510Y515842D03*
X436822Y1161570D03*
Y1153370D03*
X431722D03*
Y1161570D03*
X434272Y1153370D03*
Y1161570D03*
X436822Y1170070D03*
X431722D03*
X434272D03*
X430999Y1286758D03*
X423229D03*
X426229D03*
X433999D03*
X436920Y1541562D03*
X422566Y1550046D03*
X432996Y1558322D03*
X436840Y1632682D03*
X436880Y1622442D03*
X432895Y1737108D03*
X447100Y1622562D03*
X447020Y1632632D03*
X452895Y1737108D03*
X465236Y293823D03*
X467736Y312938D03*
X455326Y520389D03*
X457196Y1161570D03*
X459696D03*
X462196D03*
X459696Y1153370D03*
X457196D03*
X462196D03*
X459696Y1170070D03*
X462196D03*
X457196D03*
X460049Y1286978D03*
X463049D03*
X469019Y1286718D03*
X465749Y1401238D03*
X455602Y1412334D03*
X473870Y506622D03*
X474220Y572782D03*
X471940Y597532D03*
X483030Y1153370D03*
Y1161570D03*
Y1170070D03*
X474509Y1286848D03*
X481509D03*
X477509D03*
X484509D03*
X475285Y1395402D03*
X477835Y1673462D03*
Y1685462D03*
X472895Y1737108D03*
X498636Y293123D03*
X501136Y312238D03*
X486861Y309398D03*
X490759Y1291978D03*
X495309Y1300058D03*
X498309D03*
X492895Y1737108D03*
X517914Y42257D03*
X517902Y49194D03*
X510815D03*
X517989Y1300108D03*
X514989D03*
X508881Y1404880D03*
X506181D03*
X503559Y1405025D03*
X508775Y1409889D03*
X508828Y1407385D03*
X508802Y1412420D03*
X506075Y1409889D03*
X506128Y1407385D03*
X503572Y1407539D03*
Y1415039D03*
Y1412539D03*
X506102Y1412420D03*
X503572Y1410039D03*
X512895Y1737108D03*
X525000Y42257D03*
X524988Y49194D03*
X532533Y299500D03*
X529533D03*
X526941Y447802D03*
X521561Y550819D03*
X526280Y569122D03*
X520710Y592552D03*
X532895Y1737108D03*
X549610Y120682D03*
X535290Y572932D03*
X543450Y590262D03*
X562780Y32842D03*
X564430Y45132D03*
X565849Y1346968D03*
X552895Y1737108D03*
X578620Y45112D03*
X573849Y1346968D03*
X569849D03*
X572895Y1737108D03*
X596840Y45152D03*
X593925Y49193D03*
X590350Y294402D03*
X607890Y34389D03*
X615420Y42342D03*
X605060Y42402D03*
X615185Y49193D03*
X611310Y266272D03*
X612895Y1737108D03*
X621740Y265952D03*
X632895Y1737108D03*
X661681Y49193D03*
X654595D03*
X652895Y1737108D03*
X675854Y49193D03*
X668768D03*
X673517Y1360815D03*
X676017D03*
X678517D03*
X671112Y1639962D03*
X672895Y1737108D03*
X697122Y1632667D03*
X683592Y1634844D03*
X697197Y1644667D03*
X712433Y103308D03*
X712060Y1360815D03*
X722580Y49182D03*
X724133Y141288D03*
X713820Y488762D03*
Y484662D03*
X714560Y1360815D03*
X717060D03*
X744800Y1664840D03*
X732895Y1737108D03*
X762198Y129684D03*
Y126684D03*
X758110Y172636D03*
X752895Y1737108D03*
X777283Y320892D03*
X772208Y1731911D03*
X792208D03*
X810781Y372615D03*
X821164Y372312D03*
X812208Y1731911D03*
X836502Y161553D03*
X837975Y210064D03*
X832208Y1731911D03*
X856776Y129268D03*
X846846Y127064D03*
X851895Y160262D03*
X849710Y212062D03*
X845220Y216532D03*
X854706Y229878D03*
X852206D03*
X856842Y410760D03*
X852208Y1731911D03*
X874295Y163862D03*
X863488Y176332D03*
X872208Y1731911D03*
X886280Y174085D03*
X887671Y487831D03*
Y494767D03*
X878931Y509051D03*
X878941Y503813D03*
X892208Y1731911D03*
X899625Y473856D03*
X893321Y480293D03*
X893311Y485531D03*
X893572Y503050D03*
Y496114D03*
X920246Y184138D03*
X914550Y239924D03*
X923403Y983327D03*
X923322Y990227D03*
X921880Y1525110D03*
X924380D03*
X921880Y1527610D03*
X924380D03*
X912208Y1731911D03*
X935496Y195925D03*
Y203012D03*
Y210098D03*
Y217185D03*
Y224272D03*
Y231358D03*
X940596Y498648D03*
X939097Y527257D03*
X939282Y534020D03*
X930233Y983298D03*
X930274Y990237D03*
X939380Y1525110D03*
X926880D03*
X929380D03*
X931880D03*
X934380D03*
X936880D03*
X926880Y1527610D03*
X929380D03*
X931880D03*
X934380D03*
X936880D03*
X939380D03*
X932208Y1731911D03*
X947190Y527330D03*
X952208Y1731911D03*
X972208D03*
X989910Y-27961D03*
X989925Y-25446D03*
X983632Y-26655D03*
X989925Y-21572D03*
X983632Y-16626D03*
X989910Y-17932D03*
X989925Y-15417D03*
Y-11543D03*
X989910Y-7903D03*
X989925Y-5388D03*
X983632Y-6597D03*
X989925Y4641D03*
X989910Y2126D03*
X983632Y3432D03*
X989925Y14670D03*
X989910Y12155D03*
X989925Y8515D03*
X983632Y13461D03*
X989925Y19044D03*
X983632Y23990D03*
X987259Y276094D03*
X998500Y269862D03*
X1002500D03*
X992208Y1731911D03*
X1014500Y269862D03*
X1018000D03*
X1006500D03*
X1010500D03*
X1021419Y305704D03*
X1012208Y1731911D03*
X1032208D03*
X1053028Y246518D03*
X1053428Y261118D03*
X1052208Y1731911D03*
X1058028Y246518D03*
X1055528D03*
X1068093Y265503D03*
X1058428Y261118D03*
X1055928D03*
X1067618Y273800D03*
X1070718Y273700D03*
X1067718Y285600D03*
X1070618D03*
X1072208Y1731911D03*
X1102561Y78461D03*
X1117574Y1448604D03*
X1111866Y1737108D03*
X1135709Y1397119D03*
X1133209D03*
X1127008Y1524203D03*
X1135748Y1524187D03*
X1131866Y1737108D03*
X1138209Y1397119D03*
X1170337Y607327D03*
X1171752Y1397119D03*
X1176752D03*
X1174252D03*
X1179922Y1524203D03*
X1201110Y1681767D03*
X1191866Y1737108D03*
X1211866D03*
X1231866D03*
X1253586Y1334649D03*
X1257586D03*
X1251866Y1737108D03*
X1276745Y125850D03*
X1275807Y132922D03*
X1281600Y137962D03*
X1282568Y212722D03*
X1272707Y1334865D03*
X1271866Y1737108D03*
X1293024Y-36695D03*
Y-26666D03*
Y-16637D03*
Y-6608D03*
Y3421D03*
Y13450D03*
Y23979D03*
X1291280Y58262D03*
X1293860Y58312D03*
X1284930Y124922D03*
X1285793Y141562D03*
X1288258Y145501D03*
X1283781Y149115D03*
Y155788D03*
X1283425Y179272D03*
X1283397Y202085D03*
X1295150Y1323217D03*
X1298150D03*
X1291010Y1323307D03*
X1288010D03*
X1291866Y1737108D03*
X1299317Y-35486D03*
Y-31612D03*
X1299302Y-38001D03*
Y-27972D03*
X1299317Y-25457D03*
Y-21583D03*
X1299302Y-17943D03*
X1299317Y-15428D03*
Y-11554D03*
X1299302Y-7914D03*
X1299317Y-5399D03*
Y4630D03*
X1299302Y2115D03*
X1299317Y-1525D03*
Y14659D03*
X1299302Y12144D03*
X1299317Y8504D03*
Y19033D03*
X1304066Y1323578D03*
X1307656Y1326704D03*
X1305056D03*
X1311866Y1737108D03*
X1323958Y146227D03*
X1333811Y235348D03*
X1338652Y536654D03*
Y543590D03*
X1337663Y1301001D03*
X1340663D03*
X1331866Y1737108D03*
X1349704Y145385D03*
X1357888Y145893D03*
X1361111Y236448D03*
X1353982Y1287048D03*
X1362382D03*
X1359382D03*
X1350982D03*
X1351866Y1737108D03*
X1366868Y147341D03*
X1369593Y147462D03*
X1369916Y154132D03*
X1379969Y176330D03*
X1370586Y176366D03*
X1370405Y186938D03*
X1369479Y208384D03*
X1370636Y227292D03*
X1369410Y224504D03*
X1375463Y1287048D03*
X1372463D03*
X1376666Y1402778D03*
X1376686Y1399758D03*
X1371866Y1737108D03*
X1384173Y1161549D03*
X1384089Y1153369D03*
X1386673Y1161520D03*
Y1153340D03*
X1384173Y1169599D03*
X1386673Y1169570D03*
X1391866Y1737108D03*
X1407613Y177159D03*
X1398770D03*
X1402258Y184263D03*
X1411101D03*
X1407913Y1161569D03*
X1410413Y1153369D03*
X1407913D03*
X1410613Y1161569D03*
X1407913Y1170069D03*
X1410613D03*
X1410819Y1287198D03*
X1407819D03*
X1399419D03*
X1402419D03*
X1411866Y1737108D03*
X1420222Y184263D03*
X1429250Y1623391D03*
X1419270Y1631000D03*
X1429382Y184263D03*
X1430000Y220018D03*
X1435387Y1161569D03*
X1435837Y1153369D03*
X1432887Y1161569D03*
X1433337Y1153369D03*
X1435387Y1170069D03*
X1432887D03*
X1437258Y1287198D03*
X1445106Y1287158D03*
X1440258Y1287198D03*
X1431829Y1412370D03*
X1443325Y1410068D03*
X1431717Y1424125D03*
X1441800Y1620300D03*
Y1632900D03*
X1431866Y1737108D03*
X1458911Y1161569D03*
Y1170069D03*
X1453366Y1287198D03*
X1458766D03*
X1461766D03*
X1450366D03*
X1474180Y1300407D03*
X1471180D03*
X1491661Y-27972D03*
X1491676Y-25457D03*
X1485383Y-26666D03*
X1491661Y-38001D03*
X1491676Y-35486D03*
Y-31612D03*
X1485383Y-36695D03*
X1491661Y-17943D03*
X1491676Y-15428D03*
Y-11554D03*
X1485383Y-16637D03*
X1491676Y-21583D03*
X1485383Y3421D03*
X1491661Y2115D03*
X1491676Y4630D03*
X1491661Y-7914D03*
X1491676Y-5399D03*
Y-1525D03*
X1485383Y-6608D03*
X1491676Y14659D03*
X1491661Y12144D03*
X1485383Y13450D03*
X1491676Y8504D03*
Y19033D03*
X1485383Y23979D03*
X1487058Y281456D03*
X1484958Y289656D03*
X1487658D03*
X1484758Y312356D03*
X1487458D03*
X1484858Y305956D03*
X1487558D03*
X1491840Y1300447D03*
X1479658Y1405397D03*
X1485301Y1409442D03*
X1485274Y1406911D03*
X1485380Y1412202D03*
X1479671Y1410411D03*
Y1412911D03*
Y1407911D03*
X1482201Y1409442D03*
X1482174Y1406911D03*
X1482280Y1412202D03*
X1491866Y1737108D03*
X1504602Y312867D03*
X1494840Y1300447D03*
X1511866Y1737108D03*
X1540937Y576522D03*
X1536527Y589012D03*
X1531866Y1737108D03*
X1547429Y28406D03*
X1554515D03*
Y40020D03*
X1547429D03*
X1547312Y579080D03*
X1551866Y1737108D03*
X1561602Y28406D03*
X1568688D03*
Y40020D03*
X1561602D03*
X1575775Y28406D03*
X1582862D03*
X1589948D03*
Y40020D03*
X1582862D03*
X1575775D03*
X1591866Y1737108D03*
X1597035Y28406D03*
X1604122D03*
Y40020D03*
X1597035D03*
X1623881Y117627D03*
X1619980Y615201D03*
X1614116Y1411169D03*
X1611866Y1737108D03*
X1625814Y28406D03*
X1632901D03*
X1639988D03*
X1625814Y40020D03*
X1632901D03*
X1639988D03*
X1637183Y1394411D03*
X1639683D03*
X1634683D03*
X1631866Y1737108D03*
X1654161Y28406D03*
X1647074D03*
Y40020D03*
X1654161D03*
X1652113Y527325D03*
X1652138Y524071D03*
X1651931Y540071D03*
Y536071D03*
X1649291Y556057D03*
X1649149Y607022D03*
X1653929Y604546D03*
X1649139Y604576D03*
X1653736Y607033D03*
X1649117Y602139D03*
X1653930Y602099D03*
X1651866Y1737108D03*
X1669948Y28406D03*
Y40020D03*
X1663376Y515531D03*
X1667376D03*
X1664997Y604762D03*
X1659458Y637149D03*
X1658085Y639511D03*
X1659458Y671149D03*
X1658085Y673511D03*
X1659458Y705149D03*
X1658085Y707511D03*
X1673226Y1394411D03*
X1671866Y1737108D03*
X1677035Y28406D03*
X1684122D03*
X1677035Y40020D03*
X1684122D03*
X1681612Y499290D03*
X1675926Y1394411D03*
X1678426D03*
X1691208Y28406D03*
X1698295D03*
X1705381D03*
X1697824Y39974D03*
X1691208Y40020D03*
X1693987Y230174D03*
Y233174D03*
X1703487Y232174D03*
X1699265Y525507D03*
X1699291Y537507D03*
X1699251Y529507D03*
X1699297Y549507D03*
X1705723Y1583821D03*
X1691866Y1737108D03*
X1711866D03*
X1738200Y193862D03*
X1731866Y1737108D03*
X1753388Y28360D03*
X1754398Y100307D03*
X1752200Y197762D03*
X1748500Y193862D03*
X1745500D03*
X1741200D03*
X1740831Y489362D03*
X1740886Y493960D03*
X1751866Y1737108D03*
X1760475Y28360D03*
X1764678Y122927D03*
X1766880Y234842D03*
Y231842D03*
X1758500Y231822D03*
Y234822D03*
X1755378Y233528D03*
X1782000Y128455D03*
X1771915Y128393D03*
X1782000Y125955D03*
Y123455D03*
X1771915Y125893D03*
Y123393D03*
X1783800Y231762D03*
Y234762D03*
X1775140Y234792D03*
Y231792D03*
X1779226Y275604D03*
X1783563Y273471D03*
X1786089D03*
X1771866Y1737108D03*
X1797663Y269571D03*
X1800189D03*
X1790563Y273471D03*
X1793089D03*
X1802763Y308671D03*
X1795763D03*
X1798289D03*
X1788763D03*
X1791289D03*
X1814349Y269634D03*
X1811823D03*
X1807249D03*
X1804723D03*
X1812349Y308734D03*
X1809823D03*
X1805289Y308671D03*
X1828777Y156520D03*
X1841257Y151402D03*
G54D19*
X20188Y1599396D03*
G54D67*
X1156378Y133866D03*
G54D71*
X1850331Y311946D03*
G54D26*
X60303Y20354D03*
X312921Y24291D03*
X505185Y41142D03*
X757803Y45079D03*
X922441Y237697D03*
X929331Y160413D03*
X1534712Y20354D03*
X1787330Y24291D03*
G54D42*
X337778Y854584D03*
X335924Y857789D03*
X334079Y880219D03*
X332228Y877014D03*
X335928D03*
X334078Y893036D03*
X335928Y896240D03*
X332229Y902649D03*
X332228Y915466D03*
X335928D03*
X332229Y921875D03*
Y941100D03*
X332228Y934692D03*
X335928D03*
X334079Y957122D03*
X335928Y953917D03*
X332228D03*
X332229Y973143D03*
X334079Y976347D03*
X338210Y996480D03*
X332661Y1006093D03*
X338211Y1002888D03*
X332661Y1025318D03*
Y1018910D03*
X338211Y1015705D03*
Y1022114D03*
X332661Y1044544D03*
X338211Y1041340D03*
X334511D03*
X338211Y1060565D03*
X336360Y1082995D03*
X338211Y1111834D03*
Y1105426D03*
Y1124651D03*
X336361Y1115039D03*
Y1127856D03*
X347028Y844971D03*
X345178Y848176D03*
X350727Y844971D03*
X347027Y851380D03*
X343327D03*
X354429D03*
X341478Y854584D03*
X339628Y857789D03*
X347029Y864197D03*
Y857789D03*
X348878Y854584D03*
X345179Y860993D03*
X343327Y857789D03*
X354429Y864197D03*
X350729D03*
X341479Y867401D03*
X348879D03*
X352579D03*
X354429Y877014D03*
X339629D03*
X341479Y873810D03*
X345179Y880219D03*
Y873810D03*
X343329Y877014D03*
X352579Y880219D03*
X350729Y877014D03*
X339629Y883423D03*
X347029D03*
X350729D03*
X352578Y899445D03*
X339629Y896240D03*
Y889832D03*
X348879Y886627D03*
X345179Y893036D03*
X343328Y896240D03*
X352578Y893036D03*
Y886627D03*
X345179Y899445D03*
X348878Y905853D03*
X352578D03*
X341479Y912262D03*
X341478Y905853D03*
X347029Y909057D03*
Y902649D03*
X345179Y912262D03*
X352578D03*
X339629Y915466D03*
X343329D03*
X348878Y925079D03*
X352578D03*
Y918670D03*
X341478Y925079D03*
X347029Y928283D03*
Y921875D03*
X345179Y918670D03*
X341479Y931488D03*
X345179D03*
X352578D03*
X341478Y944304D03*
X352578D03*
X347029Y941100D03*
X348878Y944304D03*
X347029Y947509D03*
X352578Y937896D03*
X339629Y934692D03*
X345179Y937896D03*
X343328Y934692D03*
X348878Y963530D03*
X347029Y960326D03*
X343328D03*
X343329Y966735D03*
X339629D03*
Y953917D03*
X343328D03*
X345179Y957122D03*
X352578D03*
X347029Y966735D03*
X352578Y963530D03*
X341479Y950713D03*
X345179D03*
X352578D03*
X354428Y973143D03*
X339629D03*
X345179Y976347D03*
Y969939D03*
X350729Y973143D03*
X347029Y979552D03*
X352579Y976347D03*
X352578Y969939D03*
X348878Y982756D03*
X352578D03*
X339629Y979552D03*
X343329Y973143D03*
X341911Y1009297D03*
Y1002888D03*
X347461Y999684D03*
X345611Y1009297D03*
X343761Y1006093D03*
X345611Y1002888D03*
X351162Y1006093D03*
X354861D03*
X353011Y1009297D03*
Y1002888D03*
X347461Y1012501D03*
X353011Y1028523D03*
Y1015705D03*
X341911Y1022114D03*
Y1015705D03*
X349311D03*
X347461Y1018910D03*
X345611Y1028523D03*
X343761Y1018910D03*
X345611Y1022114D03*
Y1015705D03*
X353011Y1022114D03*
X343761Y1031727D03*
X347461D03*
X353011Y1034931D03*
Y1047749D03*
X341911Y1041340D03*
X343761Y1038136D03*
X349311Y1034931D03*
X347461Y1038136D03*
X345611Y1041340D03*
X343761Y1044544D03*
X353011Y1041340D03*
X345611Y1047749D03*
X349311Y1054157D03*
X353011Y1060565D03*
Y1054157D03*
X343761Y1057361D03*
Y1050952D03*
X347461D03*
Y1057361D03*
X345611Y1060565D03*
X343761Y1063770D03*
X353011Y1073383D03*
X343761Y1076587D03*
Y1070178D03*
X340062Y1076587D03*
X347461D03*
Y1070178D03*
X349312Y1073383D03*
X345611Y1066974D03*
X353011D03*
X345611Y1079791D03*
X341911D03*
X353011D03*
Y1086200D03*
X349310Y1092609D03*
X347461Y1089404D03*
X345610Y1086200D03*
X343760Y1082995D03*
X340060D03*
X353011Y1092608D03*
X340061Y1095813D03*
X347461Y1108630D03*
X354861D03*
X353011Y1099017D03*
X340061Y1108630D03*
Y1102221D03*
X349311Y1099017D03*
X347461Y1102221D03*
X343761D03*
X340061Y1115039D03*
X349311Y1124651D03*
X349312Y1118243D03*
X345611D03*
X343761Y1115039D03*
X341911Y1124651D03*
X354861Y1115039D03*
X351161Y1121447D03*
Y1115039D03*
X345611Y1137469D03*
Y1131060D03*
X349311D03*
X343761Y1134264D03*
X353011Y1137469D03*
Y1131060D03*
X361829Y851380D03*
X358129D03*
X365529Y864197D03*
X361829D03*
X359979Y854584D03*
X358129Y864197D03*
X369229D03*
X367379Y854584D03*
X359979Y867401D03*
X367379D03*
X365529Y877014D03*
X361829D03*
X358129D03*
X369229D03*
X367379Y880219D03*
X356278Y886627D03*
X365529Y896240D03*
Y889832D03*
X361828Y896240D03*
X361829Y889832D03*
X359979Y893036D03*
X358128Y889832D03*
X369229Y896240D03*
Y889832D03*
X356278Y905853D03*
X365529Y909057D03*
Y902649D03*
X359978Y912262D03*
X358128Y909057D03*
X358129Y902649D03*
X371079Y912262D03*
X365529Y915466D03*
X361828D03*
X369229D03*
X356279Y925079D03*
X365529Y928283D03*
Y921875D03*
X358128Y928283D03*
X358129Y921875D03*
X371078Y918670D03*
X359978Y931488D03*
X371079D03*
X358128Y947509D03*
X358129Y941100D03*
X356279Y944304D03*
X365529Y947509D03*
Y934691D03*
X361828D03*
X369229D03*
X356279Y963530D03*
X358129Y960326D03*
X359979Y957122D03*
X358128Y966735D03*
X361829Y953917D03*
X359978Y950713D03*
X371078Y957122D03*
X371079Y950713D03*
X365529Y953917D03*
X367378Y963530D03*
X363679D03*
X365529Y960326D03*
X365528Y966735D03*
X369229Y953917D03*
X359979Y976347D03*
X358129Y979552D03*
X359978Y969939D03*
X361828Y973143D03*
X356279Y982756D03*
X371078Y976347D03*
X371079Y969939D03*
X369229Y973143D03*
X365529Y979552D03*
Y973143D03*
X365962Y999684D03*
Y1006093D03*
X362261D03*
X360411Y1009297D03*
X360412Y1002888D03*
X358562Y999684D03*
X371512Y1009297D03*
X365961Y1012501D03*
X358561D03*
X356712Y1015705D03*
X365962Y1025318D03*
Y1018910D03*
X364112Y1015705D03*
X360411Y1028523D03*
X362261Y1025318D03*
X360412Y1022114D03*
X358562Y1018910D03*
X369662Y1025318D03*
X367811Y1015705D03*
X371511Y1028523D03*
Y1022114D03*
X365962Y1031727D03*
X358561D03*
X356712Y1034931D03*
X365962Y1044544D03*
Y1038136D03*
X362261Y1044544D03*
X360412Y1041340D03*
X358562Y1038136D03*
X369662Y1044544D03*
X371511Y1041340D03*
X360411Y1047749D03*
X371511D03*
X356712Y1054157D03*
X365962Y1057361D03*
Y1050952D03*
X360412Y1060565D03*
X358562Y1057361D03*
X358561Y1050952D03*
X371511Y1060565D03*
X365962Y1063770D03*
X362261D03*
X369662D03*
X356712Y1073383D03*
X365962Y1070178D03*
X360411Y1066974D03*
X358561Y1070178D03*
X358562Y1076587D03*
X371512Y1066974D03*
X360412Y1079791D03*
X371511D03*
X365962Y1089404D03*
Y1082995D03*
X362261D03*
X360411Y1086200D03*
X358561Y1089404D03*
X356712Y1092608D03*
X369662Y1082995D03*
X371512Y1086200D03*
X365962Y1095813D03*
X358561D03*
X365962Y1102221D03*
X362262D03*
X360411Y1099017D03*
X356711Y1105426D03*
Y1099017D03*
X371512Y1105426D03*
Y1099017D03*
X364112Y1111834D03*
X356712D03*
X371512D03*
X364111Y1118243D03*
X362261Y1115039D03*
X360411Y1118243D03*
X356711D03*
X367811D03*
X371511D03*
X365962Y1127856D03*
X358561D03*
X365961Y1140973D03*
X364112Y1131060D03*
X360412D03*
X358561Y1140973D03*
X356712Y1131060D03*
X367811D03*
X371511D03*
X382179Y854584D03*
X380329Y864197D03*
X376629D03*
X374779Y854584D03*
X372929Y864197D03*
X384029D03*
X387729D03*
X382179Y867401D03*
X374779D03*
X382179Y880219D03*
X380329Y877014D03*
X376629D03*
X374779Y880219D03*
X372929Y877014D03*
X384029D03*
X387729D03*
X380329Y889832D03*
X378479Y893036D03*
X376629Y889832D03*
X372929D03*
X384029D03*
X387729Y896240D03*
Y889832D03*
X378478Y899445D03*
X385879D03*
X382179Y905853D03*
X378478Y912262D03*
Y905853D03*
X374778D03*
X372929Y909057D03*
X372928Y902649D03*
X385878Y912262D03*
X384028Y909057D03*
X384029Y902649D03*
X387728Y915466D03*
X382179Y925079D03*
X378478D03*
Y918670D03*
X374778Y925079D03*
X372929Y928283D03*
X372928Y921875D03*
X385879Y918670D03*
X384028Y928283D03*
X384029Y921875D03*
X385878Y931488D03*
X384029Y941100D03*
X384028Y947509D03*
X374778Y944304D03*
X372929Y947509D03*
X372928Y941100D03*
X382179Y944304D03*
X378478D03*
Y937896D03*
X385879D03*
X387728Y934691D03*
X387729Y953917D03*
X372928Y960326D03*
X374778Y963530D03*
X372929Y966735D03*
X382179Y963530D03*
X378478D03*
Y957122D03*
X384029Y960326D03*
X385879Y957122D03*
X384028Y966735D03*
X385878Y950713D03*
X378478D03*
X387728Y973143D03*
X376629D03*
X380328D03*
X378479Y976347D03*
X378478Y969939D03*
X385879Y976347D03*
X384029Y979552D03*
X385878Y969939D03*
X374778Y982756D03*
X382179D03*
X378478D03*
X372928Y979552D03*
X375210Y996480D03*
X373361Y999684D03*
X378911Y1009297D03*
Y1002888D03*
X386311Y1009297D03*
X386312Y1002888D03*
X384462Y999684D03*
X373362Y1012501D03*
X384461D03*
X382612Y1015705D03*
X378911Y1028523D03*
Y1022114D03*
Y1015705D03*
X375211D03*
X373361Y1018910D03*
X386311Y1028523D03*
X386312Y1022114D03*
X384462Y1018910D03*
X373362Y1031727D03*
X384461D03*
X382612Y1034931D03*
X378911Y1041340D03*
Y1034931D03*
X375211D03*
X373361Y1038136D03*
X386312Y1041340D03*
X384462Y1038136D03*
X378911Y1047749D03*
X386311D03*
X382612Y1054157D03*
X378911D03*
X375211D03*
X373361Y1057361D03*
X373362Y1050952D03*
X386312Y1060565D03*
X384462Y1057361D03*
X384461Y1050952D03*
X382612Y1073383D03*
X378911D03*
Y1066974D03*
X375211Y1073383D03*
X373361Y1076587D03*
X373362Y1070178D03*
X386311Y1066974D03*
X384462Y1076587D03*
X384461Y1070178D03*
X378911Y1079791D03*
X386311D03*
X382611Y1092608D03*
X378911D03*
Y1086200D03*
X375211Y1092608D03*
X373362Y1089404D03*
X386311Y1086200D03*
X384461Y1089404D03*
X373362Y1095813D03*
X384462D03*
X380762Y1108630D03*
X378911Y1099017D03*
X377062Y1102221D03*
X373361Y1108630D03*
Y1102221D03*
X386312Y1099017D03*
X384462Y1102221D03*
X382611Y1118243D03*
X378911D03*
X377061Y1115039D03*
X375211Y1118243D03*
X373361Y1115039D03*
X386311Y1118243D03*
X384461Y1115039D03*
X380761Y1127856D03*
X373361D03*
X382611Y1131060D03*
X380761Y1140973D03*
X378911Y1131060D03*
X375211D03*
X373361Y1140973D03*
X386311Y1131060D03*
X396979Y841467D03*
X398829Y851380D03*
X395129D03*
X391429D03*
X402529D03*
X398829Y864197D03*
X396979Y854584D03*
X395129Y864197D03*
X391429D03*
X389579Y854584D03*
X402529Y864197D03*
X396979Y867401D03*
X389579D03*
X398829Y877014D03*
X396979Y880219D03*
X395129Y877014D03*
X391429D03*
X389579Y880219D03*
X402529Y877014D03*
X398829Y889832D03*
X395129Y896240D03*
Y889832D03*
X391428Y896240D03*
X391429Y889832D03*
X389579Y893036D03*
X402529Y889832D03*
X398829Y909057D03*
X398828Y902649D03*
X396979Y912262D03*
X391429Y909057D03*
Y902649D03*
X395129Y915466D03*
X391429D03*
X398829Y928283D03*
X398828Y921875D03*
X396978Y918670D03*
X391429Y928283D03*
Y921875D03*
X400678Y925079D03*
X396979Y931488D03*
X398828Y941100D03*
X395129Y934691D03*
X391429Y941100D03*
Y934691D03*
X400678Y937896D03*
X398829Y947509D03*
X391429D03*
X398828Y960326D03*
X396978Y957122D03*
X396979Y950713D03*
X395129Y953917D03*
X391429Y960326D03*
Y953917D03*
X400678Y957122D03*
X398829Y966735D03*
X391429D03*
X400678Y963530D03*
X398828Y979552D03*
X396978Y976347D03*
X396979Y969939D03*
X395129Y973143D03*
X391429Y979552D03*
Y973143D03*
X400678Y982756D03*
Y969939D03*
X397412Y1009297D03*
X397411Y1002888D03*
X395562Y1006093D03*
X391862D03*
Y999684D03*
X388161Y1006093D03*
X401111Y1002888D03*
X399262Y1012501D03*
X391861D03*
X399261Y1018910D03*
X397411Y1028523D03*
Y1022114D03*
X395562Y1025318D03*
X393711Y1015705D03*
X391862Y1025318D03*
Y1018910D03*
X390012Y1015705D03*
X388161Y1025318D03*
X399262Y1031727D03*
X391862D03*
X399261Y1038136D03*
X397411Y1041340D03*
X395562Y1044544D03*
X391862D03*
Y1038136D03*
X388161Y1044544D03*
X397411Y1047749D03*
X399261Y1057361D03*
X399262Y1050952D03*
X397411Y1060565D03*
X391862Y1057361D03*
Y1050952D03*
X395562Y1063770D03*
X391862D03*
X388161D03*
X399261Y1076587D03*
X399262Y1070178D03*
X397412Y1066974D03*
X391862Y1076587D03*
Y1070178D03*
X401111Y1073383D03*
X397411Y1079791D03*
X401111D03*
X399262Y1089404D03*
X397412Y1086200D03*
X395562Y1082995D03*
X391862Y1089404D03*
Y1082995D03*
X388161D03*
X401112Y1092608D03*
X401111Y1086200D03*
X399261Y1095813D03*
X391862D03*
X402962D03*
X399262Y1102221D03*
X397412Y1099017D03*
X395562Y1102221D03*
X390011Y1105426D03*
X388162Y1108630D03*
Y1102221D03*
X401111Y1105426D03*
X397411Y1111834D03*
X390011D03*
X397411Y1118243D03*
X395561Y1115039D03*
X393711Y1118243D03*
X390011D03*
X388161Y1115039D03*
X401111Y1118243D03*
X395561Y1127856D03*
X388161D03*
X402961D03*
X397411Y1131060D03*
X395561Y1140973D03*
X393711Y1131060D03*
X390011D03*
X388161Y1140973D03*
X402961D03*
X401111Y1131060D03*
X419179Y841467D03*
X404379D03*
X411779D03*
X413629Y851380D03*
X409929D03*
X406229D03*
X417329D03*
X404379Y854584D03*
X413629Y864197D03*
X411779Y854584D03*
X409929Y864197D03*
X406229D03*
X419179Y854584D03*
X417329Y864197D03*
X404379Y867401D03*
X411779D03*
X419179D03*
X404379Y880219D03*
X413629Y877014D03*
X411779Y880219D03*
X409929Y877014D03*
Y870606D03*
X406229Y877014D03*
X419179Y880219D03*
X417329Y877014D03*
X413629Y889832D03*
X411779Y893036D03*
X409929Y889832D03*
X408079Y893036D03*
X406229Y889832D03*
X419179Y893036D03*
X417329Y889832D03*
X413629Y902649D03*
X409929Y909057D03*
Y902649D03*
X404378Y912262D03*
Y905853D03*
X419178Y912262D03*
X419179Y905853D03*
X417329Y902649D03*
X409929Y915466D03*
Y921875D03*
X404378Y918670D03*
X418229Y926896D03*
X419178Y918670D03*
X405048Y930812D03*
X405145Y946239D03*
Y948539D03*
X414093Y942098D03*
X405048Y938046D03*
Y935746D03*
X416393Y942098D03*
X418693D03*
X405122Y965896D03*
Y963596D03*
X414365Y971140D03*
X416755D03*
X404861Y981269D03*
Y978969D03*
Y986421D03*
X405101Y992971D03*
Y995271D03*
X404861Y988721D03*
X405227Y1007156D03*
X405231Y1004848D03*
X417575Y1000060D03*
X415185D03*
X404986Y1022427D03*
X404998Y1026821D03*
X408325Y1031971D03*
Y1034271D03*
X408511Y1041340D03*
X417762Y1044544D03*
X412211Y1047749D03*
X404811D03*
X415911Y1060565D03*
Y1054157D03*
X412211Y1060565D03*
X410361Y1050952D03*
X408511Y1054157D03*
X404811Y1060565D03*
X417761Y1050952D03*
X415911Y1066974D03*
X410362Y1076587D03*
Y1070178D03*
X406661Y1076587D03*
X404811Y1066974D03*
X419611Y1073383D03*
X412211Y1079791D03*
X404811D03*
X415911Y1092608D03*
X415912Y1086200D03*
X412211Y1092608D03*
X408511Y1086200D03*
X417761Y1089404D03*
Y1082995D03*
X410362Y1095813D03*
X406662D03*
X415912Y1099017D03*
X414062Y1108630D03*
X412211Y1099017D03*
X410362Y1102221D03*
X406661Y1108630D03*
Y1102221D03*
X404812Y1105426D03*
X417762Y1102221D03*
X404812Y1111834D03*
X415911Y1118243D03*
X414061Y1121447D03*
X412211Y1124651D03*
Y1118243D03*
X410361Y1115039D03*
X408511Y1118243D03*
X406661Y1115039D03*
X404811Y1118243D03*
X417761Y1115039D03*
X410361Y1127856D03*
X414062Y1134264D03*
X412212Y1131060D03*
X410361Y1140973D03*
X408511Y1131060D03*
X404811D03*
X432128Y844671D03*
X426579Y841467D03*
X432129Y851380D03*
X428429D03*
X424729D03*
X421029D03*
X432129Y864197D03*
X428429D03*
X426579Y854584D03*
X424729Y864197D03*
X421029D03*
X433979Y854584D03*
X426579Y867401D03*
X433979D03*
X432129Y877014D03*
X428429D03*
X426579Y880219D03*
X424729Y877014D03*
X421029D03*
X433979Y880219D03*
X432129Y889832D03*
X428429D03*
X426579Y893036D03*
X424729Y889832D03*
X421029D03*
X433979Y893036D03*
X424729Y902649D03*
X432129D03*
X428429Y909057D03*
Y902649D03*
X421029D03*
X428429Y915466D03*
X433980Y925079D03*
Y931487D03*
X426875Y947199D03*
Y949499D03*
X427875Y936470D03*
X426905Y965935D03*
Y963635D03*
Y980336D03*
Y978036D03*
Y994722D03*
Y992422D03*
Y1006875D03*
Y1009175D03*
Y1021963D03*
Y1019663D03*
X428862Y1044544D03*
X430712Y1047749D03*
X423311D03*
X425162Y1057361D03*
X432561Y1050952D03*
X434411Y1060565D03*
Y1054157D03*
X421462Y1063770D03*
X430711Y1073383D03*
X427011D03*
Y1066974D03*
X425162Y1076587D03*
X423311Y1066974D03*
X432561Y1076587D03*
X434411Y1073383D03*
Y1066974D03*
X427012Y1079791D03*
X434411D03*
X428861Y1082995D03*
X425162Y1089404D03*
X421462Y1082995D03*
X432561Y1089404D03*
Y1082995D03*
X434411Y1086200D03*
X428861Y1095813D03*
X421462D03*
X432561D03*
X427011Y1099017D03*
X425161Y1102221D03*
X423311Y1105426D03*
X421462Y1108630D03*
X434411Y1105426D03*
X423311Y1111834D03*
X434411D03*
X423311Y1124651D03*
Y1118243D03*
X421462Y1115039D03*
X434411Y1124651D03*
Y1118243D03*
X423312Y1137469D03*
X423311Y1131060D03*
X434412Y1137769D03*
X434411Y1131060D03*
X452478Y848176D03*
X445078D03*
X441378D03*
X439529Y844671D03*
X446929Y851380D03*
X443228D03*
X439529D03*
X448779Y854584D03*
X446929Y864197D03*
X443229D03*
X441379Y854584D03*
X439529Y864197D03*
X439528Y857789D03*
X437680Y860992D03*
X450629Y864197D03*
X448779Y867401D03*
X441379D03*
X448779Y880219D03*
X446929Y877014D03*
X443229D03*
X441379Y880219D03*
X439529Y877014D03*
X448779Y893036D03*
X446929Y889832D03*
X443229D03*
X441379Y893036D03*
X439529Y896240D03*
Y889832D03*
X437678Y886627D03*
X450629Y889832D03*
X437679Y899445D03*
X446929Y909057D03*
Y902649D03*
X443229D03*
X439528D03*
X437679Y905853D03*
X450629Y902649D03*
X446929Y915466D03*
X446930Y928283D03*
X441379Y925079D03*
Y931487D03*
X446929Y921875D03*
X437678Y918670D03*
X448779Y937897D03*
X447360Y1038136D03*
X452911Y1041340D03*
X451061Y1044544D03*
X449211Y1047749D03*
X447361Y1057361D03*
Y1050952D03*
X452911Y1060565D03*
X447361Y1063770D03*
Y1076587D03*
Y1070178D03*
X449211Y1073383D03*
X452911Y1079791D03*
X449211D03*
X447361Y1082995D03*
X452911Y1092608D03*
X451062Y1089404D03*
X449212Y1086200D03*
X451062Y1095813D03*
X447361Y1108630D03*
Y1102221D03*
X452911Y1099017D03*
X447361Y1121447D03*
Y1115039D03*
Y1127856D03*
Y1134264D03*
X461729Y851380D03*
X458029D03*
X454328D03*
X456179Y841467D03*
X463579D03*
X469129Y851380D03*
X465429D03*
X456179Y854584D03*
X463579D03*
X461729Y864197D03*
X458029D03*
X454329D03*
X469129D03*
X465429D03*
X456179Y867401D03*
X463579D03*
X461729Y877014D03*
X458029D03*
X456179Y880219D03*
X454329Y877014D03*
X463579Y880219D03*
X469129Y877014D03*
X465429D03*
X461729Y889832D03*
X458029D03*
X456179Y893036D03*
X454329Y889832D03*
X463579Y893036D03*
X469129Y896240D03*
Y889832D03*
X465429D03*
X461729Y902649D03*
X458029D03*
X456178Y905853D03*
X454329Y902649D03*
X465429D03*
Y909057D03*
Y915466D03*
X454103Y931359D03*
Y933659D03*
X456178Y918670D03*
X454434Y1022186D03*
Y1019886D03*
X460311Y1041340D03*
X467372Y1036874D03*
X465861Y1044544D03*
X456611Y1047749D03*
X464011D03*
X456611Y1054157D03*
X462162Y1050952D03*
X454761Y1076587D03*
X462162Y1070178D03*
X456612Y1079791D03*
X467711D03*
X458461Y1082995D03*
X456611Y1086200D03*
X460311Y1092608D03*
X464011Y1086200D03*
X467712D03*
Y1092608D03*
X460312Y1105426D03*
X458462Y1102221D03*
X456611Y1099017D03*
X464012Y1105426D03*
Y1099017D03*
X462162Y1108630D03*
X465861D03*
Y1102221D03*
X464012Y1111834D03*
X467711Y1105426D03*
Y1111834D03*
X458462Y1121447D03*
Y1115039D03*
X467712Y1124651D03*
X467711Y1118243D03*
X465862Y1121447D03*
Y1115039D03*
X458462Y1127856D03*
Y1134264D03*
X478379Y841467D03*
X470979D03*
X476529Y851380D03*
X480229D03*
X472829D03*
X483929D03*
X480229Y864197D03*
X478379Y854584D03*
X476529Y864197D03*
X470979Y854584D03*
X472829Y864197D03*
X483929D03*
X478379Y867401D03*
X470979D03*
X480229Y877014D03*
X478379Y880219D03*
X476529Y877014D03*
X472829D03*
X472828Y870606D03*
X470979Y880219D03*
Y873810D03*
X483929Y877014D03*
X480228Y896240D03*
X480229Y889832D03*
X478379Y893036D03*
X470979D03*
X476529Y889832D03*
X472829D03*
X483929D03*
X482078Y899445D03*
X474678Y905853D03*
X483929Y909057D03*
X482079Y912262D03*
X483928Y902649D03*
X476285Y930126D03*
X476528Y921875D03*
X474678Y918670D03*
X483929Y928283D03*
X482078Y918670D03*
X483928Y921875D03*
X482079Y931488D03*
X476285Y934726D03*
X476180Y945355D03*
Y947655D03*
X478378Y944304D03*
X480229Y934691D03*
X483928Y941100D03*
X482079Y944304D03*
X482078Y937896D03*
X483928Y947509D03*
X476285Y962326D03*
Y960026D03*
Y964626D03*
X483928Y960326D03*
X482078Y957122D03*
X482079Y950713D03*
X483929Y966735D03*
X476285Y966926D03*
X476192Y977670D03*
X476335Y980737D03*
X482079Y969939D03*
X483928Y979552D03*
X482078Y976347D03*
X476285Y996826D03*
Y994526D03*
Y989926D03*
Y987626D03*
X476295Y1010500D03*
X476285Y1012926D03*
Y1006026D03*
Y1003726D03*
X484361Y999684D03*
X482512Y1009297D03*
X482511Y1002888D03*
X484362Y1012501D03*
X476275Y1022636D03*
X476285Y1017526D03*
X482511Y1028523D03*
Y1022114D03*
X484361Y1018910D03*
Y1031727D03*
X471282Y1036526D03*
X473507Y1035928D03*
X475111Y1041340D03*
X482511D03*
X482512Y1034931D03*
X484361Y1038136D03*
X471411Y1047749D03*
X482511D03*
X480662Y1050952D03*
X471411Y1054157D03*
X482511Y1060565D03*
X484362Y1050952D03*
Y1070178D03*
X482511Y1079791D03*
X480662Y1082995D03*
X476962Y1089404D03*
X473262Y1082995D03*
X469561Y1089404D03*
X482512Y1086200D03*
X484362Y1089404D03*
X480661Y1095813D03*
X469562D03*
X484362D03*
X480662Y1108630D03*
X478811Y1099017D03*
X473262Y1108630D03*
X476962Y1102221D03*
X475112Y1099017D03*
X471411D03*
X469562Y1102221D03*
X482511Y1105426D03*
Y1111834D03*
X484362Y1108630D03*
X475111Y1111834D03*
X471411D03*
X478811Y1105426D03*
X469562Y1108630D03*
X473262Y1102221D03*
X482511Y1099017D03*
X478811Y1111834D03*
X476962Y1108630D03*
X471411Y1105426D03*
X475111D03*
X484362Y1102221D03*
X480661Y1115039D03*
X478811Y1118243D03*
X476961Y1115039D03*
X475111Y1118243D03*
X471411D03*
X469561Y1115039D03*
X482511Y1118243D03*
X476961Y1127856D03*
X469562D03*
X484361D03*
X484362Y1115039D03*
X473262D03*
X478811Y1131060D03*
X476961Y1140973D03*
X475111Y1131060D03*
X471412Y1137469D03*
Y1131060D03*
X469561Y1140973D03*
X473261Y1134264D03*
X482511Y1131060D03*
X484361Y1140973D03*
X493179Y841467D03*
X485779D03*
X500579D03*
X495029Y851380D03*
X491329D03*
X487629D03*
X498729D03*
X495029Y864197D03*
X493179Y854584D03*
X491329Y864197D03*
X487629D03*
X485779Y854584D03*
X498729Y864197D03*
X500579Y854584D03*
X493179Y867401D03*
X485779D03*
X500579D03*
X495029Y877014D03*
X493179Y880219D03*
X491329Y877014D03*
X487629D03*
X485779Y880219D03*
X500579D03*
X498729Y877014D03*
X489479Y893036D03*
X495029Y889832D03*
X491329D03*
X487629D03*
X498729D03*
X500579Y893036D03*
X498729Y896240D03*
X496879Y899445D03*
X489478D03*
X496878Y912262D03*
X495029Y909057D03*
X489478Y905853D03*
X495029Y902649D03*
X493179Y905853D03*
X485778D03*
X498728Y915466D03*
X495028Y928283D03*
X493179Y925079D03*
X489478D03*
Y918670D03*
X485778Y925079D03*
X496879Y918670D03*
X495029Y921875D03*
X496878Y931488D03*
X489478D03*
X496879Y937896D03*
X495029Y941100D03*
X493179Y944304D03*
X489478D03*
Y937896D03*
X485778Y944304D03*
X498729Y934691D03*
X495028Y947509D03*
X496879Y957122D03*
X495029Y960326D03*
X489478Y957122D03*
Y950713D03*
X496878D03*
X498729Y953917D03*
X495028Y966735D03*
X493179Y963530D03*
X485778D03*
X489478D03*
X500579D03*
X496879Y976347D03*
X496878Y969939D03*
X489478Y976347D03*
Y969939D03*
X495029Y979552D03*
X498728Y973143D03*
X493179Y982756D03*
X489478D03*
X485778D03*
X497311Y1009297D03*
X497312Y1002888D03*
X495462Y999684D03*
X489911Y1009297D03*
X489912Y1002888D03*
X491761Y1006093D03*
X488062D03*
X499161D03*
X495461Y1012501D03*
X497311Y1028523D03*
X489911D03*
Y1022114D03*
Y1015705D03*
X497311Y1022114D03*
X495462Y1018910D03*
X493612Y1015705D03*
X486211D03*
X501012D03*
X499161Y1025318D03*
X495461Y1031727D03*
X497312Y1041340D03*
X489911D03*
Y1034931D03*
X495462Y1038136D03*
X493612Y1034931D03*
X486211D03*
X499161Y1044544D03*
X489911Y1047749D03*
X497311D03*
Y1060565D03*
X489911D03*
Y1054157D03*
X495461Y1050952D03*
X493611Y1054157D03*
X486211D03*
X489911Y1066974D03*
X495461Y1070178D03*
X489911Y1073383D03*
X497312Y1079791D03*
X489911D03*
X497311Y1086200D03*
X493612Y1092608D03*
X489911D03*
Y1086200D03*
X486211Y1092608D03*
X495461Y1089404D03*
X499161Y1082995D03*
X495462Y1095813D03*
X499162D03*
X491762D03*
X497312Y1105426D03*
X493611D03*
X491762Y1102221D03*
X488061D03*
X486211Y1105426D03*
X486212Y1099017D03*
X499161Y1108630D03*
Y1102221D03*
X497312Y1111834D03*
X489911D03*
Y1099017D03*
X495462Y1102221D03*
X501011Y1099017D03*
X493611D03*
X497311D03*
X489911Y1105426D03*
X486211Y1111834D03*
X491762Y1108630D03*
X488062D03*
X497311Y1118243D03*
X495462Y1121447D03*
X493612Y1118243D03*
X489911D03*
X486211D03*
X501011D03*
X499161Y1115039D03*
X491761Y1127856D03*
X499161D03*
X491762Y1115039D03*
X495462D03*
X497311Y1131060D03*
X493611D03*
X489911D03*
X486211D03*
X491761Y1140973D03*
X501011Y1131060D03*
X499161Y1140973D03*
X507979Y841467D03*
X515379D03*
X506129Y851380D03*
X502429D03*
X513529D03*
X509829D03*
X517229D03*
X513529Y864197D03*
X509829D03*
X506129D03*
X502429D03*
X507979Y854584D03*
X515379D03*
X517229Y864197D03*
X507979Y867401D03*
X515379D03*
X509829Y877014D03*
X507979Y880219D03*
X502429Y877014D03*
X513529D03*
X506129D03*
X515379Y880219D03*
X517229Y877014D03*
X506129Y889832D03*
X502428Y896240D03*
X502429Y889832D03*
X513529D03*
X509829D03*
X506128Y896240D03*
X504279Y893036D03*
X515379D03*
X517229Y889832D03*
X507978Y899445D03*
X515378D03*
X511678Y905853D03*
X509829Y909057D03*
X507979Y912262D03*
X502429Y909057D03*
Y902649D03*
X509828D03*
X515378Y912262D03*
Y905853D03*
X502429Y915466D03*
X506129D03*
X511678Y925079D03*
X509829Y928283D03*
X502429D03*
Y921875D03*
X509828D03*
X507978Y918670D03*
X515378Y925079D03*
Y918670D03*
X507979Y931488D03*
X515378D03*
X511678Y944304D03*
X509828Y941100D03*
X506129Y934691D03*
X502429Y941100D03*
Y934691D03*
X515378Y944304D03*
Y937896D03*
X502429Y947509D03*
X509828Y960326D03*
X507978Y957122D03*
X506129Y953917D03*
X502429Y960326D03*
Y953917D03*
X507979Y950713D03*
X515378Y957122D03*
Y950713D03*
X509829Y966735D03*
X502428D03*
X511678Y963530D03*
X504278D03*
X515378D03*
X507978Y976347D03*
X507979Y969939D03*
X502429Y979552D03*
Y973143D03*
X513529D03*
X509828Y979552D03*
X506129Y973143D03*
X515379Y976347D03*
X515378Y969939D03*
X517228Y973143D03*
X511678Y982756D03*
X515378D03*
X510261Y999684D03*
X508411Y1002888D03*
X506562Y1006093D03*
X502862Y999684D03*
X502861Y1012501D03*
X508412Y1009297D03*
X510262Y1012501D03*
X515811Y1009297D03*
Y1002888D03*
X508411Y1028523D03*
X502862Y1025318D03*
Y1018910D03*
X510261D03*
X508411Y1022114D03*
X506562Y1025318D03*
X504711Y1015705D03*
X515811Y1028523D03*
Y1022114D03*
X510262Y1031727D03*
X502862D03*
X515811Y1015705D03*
X512111D03*
X502862Y1044544D03*
Y1038136D03*
X512111Y1034931D03*
X510261Y1038136D03*
X508411Y1041340D03*
X506562Y1044544D03*
X515811Y1034931D03*
Y1041340D03*
X508411Y1047749D03*
X515811D03*
X508411Y1060565D03*
X502862Y1057361D03*
Y1050952D03*
X512111Y1054157D03*
X510262Y1050952D03*
X515811Y1054157D03*
Y1060565D03*
X502862Y1063770D03*
X510262Y1070178D03*
X502862Y1076587D03*
Y1070178D03*
X515811Y1073383D03*
Y1079791D03*
X512112Y1092608D03*
X510262Y1089404D03*
X508412Y1086200D03*
X506562Y1082995D03*
X502862Y1089404D03*
Y1082995D03*
X515812Y1092608D03*
X513961Y1095813D03*
X502862D03*
X517662D03*
X513962Y1108630D03*
Y1102221D03*
X512112Y1099017D03*
X508411D03*
X506562Y1108630D03*
X504711Y1099017D03*
X502862Y1102221D03*
X515811Y1105426D03*
Y1111834D03*
X517662Y1108630D03*
X513961Y1115039D03*
X512111Y1118243D03*
X508411D03*
X504711D03*
X510261Y1115039D03*
X515811Y1118243D03*
X513961Y1127856D03*
X506561D03*
X517662Y1115039D03*
X513961Y1140973D03*
X512111Y1131060D03*
X508411D03*
X504711D03*
X506561Y1140973D03*
X515811Y1131060D03*
X528329Y844671D03*
X522779Y841467D03*
X528329Y851380D03*
X524629D03*
X520929D03*
X532029D03*
X528329Y864197D03*
X524629D03*
X520929D03*
X530179Y860993D03*
Y854584D03*
X522779D03*
X532028Y857789D03*
X533879Y860993D03*
X530178Y867401D03*
X522779D03*
X533879D03*
X528329Y877014D03*
X522779Y880219D03*
X520929Y877014D03*
X530179Y880219D03*
X524629Y877014D03*
X532029D03*
X533879Y880219D03*
Y873810D03*
X532028Y883423D03*
X528329Y896240D03*
Y889832D03*
X524629D03*
X526479Y893036D03*
X524629Y896240D03*
X520929Y889832D03*
X532029D03*
Y896240D03*
X533879Y893036D03*
X522779Y899445D03*
X533879D03*
X528329Y902649D03*
X522778Y912262D03*
X520928Y909057D03*
X519079Y905853D03*
X520929Y902649D03*
X528329Y915466D03*
X524628D03*
X532029D03*
X528329Y909057D03*
X533879Y912262D03*
X528329Y921875D03*
X520928Y928283D03*
X519079Y925079D03*
X522779Y918670D03*
X520929Y921875D03*
X522778Y931488D03*
X528329Y928283D03*
X533879Y918670D03*
X533878Y931488D03*
X528329Y941100D03*
Y934691D03*
X524628D03*
X522779Y937896D03*
X520929Y941100D03*
X519079Y944304D03*
X520928Y947509D03*
X532029Y934691D03*
X533879Y937896D03*
X528329Y947509D03*
Y960326D03*
Y953917D03*
X524629D03*
X522779Y957122D03*
X520929Y960326D03*
X522778Y950713D03*
X520928Y966735D03*
X526479Y963530D03*
X519079D03*
X533879Y957122D03*
X532029Y953917D03*
X533879Y950713D03*
X530178Y963530D03*
X528329Y966735D03*
Y979552D03*
Y973143D03*
X522779Y976347D03*
X522778Y969939D03*
X524628Y973143D03*
X520929Y979552D03*
X533879Y976347D03*
X519079Y982756D03*
X533901Y980606D03*
X533879Y969939D03*
X532029Y973143D03*
X521361Y1012501D03*
Y999684D03*
X528762Y1006093D03*
Y999684D03*
X525061Y1006093D03*
X523211Y1009297D03*
X523212Y1002888D03*
X534311Y1009297D03*
Y1002888D03*
X532461Y1006093D03*
X528761Y1012501D03*
X528762Y1025318D03*
X523211Y1028523D03*
X525061Y1025318D03*
X528762Y1031727D03*
X521361D03*
X519512Y1015705D03*
X521362Y1018910D03*
X523211Y1022114D03*
X526912Y1015705D03*
X528762Y1018910D03*
X530611Y1015705D03*
X534311Y1028523D03*
X534310Y1022114D03*
X532461Y1025318D03*
X528762Y1044544D03*
X525061D03*
X523212Y1041340D03*
X521362Y1038136D03*
X519512Y1034931D03*
X532462Y1044544D03*
X523211Y1047749D03*
X528762Y1038136D03*
X534311Y1041340D03*
Y1047749D03*
X528762Y1057361D03*
Y1050952D03*
X523212Y1060565D03*
X521361Y1050952D03*
X519512Y1054157D03*
X528762Y1063770D03*
X534311Y1060565D03*
X528762Y1076587D03*
Y1070178D03*
X521361D03*
X523212Y1079791D03*
X534311D03*
X523211Y1086200D03*
X521361Y1089404D03*
X519511Y1092608D03*
X528762Y1089404D03*
Y1082995D03*
X525061D03*
X532462Y1082996D03*
X534311Y1086200D03*
X528761Y1095813D03*
X526911Y1105426D03*
X521361Y1102221D03*
X519511Y1105426D03*
X519512Y1099017D03*
X532461Y1108630D03*
X530612Y1111834D03*
X523211D03*
X526911Y1099017D03*
X534311D03*
X532460Y1102221D03*
X521362Y1108630D03*
X525062D03*
X534311Y1111834D03*
X523211Y1105426D03*
X534311D03*
X528762Y1108630D03*
X519511Y1111834D03*
X526911D03*
X530611Y1124651D03*
Y1118243D03*
X528762Y1121447D03*
X523211Y1118243D03*
X521361Y1115039D03*
X519511Y1118243D03*
X532461Y1115039D03*
X528761Y1127856D03*
X521361D03*
X525062Y1115039D03*
X528762D03*
X530612Y1137469D03*
Y1131060D03*
X526912D03*
X523211D03*
X519511D03*
X528761Y1134264D03*
X521361Y1140973D03*
X534311Y1131060D03*
X537580Y848176D03*
X535729Y844671D03*
Y851380D03*
X544979Y860993D03*
Y854584D03*
X539428Y864197D03*
X537579Y854584D03*
Y860993D03*
X544979Y867401D03*
X541279D03*
X537579D03*
X546829Y870606D03*
X541279Y873810D03*
X535729Y870606D03*
Y883423D03*
X541279Y880219D03*
X546829Y883423D03*
X537579Y893036D03*
X541279Y886627D03*
X544979D03*
X537579D03*
X535729Y889832D03*
X550529D03*
X537579Y899445D03*
X548679Y912262D03*
X537579D03*
X539429Y909057D03*
X537579Y905853D03*
X535729Y909057D03*
X543129D03*
X535729Y902649D03*
X548679Y905853D03*
X537579Y918670D03*
X535729Y921875D03*
X537578Y931488D03*
X548678D03*
X537579Y937896D03*
X535729Y941100D03*
X539429Y947509D03*
X535729D03*
X537579Y957122D03*
Y950713D03*
X535729Y960326D03*
Y966735D03*
X537579Y963530D03*
X539429Y979552D03*
X537579Y982756D03*
X541279Y969939D03*
X539429Y973143D03*
X535729D03*
X539862Y1006092D03*
X539861Y999684D03*
X536161D03*
Y1006093D03*
X543563Y1006092D03*
X549254Y1000648D03*
X536161Y1012501D03*
Y1025318D03*
X539861Y1018910D03*
X541712Y1015705D03*
X545412D03*
X538012D03*
X536161Y1018910D03*
X549112Y1015705D03*
X536161Y1031727D03*
X545412Y1034931D03*
X539862Y1044544D03*
X539861Y1038136D03*
X541711Y1034931D03*
X538011D03*
X536161Y1038136D03*
X549112Y1034931D03*
X541711Y1054157D03*
X538011D03*
X545411D03*
X538011Y1060565D03*
X536161Y1050952D03*
X538011Y1066974D03*
X539861Y1076587D03*
X536162Y1082996D03*
X538011Y1092608D03*
X536161Y1089404D03*
X545411Y1092608D03*
X547262Y1082996D03*
X543561Y1095813D03*
X536161D03*
X547261D03*
X545412Y1105426D03*
X541711D03*
X539861Y1108630D03*
Y1102221D03*
X536161D03*
X541711Y1111834D03*
X545411D03*
X538011Y1105426D03*
X536161Y1108630D03*
X538011Y1111834D03*
X543561Y1108630D03*
X545411Y1124651D03*
Y1118243D03*
X543562Y1115039D03*
X539862D03*
X538011Y1124651D03*
X536161Y1115039D03*
X541711Y1131060D03*
X536162Y1134264D03*
X551429Y979057D03*
X550701Y972608D03*
X550961Y1031727D03*
X560571Y1614292D03*
X580431Y1602380D03*
X688999Y1051247D03*
X748399D03*
X1293802Y162999D03*
X1297007Y161149D03*
X1297012Y168549D03*
X1297007Y164849D03*
X1293802Y183349D03*
Y187049D03*
Y190749D03*
Y198149D03*
Y194449D03*
Y201849D03*
X1296999Y209249D03*
X1300774Y155288D03*
X1309832Y161149D03*
X1303417D03*
X1309832Y168549D03*
X1303417D03*
X1303422Y172249D03*
X1313033Y174099D03*
X1306622D03*
X1300207Y185199D03*
X1306617Y181499D03*
X1300207Y192599D03*
X1309817Y187049D03*
X1306617Y192599D03*
X1313023Y199999D03*
X1306617D03*
X1300207D03*
X1303407Y201849D03*
X1303422Y209249D03*
X1313032Y214799D03*
X1306622Y218499D03*
X1303417Y212949D03*
Y216649D03*
X1300207Y214799D03*
X1301151Y225450D03*
X1309828Y224049D03*
X1306622Y222199D03*
X1309100Y236477D03*
X1313920Y854584D03*
X1312266Y857972D03*
X1312070Y877014D03*
X1310221Y880219D03*
X1308370Y877014D03*
X1312070Y896240D03*
X1310220Y893036D03*
X1308371Y902649D03*
X1312070Y915466D03*
X1308370D03*
X1308371Y921875D03*
X1312070Y934692D03*
X1308371Y941100D03*
X1308370Y934692D03*
X1312070Y953917D03*
X1308370D03*
X1310221Y957122D03*
X1308371Y973143D03*
X1310221Y976347D03*
X1314352Y996480D03*
X1314353Y1002888D03*
X1308803Y1006093D03*
X1314353Y1015705D03*
Y1022114D03*
X1308803Y1025318D03*
Y1018910D03*
X1314353Y1041340D03*
X1308803Y1044544D03*
X1310653Y1041340D03*
X1314353Y1060565D03*
X1312502Y1082995D03*
X1314353Y1111834D03*
Y1105426D03*
X1312503Y1115039D03*
Y1127856D03*
X1320469Y155288D03*
X1322652Y161149D03*
X1316242D03*
X1319452Y166699D03*
X1329062Y168549D03*
X1319442Y170399D03*
X1318502Y176574D03*
Y186024D03*
Y182874D03*
X1329062Y172249D03*
X1316237D03*
X1331102Y176574D03*
X1327952Y186024D03*
Y182874D03*
X1318502Y189174D03*
X1315352Y195474D03*
X1327952Y189174D03*
X1331102Y195474D03*
X1327952Y198624D03*
X1321652D03*
X1325852Y214799D03*
X1319442Y218499D03*
X1329062Y209249D03*
X1319442Y207399D03*
X1329062Y216649D03*
X1319442Y222199D03*
X1329061Y224049D03*
X1326377Y235784D03*
X1321986Y236726D03*
X1326869Y844971D03*
X1323170D03*
X1321320Y848176D03*
X1330571Y851380D03*
X1323170D03*
X1319469D03*
X1317620Y854584D03*
X1315770Y857789D03*
X1330571Y864197D03*
X1326871D03*
X1323171D03*
Y857789D03*
X1325020Y854584D03*
X1321321Y860993D03*
X1319469Y857789D03*
X1317621Y867401D03*
X1328721D03*
X1325021D03*
X1330571Y877014D03*
X1328722Y880219D03*
X1326871Y877014D03*
X1321321Y873810D03*
X1315771Y877014D03*
X1317621Y873810D03*
X1321321Y880219D03*
X1319471Y877014D03*
X1315771Y883423D03*
X1326871D03*
X1323171D03*
X1328720Y899445D03*
X1315771Y896240D03*
Y889832D03*
X1328720Y893036D03*
Y886627D03*
X1325021D03*
X1321321Y893036D03*
X1319470Y896240D03*
X1321321Y899445D03*
X1328720Y905853D03*
X1325020D03*
X1317621Y912262D03*
X1317620Y905853D03*
X1328720Y912262D03*
X1323171Y909057D03*
Y902649D03*
X1321321Y912262D03*
X1315771Y915466D03*
X1319471D03*
X1328720Y925079D03*
Y918670D03*
X1325020Y925079D03*
X1317620D03*
X1323171Y928283D03*
Y921875D03*
X1321321Y918670D03*
X1317621Y931488D03*
X1328720D03*
X1321321D03*
X1323171Y941100D03*
X1325020Y944304D03*
X1323171Y947509D03*
X1317620Y944304D03*
X1328720D03*
Y937896D03*
X1315771Y934692D03*
X1321321Y937896D03*
X1319470Y934692D03*
X1321321Y957122D03*
X1323171Y966735D03*
X1325020Y963530D03*
X1323171Y960326D03*
X1321321Y950713D03*
X1315771Y953917D03*
Y966735D03*
X1319470Y953917D03*
X1319471Y966735D03*
X1319470Y960326D03*
X1317621Y950713D03*
X1328720Y957122D03*
Y963530D03*
Y950713D03*
X1321321Y969939D03*
X1325020Y982756D03*
X1323171Y979552D03*
X1321321Y976347D03*
X1315771Y973143D03*
X1319471D03*
X1328720Y969939D03*
X1330570Y973143D03*
X1326871D03*
X1328720Y982756D03*
X1328721Y976347D03*
X1315771Y979552D03*
X1318053Y1009297D03*
Y1002888D03*
X1327304Y1006093D03*
X1331003D03*
X1329153Y1009297D03*
Y1002888D03*
X1323603Y999684D03*
X1321753Y1009297D03*
X1319903Y1006093D03*
X1321753Y1002888D03*
X1323603Y1012501D03*
X1329153Y1028523D03*
Y1015705D03*
X1318053Y1022114D03*
Y1015705D03*
X1329153Y1022114D03*
X1325453Y1015705D03*
X1323603Y1018910D03*
X1321753Y1028523D03*
X1319903Y1018910D03*
X1321753Y1022114D03*
Y1015705D03*
X1319903Y1031727D03*
X1323603D03*
X1329153Y1034931D03*
Y1047749D03*
X1318053Y1041340D03*
X1319903Y1038136D03*
X1329153Y1041340D03*
X1325453Y1034931D03*
X1323603Y1038136D03*
X1321753Y1041340D03*
X1319903Y1044544D03*
X1321753Y1047749D03*
X1329153Y1060565D03*
Y1054157D03*
X1325453D03*
X1319903Y1057361D03*
Y1050952D03*
X1323603D03*
Y1057361D03*
X1321753Y1060565D03*
X1319903Y1063770D03*
X1329153Y1073383D03*
X1319903Y1076587D03*
Y1070178D03*
X1316204Y1076587D03*
X1329153Y1066974D03*
X1323603Y1076587D03*
Y1070178D03*
X1325454Y1073383D03*
X1321753Y1066974D03*
X1329153Y1079791D03*
X1321753D03*
X1318053D03*
X1329153Y1086200D03*
Y1092608D03*
X1325452Y1092609D03*
X1323603Y1089404D03*
X1321752Y1086200D03*
X1319902Y1082995D03*
X1316202D03*
X1316203Y1095813D03*
X1331003Y1108630D03*
X1329153Y1099017D03*
X1323603Y1108630D03*
X1316203D03*
Y1102221D03*
X1325453Y1099017D03*
X1323603Y1102221D03*
X1319903D03*
X1316203Y1115039D03*
X1331003D03*
X1327303Y1121447D03*
Y1115039D03*
X1325453Y1124651D03*
X1325454Y1118243D03*
X1321753D03*
X1319903Y1115039D03*
X1329152Y1137469D03*
X1329153Y1131060D03*
X1321752Y1137469D03*
X1325453Y1131060D03*
X1319903Y1134264D03*
X1344103Y155288D03*
X1342936Y159301D03*
X1335472Y161149D03*
X1346137Y168549D03*
X1342907Y166699D03*
X1332268D03*
X1346137Y164849D03*
X1339727D03*
X1335472Y168549D03*
X1339568Y176028D03*
X1339727Y179649D03*
X1342937Y181499D03*
Y185199D03*
X1346137Y172249D03*
X1335472D03*
X1339727Y190749D03*
X1342937Y188899D03*
X1334252Y195474D03*
X1346137Y194449D03*
Y190749D03*
X1346147Y209248D03*
X1332262Y218499D03*
Y214799D03*
X1332285Y226210D03*
X1342937Y222199D03*
X1332267D03*
X1343521Y841467D03*
X1336121D03*
X1345371Y851380D03*
X1341671D03*
X1337971D03*
X1334271D03*
X1345371Y864197D03*
X1343521Y854584D03*
X1341671Y864197D03*
X1337971D03*
X1336121Y854584D03*
X1334271Y864197D03*
X1343521Y867401D03*
X1336121D03*
X1345371Y877014D03*
X1343521Y880219D03*
X1341671Y877014D03*
X1337971D03*
X1334271D03*
X1332420Y886627D03*
X1345371Y896240D03*
Y889832D03*
X1341671Y896240D03*
Y889832D03*
X1337970Y896240D03*
X1337971Y889832D03*
X1336121Y893036D03*
X1334270Y889832D03*
X1332420Y905853D03*
X1341671Y909057D03*
Y902649D03*
X1336120Y912262D03*
X1334270Y909057D03*
X1334271Y902649D03*
X1347221Y912262D03*
X1345371Y915466D03*
X1341671D03*
X1337970D03*
X1332421Y925079D03*
X1341671Y928283D03*
Y921875D03*
X1334270Y928283D03*
X1334271Y921875D03*
X1347220Y918670D03*
X1336120Y931488D03*
X1347221D03*
X1341671Y947509D03*
X1334270D03*
X1334271Y941100D03*
X1332421Y944304D03*
X1345371Y934691D03*
X1341671D03*
X1337970D03*
X1337971Y953917D03*
X1345371D03*
X1341671D03*
Y960326D03*
X1347220Y957122D03*
X1343520Y963530D03*
X1339821D03*
X1341670Y966735D03*
X1347221Y950713D03*
X1334271Y960326D03*
X1336121Y957122D03*
X1332421Y963530D03*
X1334270Y966735D03*
X1336120Y950713D03*
X1347221Y969939D03*
X1337970Y973143D03*
X1347220Y976347D03*
X1345371Y973143D03*
X1341671Y979552D03*
Y973143D03*
X1336120Y969939D03*
X1336121Y976347D03*
X1334271Y979552D03*
X1332421Y982756D03*
X1342104Y999684D03*
Y1006093D03*
X1338403D03*
X1336553Y1009297D03*
X1336554Y1002888D03*
X1334704Y999684D03*
X1347654Y1009297D03*
X1342103Y1012501D03*
X1334703D03*
X1332854Y1015705D03*
X1345804Y1025318D03*
X1343953Y1015705D03*
X1342104Y1025318D03*
Y1018910D03*
X1340254Y1015705D03*
X1336553Y1028523D03*
X1338403Y1025318D03*
X1336554Y1022114D03*
X1334704Y1018910D03*
X1347653Y1028523D03*
Y1022114D03*
X1342104Y1031727D03*
X1334703D03*
X1332854Y1034931D03*
X1345804Y1044544D03*
X1342104D03*
Y1038136D03*
X1338403Y1044544D03*
X1336554Y1041340D03*
X1334704Y1038136D03*
X1347653Y1041340D03*
X1336553Y1047749D03*
X1347653D03*
X1332854Y1054157D03*
X1342104Y1057361D03*
Y1050952D03*
X1336554Y1060565D03*
X1334704Y1057361D03*
X1334703Y1050952D03*
X1347653Y1060565D03*
X1345804Y1063770D03*
X1342104D03*
X1338403D03*
X1332854Y1073383D03*
X1342104Y1070178D03*
X1336553Y1066974D03*
X1334703Y1070178D03*
X1334704Y1076587D03*
X1347654Y1066974D03*
X1336554Y1079791D03*
X1347653D03*
X1345804Y1082995D03*
X1342104Y1089404D03*
Y1082995D03*
X1338403D03*
X1336553Y1086200D03*
X1334703Y1089404D03*
X1332854Y1092608D03*
X1347654Y1086200D03*
X1342104Y1095813D03*
X1334703D03*
X1342104Y1102221D03*
X1338404D03*
X1336553Y1099017D03*
X1332853Y1105426D03*
Y1099017D03*
X1347654Y1105426D03*
Y1099017D03*
X1340254Y1111834D03*
X1332854D03*
X1347654D03*
X1343953Y1118243D03*
X1340253D03*
X1338403Y1115039D03*
X1336553Y1118243D03*
X1332853D03*
X1347653D03*
X1342104Y1127856D03*
X1334703D03*
X1343953Y1131060D03*
X1342103Y1140973D03*
X1340254Y1131060D03*
X1336554D03*
X1334703Y1140973D03*
X1332854Y1131060D03*
X1347653D03*
X1349351Y159298D03*
X1355758D03*
X1355761Y162998D03*
X1358865Y166732D03*
Y158854D03*
Y162793D03*
X1349351Y166698D03*
X1352557Y164848D03*
X1358865Y170671D03*
Y174603D03*
Y182484D03*
Y178544D03*
X1355761Y170398D03*
X1352557Y179648D03*
X1358371Y188778D03*
X1358865Y195240D03*
Y199180D03*
X1349351Y196298D03*
X1352561Y194448D03*
X1352551Y190748D03*
X1349345Y188898D03*
X1355761Y192598D03*
X1358865Y207060D03*
Y203120D03*
Y213994D03*
Y217934D03*
X1352560Y205549D03*
X1355765Y207399D03*
X1349351Y214798D03*
X1352561Y212948D03*
X1349351Y211098D03*
Y222198D03*
X1358321Y841467D03*
X1350921D03*
X1360171Y851380D03*
X1356471D03*
X1352771D03*
X1349071D03*
X1363871D03*
X1360171Y864197D03*
X1358321Y854584D03*
X1356471Y864197D03*
X1352771D03*
X1350921Y854584D03*
X1349071Y864197D03*
X1363871D03*
X1358321Y867401D03*
X1350921D03*
X1360171Y877014D03*
X1358321Y880219D03*
X1356471Y877014D03*
X1352771D03*
X1350921Y880219D03*
X1349071Y877014D03*
X1363871D03*
X1360171Y889832D03*
X1356471D03*
X1354621Y893036D03*
X1352771Y889832D03*
X1349071D03*
X1363871Y896240D03*
Y889832D03*
X1362021Y899445D03*
X1354620D03*
X1362020Y912262D03*
X1360170Y909057D03*
X1360171Y902649D03*
X1358321Y905853D03*
X1354620Y912262D03*
Y905853D03*
X1350920D03*
X1349071Y909057D03*
X1349070Y902649D03*
X1363870Y915466D03*
X1362021Y918670D03*
X1360170Y928283D03*
X1360171Y921875D03*
X1358321Y925079D03*
X1354620D03*
Y918670D03*
X1350920Y925079D03*
X1349071Y928283D03*
X1349070Y921875D03*
X1362020Y931488D03*
X1360171Y941100D03*
X1358321Y944304D03*
X1354620D03*
X1360170Y947509D03*
X1350920Y944304D03*
X1349071Y947509D03*
X1349070Y941100D03*
X1362021Y937896D03*
X1354620D03*
X1363870Y934691D03*
X1363871Y953917D03*
X1360171Y960326D03*
X1362021Y957122D03*
X1354620D03*
X1358321Y963530D03*
X1354620D03*
X1360170Y966735D03*
X1354620Y950713D03*
X1362020D03*
X1349070Y960326D03*
X1350920Y963530D03*
X1349071Y966735D03*
X1362020Y969939D03*
X1354620D03*
X1363870Y973143D03*
X1362021Y976347D03*
X1360171Y979552D03*
X1358321Y982756D03*
X1356470Y973143D03*
X1354620Y982756D03*
X1354621Y976347D03*
X1350920Y982756D03*
X1349070Y979552D03*
X1352771Y973143D03*
X1351352Y996480D03*
X1349503Y999684D03*
X1362453Y1009297D03*
X1362454Y1002888D03*
X1360604Y999684D03*
X1355053Y1009297D03*
Y1002888D03*
X1360603Y1012501D03*
X1349504D03*
X1362453Y1028523D03*
X1362454Y1022114D03*
X1360604Y1018910D03*
X1358754Y1015705D03*
X1355053Y1028523D03*
Y1022114D03*
Y1015705D03*
X1351353D03*
X1349503Y1018910D03*
X1360603Y1031727D03*
X1349504D03*
X1362454Y1041340D03*
X1360604Y1038136D03*
X1358754Y1034931D03*
X1355053Y1041340D03*
Y1034931D03*
X1351353D03*
X1349503Y1038136D03*
X1362453Y1047749D03*
X1355053D03*
X1362454Y1060565D03*
X1360604Y1057361D03*
X1360603Y1050952D03*
X1358754Y1054157D03*
X1355053D03*
X1351353D03*
X1349503Y1057361D03*
X1349504Y1050952D03*
X1362453Y1066974D03*
X1360604Y1076587D03*
X1360603Y1070178D03*
X1358754Y1073383D03*
X1355053D03*
Y1066974D03*
X1351353Y1073383D03*
X1349503Y1076587D03*
X1349504Y1070178D03*
X1362453Y1079791D03*
X1355053D03*
X1362453Y1086200D03*
X1360603Y1089404D03*
X1358753Y1092608D03*
X1355053D03*
Y1086200D03*
X1351353Y1092608D03*
X1349504Y1089404D03*
X1360604Y1095813D03*
X1349504D03*
X1362454Y1099017D03*
X1360604Y1102221D03*
X1356904Y1108630D03*
X1355053Y1099017D03*
X1353204Y1102221D03*
X1349503Y1108630D03*
Y1102221D03*
X1362453Y1118243D03*
X1360603Y1115039D03*
X1358753Y1118243D03*
X1355053D03*
X1353203Y1115039D03*
X1351353Y1118243D03*
X1349503Y1115039D03*
X1356903Y1127856D03*
X1349503D03*
X1362453Y1131060D03*
X1358753D03*
X1356903Y1140973D03*
X1355053Y1131060D03*
X1351353D03*
X1349503Y1140973D03*
X1373121Y841467D03*
X1365721D03*
X1378671Y851380D03*
X1374971D03*
X1371271D03*
X1367571D03*
X1378671Y864197D03*
X1374971D03*
X1373121Y854584D03*
X1371271Y864197D03*
X1367571D03*
X1365721Y854584D03*
X1373121Y867401D03*
X1365721D03*
X1378671Y877014D03*
X1374971D03*
X1373121Y880219D03*
X1371271Y877014D03*
X1367571D03*
X1365721Y880219D03*
X1378671Y889832D03*
X1374971D03*
X1371271Y896240D03*
Y889832D03*
X1367570Y896240D03*
X1367571Y889832D03*
X1365721Y893036D03*
X1374971Y909057D03*
X1374970Y902649D03*
X1373121Y912262D03*
X1367571Y909057D03*
Y902649D03*
X1371271Y915466D03*
X1367571D03*
X1376820Y925079D03*
X1374971Y928283D03*
X1374970Y921875D03*
X1373120Y918670D03*
X1367571Y928283D03*
Y921875D03*
X1376820Y937896D03*
X1374970Y941100D03*
X1371271Y934691D03*
X1367571Y941100D03*
Y934691D03*
X1374971Y947509D03*
X1367571D03*
X1376820Y957122D03*
X1374970Y960326D03*
X1373120Y957122D03*
X1373121Y950713D03*
X1371271Y953917D03*
X1367571Y960326D03*
Y953917D03*
X1376820Y963530D03*
X1374971Y966735D03*
X1367571D03*
X1376820Y982756D03*
Y969939D03*
X1374970Y979552D03*
X1373120Y976347D03*
X1373121Y969939D03*
X1371271Y973143D03*
X1367571Y979552D03*
Y973143D03*
X1364303Y1006093D03*
X1377253Y1002888D03*
X1373554Y1009297D03*
X1373553Y1002888D03*
X1371704Y1006093D03*
X1368004D03*
Y999684D03*
X1375404Y1012501D03*
X1368003D03*
X1364303Y1025318D03*
X1375403Y1018910D03*
X1373553Y1028523D03*
Y1022114D03*
X1371704Y1025318D03*
X1369853Y1015705D03*
X1368004Y1025318D03*
Y1018910D03*
X1366154Y1015705D03*
X1375404Y1031727D03*
X1368004D03*
X1364303Y1044544D03*
X1375403Y1038136D03*
X1373553Y1041340D03*
X1371704Y1044544D03*
X1368004D03*
Y1038136D03*
X1373553Y1047749D03*
X1375403Y1057361D03*
X1375404Y1050952D03*
X1373553Y1060565D03*
X1368004Y1057361D03*
Y1050952D03*
X1364303Y1063770D03*
X1371704D03*
X1368004D03*
X1377253Y1073383D03*
X1375403Y1076587D03*
X1375404Y1070178D03*
X1373554Y1066974D03*
X1368004Y1076587D03*
Y1070178D03*
X1377253Y1079791D03*
X1373553D03*
X1364303Y1082995D03*
X1377254Y1092608D03*
X1377253Y1086200D03*
X1375404Y1089404D03*
X1373554Y1086200D03*
X1371704Y1082995D03*
X1368004Y1089404D03*
Y1082995D03*
X1379104Y1095813D03*
X1375403D03*
X1368004D03*
X1364304Y1108630D03*
Y1102221D03*
X1377253Y1105426D03*
X1375404Y1102221D03*
X1373554Y1099017D03*
X1371704Y1102221D03*
X1366153Y1105426D03*
X1373553Y1111834D03*
X1366153D03*
X1364303Y1115039D03*
X1377253Y1118243D03*
X1373553D03*
X1371703Y1115039D03*
X1369853Y1118243D03*
X1366153D03*
X1364303Y1127856D03*
X1379103D03*
X1371703D03*
X1364303Y1140973D03*
X1379103D03*
X1377253Y1131060D03*
X1373553D03*
X1371703Y1140973D03*
X1369853Y1131060D03*
X1366153D03*
X1380521Y841467D03*
X1395321D03*
X1387921D03*
X1393471Y851380D03*
X1389771D03*
X1386071D03*
X1382371D03*
X1380521Y854584D03*
X1395321D03*
X1393471Y864197D03*
X1389771D03*
X1387921Y854584D03*
X1386071Y864197D03*
X1382371D03*
X1380521Y867401D03*
X1395321D03*
X1387921D03*
X1380521Y880219D03*
X1395321D03*
X1393471Y877014D03*
X1389771D03*
X1387921Y880219D03*
X1386071Y877014D03*
Y870606D03*
X1382371Y877014D03*
X1395321Y893036D03*
X1393471Y889832D03*
X1389771D03*
X1387921Y893036D03*
X1386071Y889832D03*
X1384221Y893036D03*
X1382371Y889832D03*
X1386071Y902649D03*
X1380520Y912262D03*
Y905853D03*
X1395320Y912262D03*
X1395321Y905853D03*
X1393471Y902649D03*
X1389771D03*
X1386071Y909057D03*
Y915466D03*
X1380520Y918670D03*
X1395187Y926265D03*
X1395320Y918670D03*
X1386071Y921875D03*
X1381189Y930811D03*
Y938045D03*
X1381287Y946239D03*
Y948539D03*
X1381189Y935745D03*
X1390234Y942097D03*
X1381264Y965896D03*
Y963596D03*
X1390506Y971139D03*
X1392896D03*
X1381003Y981269D03*
Y978969D03*
Y986421D03*
X1381243Y992971D03*
Y995271D03*
X1381003Y988721D03*
X1381369Y1007156D03*
X1381373Y1004848D03*
X1393716Y1000059D03*
X1391326D03*
X1381128Y1022427D03*
X1381140Y1026821D03*
X1384466Y1034270D03*
Y1031970D03*
X1393904Y1044544D03*
X1384653Y1041340D03*
X1380953Y1047749D03*
X1388353D03*
X1380953Y1060565D03*
X1393904Y1050952D03*
X1392053Y1060565D03*
Y1054157D03*
X1388353Y1060565D03*
X1386504Y1050952D03*
X1384653Y1054157D03*
X1380953Y1066974D03*
X1395753Y1073383D03*
X1392053Y1066974D03*
X1386504Y1076587D03*
Y1070178D03*
X1382803Y1076587D03*
X1380953Y1079791D03*
X1388353D03*
X1393903Y1089404D03*
Y1082995D03*
X1392053Y1092608D03*
X1392054Y1086200D03*
X1388353Y1092608D03*
X1384653Y1086200D03*
X1386504Y1095813D03*
X1382804D03*
X1380954Y1105426D03*
X1393904Y1102221D03*
X1392054Y1099017D03*
X1390204Y1108630D03*
X1388353Y1099017D03*
X1386504Y1102221D03*
X1382803Y1108630D03*
Y1102221D03*
X1380954Y1111834D03*
X1380953Y1118243D03*
X1386503Y1115039D03*
X1384653Y1118243D03*
X1382803Y1115039D03*
X1386503Y1127856D03*
X1380953Y1131060D03*
X1386503Y1140973D03*
X1384653Y1131060D03*
X1408269Y844971D03*
X1402721Y841467D03*
X1397171Y851380D03*
X1408271D03*
X1404571D03*
X1400871D03*
X1397171Y864197D03*
X1408271D03*
X1404571D03*
X1402721Y854584D03*
X1400871Y864197D03*
X1410121Y854584D03*
Y867401D03*
X1402721D03*
X1397171Y877014D03*
X1410121Y880219D03*
X1408271Y877014D03*
X1404571D03*
X1402721Y880219D03*
X1400871Y877014D03*
X1397171Y889832D03*
X1410121Y893036D03*
X1408271Y889832D03*
X1404571D03*
X1402721Y893036D03*
X1400871Y889832D03*
Y902649D03*
X1397171D03*
X1408271D03*
X1404571Y909057D03*
Y902649D03*
Y915466D03*
X1410121Y925079D03*
Y931488D03*
X1403016Y949498D03*
Y947198D03*
X1406420Y937896D03*
X1404016Y936469D03*
X1410120Y937896D03*
X1403046Y963634D03*
Y965934D03*
Y978035D03*
Y980335D03*
Y992421D03*
Y994721D03*
Y1009174D03*
Y1006874D03*
Y1021962D03*
Y1019662D03*
X1397604Y1063770D03*
Y1082995D03*
Y1095813D03*
X1428620Y848176D03*
X1415669Y844971D03*
X1421220Y848176D03*
X1417520D03*
X1423070Y851380D03*
X1419370D03*
X1415671D03*
X1413822Y860993D03*
X1426771Y864197D03*
X1424921Y854584D03*
X1423071Y864197D03*
X1419371D03*
X1417521Y854584D03*
X1415671Y864197D03*
Y857789D03*
X1424921Y867401D03*
X1417521D03*
X1424921Y880219D03*
X1423071Y877014D03*
X1419371D03*
X1417521Y880219D03*
X1415671Y877014D03*
X1413820Y886627D03*
X1426771Y889832D03*
X1424921Y893036D03*
X1423071Y889832D03*
X1419371D03*
X1417521Y893036D03*
X1415671Y896240D03*
Y889832D03*
X1413821Y899445D03*
Y905853D03*
X1426771Y902649D03*
X1423071Y909057D03*
Y902649D03*
X1419371D03*
X1415670D03*
X1423071Y915466D03*
Y928283D03*
X1417520Y925079D03*
Y931488D03*
X1413820Y918670D03*
X1423071Y921875D03*
X1424920Y937896D03*
X1421220D03*
X1417520D03*
X1413820D03*
X1427203Y1044544D03*
X1425353Y1047749D03*
X1429053Y1060565D03*
X1423503Y1057361D03*
Y1050952D03*
Y1063770D03*
X1425353Y1073383D03*
X1423503Y1076587D03*
Y1070178D03*
X1429053Y1079791D03*
X1425353D03*
X1425354Y1086200D03*
X1423503Y1082995D03*
X1437871Y851380D03*
X1434171D03*
X1430470D03*
X1432321Y841467D03*
X1439721D03*
X1445271Y851380D03*
X1441571D03*
X1439721Y854584D03*
X1432321D03*
X1437871Y864197D03*
X1434171D03*
X1430471D03*
X1445271D03*
X1441571D03*
X1432321Y867401D03*
X1439721D03*
X1437871Y877014D03*
X1434171D03*
X1432321Y880219D03*
X1430471Y877014D03*
X1445271D03*
X1441571D03*
X1439721Y880219D03*
X1437871Y889832D03*
X1434171D03*
X1432321Y893036D03*
X1430471Y889832D03*
X1445271Y896240D03*
X1439721Y893036D03*
X1445271Y889832D03*
X1441571D03*
X1437871Y902649D03*
X1434171D03*
X1432320Y905853D03*
X1430471Y902649D03*
X1441571D03*
Y909057D03*
Y915466D03*
X1430244Y931358D03*
Y933658D03*
X1432320Y918670D03*
X1430575Y1022185D03*
Y1019885D03*
X1443541Y1036914D03*
X1436453Y1041340D03*
X1442003Y1044544D03*
X1432753Y1047749D03*
X1440153D03*
X1432753Y1054157D03*
X1442004Y1057361D03*
X1438304Y1050952D03*
X1434604Y1063770D03*
X1442004D03*
X1432753Y1073383D03*
X1430903Y1076587D03*
X1430904Y1070178D03*
X1443853Y1073383D03*
Y1066974D03*
X1438304Y1070178D03*
X1432754Y1079791D03*
X1443853D03*
X1434603Y1082995D03*
X1432753Y1086200D03*
X1436453Y1092608D03*
X1443854Y1086200D03*
X1440153D03*
X1443854Y1092608D03*
X1442003Y1108630D03*
Y1102221D03*
X1440154Y1099017D03*
X1443853Y1105426D03*
Y1111834D03*
X1454521Y841467D03*
X1447121D03*
X1460071Y851380D03*
X1452671D03*
X1456371D03*
X1448971D03*
X1460071Y864197D03*
X1456371D03*
X1454521Y854584D03*
X1452671Y864197D03*
X1447121Y854584D03*
X1448971Y864197D03*
X1454521Y867401D03*
X1447121D03*
X1460071Y877014D03*
X1456371D03*
X1454521Y880219D03*
X1452671Y877014D03*
X1448971D03*
X1448970Y870606D03*
X1447121Y880219D03*
Y873810D03*
X1456370Y896240D03*
X1456371Y889832D03*
X1454521Y893036D03*
X1447121D03*
X1460071Y889832D03*
X1452671D03*
X1448971D03*
X1458220Y899445D03*
X1460071Y909057D03*
X1458221Y912262D03*
X1450820Y905853D03*
X1460070Y902649D03*
X1452426Y930125D03*
X1460071Y928283D03*
X1458220Y918670D03*
X1456371Y921875D03*
X1460070D03*
X1452670D03*
X1450820Y918670D03*
X1458220Y931488D03*
X1452426Y934725D03*
X1454520Y944304D03*
X1452321Y945354D03*
Y947654D03*
X1460070Y941100D03*
X1458221Y944304D03*
X1458220Y937896D03*
X1456371Y934691D03*
X1460070Y947509D03*
X1452426Y962325D03*
Y960025D03*
Y964625D03*
X1460070Y960326D03*
X1458220Y957122D03*
X1458221Y950713D03*
X1460071Y966735D03*
X1452426Y966925D03*
X1452333Y977669D03*
X1452476Y980736D03*
X1458221Y969939D03*
X1460070Y979552D03*
X1458220Y976347D03*
X1452426Y996825D03*
Y994525D03*
Y989925D03*
Y987625D03*
X1452436Y1010499D03*
X1452426Y1006025D03*
Y1003725D03*
Y1012925D03*
X1460503Y999684D03*
X1458654Y1009297D03*
X1458653Y1002888D03*
X1460504Y1012501D03*
X1452416Y1022635D03*
X1452426Y1017525D03*
X1458653Y1028523D03*
Y1022114D03*
X1460503Y1018910D03*
Y1031727D03*
X1447424Y1036526D03*
X1449649Y1035928D03*
X1458653Y1041340D03*
X1458654Y1034931D03*
X1451253Y1041340D03*
X1460503Y1038136D03*
X1458653Y1047749D03*
X1447553D03*
X1460503Y1057361D03*
X1458653Y1060565D03*
X1456804Y1050952D03*
X1451253Y1060565D03*
X1447553Y1054157D03*
X1460504Y1050952D03*
X1460503Y1076587D03*
X1451253Y1066974D03*
X1449404Y1070178D03*
X1460504D03*
X1458654Y1066974D03*
X1454953Y1073383D03*
X1458653Y1079791D03*
X1454954D03*
X1451253D03*
X1445703Y1089404D03*
X1458654Y1086200D03*
X1456804Y1082995D03*
X1453104Y1089404D03*
X1449404Y1082995D03*
X1460504Y1089404D03*
X1445704Y1095813D03*
X1460504D03*
X1456803D03*
X1445704Y1102221D03*
X1458653Y1105426D03*
X1456804Y1108630D03*
X1454953Y1099017D03*
X1449404Y1108630D03*
X1453104Y1102221D03*
X1451254Y1099017D03*
X1447553D03*
X1458653Y1111834D03*
X1460504Y1108630D03*
X1451253Y1111834D03*
X1447553D03*
X1454953Y1105426D03*
X1445704Y1108630D03*
X1449404Y1102221D03*
X1458653Y1099017D03*
X1454953Y1111834D03*
X1453104Y1108630D03*
X1447553Y1105426D03*
X1451253D03*
X1460504Y1102221D03*
X1458653Y1118243D03*
X1456803Y1115039D03*
X1454953Y1118243D03*
X1453103Y1115039D03*
X1451253Y1118243D03*
X1460503Y1127856D03*
X1453103D03*
X1460504Y1115039D03*
X1449404D03*
X1458653Y1131060D03*
X1454953D03*
X1453103Y1140973D03*
X1451253Y1131060D03*
X1449403Y1134264D03*
X1460503Y1140973D03*
X1469321Y841467D03*
X1461921D03*
X1476721D03*
X1474871Y851380D03*
X1471171D03*
X1467471D03*
X1463771D03*
X1461921Y854584D03*
X1474871Y864197D03*
X1471171D03*
X1469321Y854584D03*
X1467471Y864197D03*
X1463771D03*
X1476721Y854584D03*
X1461921Y867401D03*
X1476721D03*
X1469321D03*
X1461921Y880219D03*
X1471171Y877014D03*
X1476721Y880219D03*
X1474871Y877014D03*
X1469321Y880219D03*
X1467471Y877014D03*
X1463771D03*
X1474871Y889832D03*
X1465621Y893036D03*
X1476721D03*
X1474871Y896240D03*
X1471171Y889832D03*
X1467471D03*
X1463771D03*
X1473021Y899445D03*
X1465620D03*
X1461920Y905853D03*
X1473020Y912262D03*
X1471171Y909057D03*
X1465620Y905853D03*
X1471171Y902649D03*
X1469321Y905853D03*
X1474870Y915466D03*
X1461920Y925079D03*
X1471170Y928283D03*
X1469321Y925079D03*
X1465620D03*
Y918670D03*
X1473021D03*
X1471171Y921875D03*
X1473020Y931488D03*
X1465620D03*
X1461920Y944304D03*
X1474871Y934691D03*
X1473021Y937896D03*
X1471171Y941100D03*
X1469321Y944304D03*
X1465620D03*
Y937896D03*
X1471170Y947509D03*
X1474871Y953917D03*
X1473021Y957122D03*
X1471171Y960326D03*
X1465620Y957122D03*
Y950713D03*
X1473020D03*
X1461920Y963530D03*
X1476721D03*
X1471170Y966735D03*
X1469321Y963530D03*
X1465620D03*
X1473021Y976347D03*
X1473020Y969939D03*
X1465620Y976347D03*
Y969939D03*
X1474870Y973143D03*
X1471171Y979552D03*
X1461920Y982756D03*
X1469321D03*
X1465620D03*
X1475303Y1006093D03*
X1473453Y1009297D03*
X1473454Y1002888D03*
X1471604Y999684D03*
X1466053Y1009297D03*
X1466054Y1002888D03*
X1467903Y1006093D03*
X1464204D03*
X1471603Y1012501D03*
X1462353Y1015705D03*
X1473453Y1028523D03*
X1466053D03*
Y1022114D03*
Y1015705D03*
X1477154D03*
X1475303Y1025318D03*
X1473453Y1022114D03*
X1471604Y1018910D03*
X1469754Y1015705D03*
X1471603Y1031727D03*
X1462353Y1034931D03*
X1473454Y1041340D03*
X1466053D03*
Y1034931D03*
X1475303Y1044544D03*
X1471604Y1038136D03*
X1469754Y1034931D03*
X1466053Y1047749D03*
X1473453D03*
X1462353Y1054157D03*
X1473453Y1060565D03*
X1471604Y1057361D03*
X1466053Y1060565D03*
Y1054157D03*
X1471603Y1050952D03*
X1469753Y1054157D03*
X1475304Y1063770D03*
X1462353Y1073383D03*
X1471604Y1076587D03*
X1469754Y1073383D03*
X1466053Y1066974D03*
X1473453D03*
X1471603Y1070178D03*
X1466053Y1073383D03*
X1473454Y1079791D03*
X1466053D03*
X1462353Y1092608D03*
X1475303Y1082995D03*
X1473453Y1086200D03*
X1469754Y1092608D03*
X1466053D03*
Y1086200D03*
X1471603Y1089404D03*
X1475304Y1095813D03*
X1471604D03*
X1467904D03*
X1462353Y1105426D03*
X1462354Y1099017D03*
X1475303Y1108630D03*
Y1102221D03*
X1473454Y1105426D03*
X1469753D03*
X1467904Y1102221D03*
X1464203D03*
X1473454Y1111834D03*
X1466053D03*
Y1099017D03*
X1471604Y1102221D03*
X1477153Y1099017D03*
X1469753D03*
X1473453D03*
X1466053Y1105426D03*
X1462353Y1111834D03*
X1467904Y1108630D03*
X1464204D03*
X1462353Y1118243D03*
X1477153D03*
X1475303Y1115039D03*
X1473453Y1118243D03*
X1471604Y1121447D03*
X1469754Y1118243D03*
X1466053D03*
X1475303Y1127856D03*
X1467903D03*
X1467904Y1115039D03*
X1471604D03*
X1462353Y1131060D03*
X1477153D03*
X1475303Y1140973D03*
X1473453Y1131060D03*
X1469753D03*
X1466053D03*
X1467903Y1140973D03*
X1491521Y841467D03*
X1484121D03*
X1478571Y851380D03*
X1482271D03*
X1489671D03*
X1485971D03*
X1493371D03*
X1478571Y864197D03*
X1491521Y854584D03*
X1489671Y864197D03*
X1485971D03*
X1482271D03*
X1493371D03*
X1491521Y867401D03*
X1484121D03*
Y854584D03*
X1478571Y877014D03*
X1491521Y880219D03*
X1485971Y877014D03*
X1484121Y880219D03*
X1489671Y877014D03*
X1482271D03*
X1493371D03*
X1478570Y896240D03*
X1478571Y889832D03*
X1491521Y893036D03*
X1482271Y889832D03*
X1489671D03*
X1485971D03*
X1482270Y896240D03*
X1480421Y893036D03*
X1493371Y889832D03*
X1491520Y899445D03*
X1484120D03*
X1478571Y909057D03*
Y902649D03*
X1491520Y912262D03*
X1487820Y905853D03*
X1485971Y909057D03*
X1484121Y912262D03*
X1491520Y905853D03*
X1485970Y902649D03*
X1478571Y915466D03*
X1482271D03*
X1478571Y928283D03*
Y921875D03*
X1491520Y925079D03*
Y918670D03*
X1487820Y925079D03*
X1485971Y928283D03*
X1485970Y921875D03*
X1484120Y918670D03*
X1491520Y931488D03*
X1484121D03*
X1478571Y941100D03*
Y934691D03*
X1491520Y944304D03*
Y937896D03*
X1487820Y944304D03*
X1485970Y941100D03*
X1482271Y934691D03*
X1478571Y947509D03*
Y960326D03*
Y953917D03*
X1491520Y957122D03*
Y950713D03*
X1485970Y960326D03*
X1484120Y957122D03*
X1482271Y953917D03*
X1484121Y950713D03*
X1478570Y966735D03*
X1491520Y963530D03*
X1485971Y966735D03*
X1487820Y963530D03*
X1480420D03*
X1478571Y979552D03*
Y973143D03*
X1491521Y976347D03*
X1491520Y969939D03*
X1484120Y976347D03*
X1484121Y969939D03*
X1489671Y973143D03*
X1485970Y979552D03*
X1482271Y973143D03*
X1493370D03*
X1491520Y982756D03*
X1487820D03*
X1479004Y999684D03*
X1486403D03*
X1484553Y1002888D03*
X1482704Y1006093D03*
X1479003Y1012501D03*
X1486404D03*
X1491953Y1009297D03*
Y1002888D03*
X1484554Y1009297D03*
X1479004Y1025318D03*
Y1018910D03*
X1491953Y1028523D03*
Y1022114D03*
X1484553Y1028523D03*
X1486403Y1018910D03*
X1484553Y1022114D03*
X1482704Y1025318D03*
X1480853Y1015705D03*
X1479004Y1031727D03*
X1486404D03*
X1488253Y1015705D03*
X1491953D03*
X1479004Y1044544D03*
Y1038136D03*
X1491953Y1034931D03*
Y1041340D03*
X1488253Y1034931D03*
X1486403Y1038136D03*
X1484553Y1041340D03*
X1482704Y1044544D03*
X1491953Y1047749D03*
X1484553D03*
X1479004Y1057361D03*
Y1050952D03*
X1491953Y1054157D03*
X1486404Y1057361D03*
X1484553Y1060565D03*
X1488253Y1054157D03*
X1486404Y1050952D03*
X1491953Y1060565D03*
X1479004Y1063770D03*
X1482704D03*
X1479004Y1076587D03*
Y1070178D03*
X1486404Y1076587D03*
Y1070178D03*
X1488253Y1073383D03*
X1484553Y1066974D03*
X1491953Y1073383D03*
Y1066974D03*
X1484553Y1079791D03*
X1491953D03*
X1479004Y1089404D03*
Y1082995D03*
X1488254Y1092608D03*
X1486404Y1089404D03*
X1484554Y1086200D03*
X1482704Y1082995D03*
X1491954Y1092608D03*
X1479004Y1095813D03*
X1490103D03*
X1493804D03*
X1479004Y1102221D03*
X1490104Y1108630D03*
Y1102221D03*
X1488254Y1099017D03*
X1484553D03*
X1482704Y1108630D03*
X1480853Y1099017D03*
X1491953Y1105426D03*
Y1111834D03*
X1493804Y1108630D03*
X1490103Y1115039D03*
X1488253Y1118243D03*
X1484553D03*
X1480853D03*
X1486403Y1115039D03*
X1491953Y1118243D03*
X1490103Y1127856D03*
X1482703D03*
X1493804Y1115039D03*
X1490103Y1140973D03*
X1488253Y1131060D03*
X1484553D03*
X1480853D03*
X1482703Y1140973D03*
X1491953Y1131060D03*
X1504471Y844671D03*
X1498921Y841467D03*
X1508171Y851380D03*
X1504471D03*
X1500771D03*
X1497071D03*
X1504471Y864197D03*
X1500771D03*
X1508170Y857789D03*
X1497071Y864197D03*
X1506321Y860993D03*
Y854584D03*
X1498921D03*
X1510021Y860993D03*
X1506320Y867401D03*
X1498921D03*
X1510021D03*
X1504471Y877014D03*
X1498921Y880219D03*
X1508171Y877014D03*
X1497071D03*
X1506321Y880219D03*
X1500771Y877014D03*
X1510021Y880219D03*
Y873810D03*
X1508170Y883423D03*
X1508171Y889832D03*
X1504471Y896240D03*
Y889832D03*
X1500771D03*
X1508171Y896240D03*
X1502621Y893036D03*
X1500771Y896240D03*
X1497071Y889832D03*
X1510021Y893036D03*
X1498921Y899445D03*
X1510021D03*
X1495221Y905853D03*
X1504471Y902649D03*
X1498920Y912262D03*
X1497070Y909057D03*
X1497071Y902649D03*
X1508171Y915466D03*
X1504471D03*
X1500770D03*
X1504471Y909057D03*
X1510021Y912262D03*
X1495221Y925079D03*
X1504471Y921875D03*
X1497070Y928283D03*
X1498921Y918670D03*
X1497071Y921875D03*
X1498920Y931488D03*
X1504471Y928283D03*
X1510021Y918670D03*
X1510020Y931488D03*
X1495221Y944304D03*
X1504471Y941100D03*
Y934691D03*
X1500770D03*
X1498921Y937896D03*
X1497071Y941100D03*
X1497070Y947509D03*
X1508171Y934691D03*
X1510021Y937896D03*
X1504471Y947509D03*
Y960326D03*
Y953917D03*
X1500771D03*
X1498921Y957122D03*
X1497071Y960326D03*
X1498920Y950713D03*
X1495221Y963530D03*
X1497070Y966735D03*
X1502621Y963530D03*
X1510021Y957122D03*
X1508171Y953917D03*
X1510021Y950713D03*
X1506320Y963530D03*
X1504471Y966735D03*
Y979552D03*
Y973143D03*
X1498921Y976347D03*
X1498920Y969939D03*
X1500770Y973143D03*
X1497071Y979552D03*
X1510021Y976347D03*
X1495221Y982756D03*
X1510043Y980606D03*
X1510021Y969939D03*
X1508171Y973143D03*
X1497503Y1012501D03*
Y999684D03*
X1504904Y1006093D03*
Y999684D03*
X1501203Y1006093D03*
X1499353Y1009297D03*
X1499354Y1002888D03*
X1510453Y1009297D03*
Y1002888D03*
X1508603Y1006093D03*
X1504903Y1012501D03*
X1504904Y1025318D03*
X1499353Y1028523D03*
X1501203Y1025318D03*
X1504904Y1031727D03*
X1497503D03*
X1495654Y1015705D03*
X1497504Y1018910D03*
X1499353Y1022114D03*
X1503054Y1015705D03*
X1504904Y1018910D03*
X1506753Y1015705D03*
X1510453Y1028523D03*
X1510452Y1022114D03*
X1508603Y1025318D03*
X1504904Y1044544D03*
X1501203D03*
X1499354Y1041340D03*
X1497504Y1038136D03*
X1495654Y1034931D03*
X1508604Y1044544D03*
X1499353Y1047749D03*
X1504904Y1038136D03*
X1510453Y1041340D03*
Y1047749D03*
X1504904Y1057361D03*
Y1050952D03*
X1499354Y1060565D03*
X1497504Y1057361D03*
X1497503Y1050952D03*
X1495654Y1054157D03*
X1504904Y1063770D03*
X1501203D03*
X1510453Y1060565D03*
X1508604Y1063770D03*
X1504904Y1076587D03*
Y1070178D03*
X1497504Y1076587D03*
X1497503Y1070178D03*
X1495654Y1073383D03*
X1499353Y1066974D03*
X1499354Y1079791D03*
X1510453Y1066974D03*
Y1079791D03*
X1499353Y1086200D03*
X1497503Y1089404D03*
X1495653Y1092608D03*
X1504904Y1089404D03*
Y1082995D03*
X1501203D03*
X1508604Y1082996D03*
X1510453Y1086200D03*
X1504903Y1095813D03*
X1503053Y1105426D03*
X1497503Y1102221D03*
X1495653Y1105426D03*
X1495654Y1099017D03*
X1508603Y1108630D03*
X1506754Y1111834D03*
X1499353D03*
X1503053Y1099017D03*
X1510453D03*
X1508602Y1102221D03*
X1497504Y1108630D03*
X1501204D03*
X1510453Y1111834D03*
X1499353Y1105426D03*
X1510453D03*
X1504904Y1108630D03*
X1495653Y1111834D03*
X1503053D03*
X1506753Y1124651D03*
Y1118243D03*
X1504904Y1121447D03*
X1499353Y1118243D03*
X1497503Y1115039D03*
X1495653Y1118243D03*
X1508603Y1115039D03*
X1504904Y1127856D03*
X1497503D03*
X1501204Y1115039D03*
X1504904D03*
X1506754Y1137469D03*
X1506753Y1131060D03*
X1503053D03*
X1499353D03*
X1495653D03*
X1504904Y1134264D03*
X1497503Y1140973D03*
X1510453Y1131060D03*
X1511871Y844671D03*
X1513722Y848176D03*
X1511871Y851380D03*
X1521121Y860993D03*
Y854584D03*
X1515570Y864197D03*
X1513721Y854584D03*
Y860993D03*
X1521121Y867401D03*
X1517421D03*
X1513721D03*
X1511871Y870606D03*
X1522971D03*
X1517421Y873810D03*
X1511871Y883423D03*
X1517421Y880219D03*
X1522971Y883423D03*
X1511871Y889832D03*
X1513721Y893036D03*
X1517421Y886627D03*
X1521121D03*
X1513721D03*
X1526671Y889832D03*
X1513721Y899445D03*
X1524821Y912262D03*
X1511871Y909057D03*
Y902649D03*
X1513721Y912262D03*
X1515571Y909057D03*
X1524821Y905853D03*
X1513721D03*
X1519271Y909057D03*
X1511871Y921875D03*
X1513721Y918670D03*
X1524820Y931488D03*
X1513720D03*
X1511871Y941100D03*
X1513721Y937896D03*
X1511871Y947509D03*
X1519271D03*
X1515571D03*
X1511871Y960326D03*
X1513721Y957122D03*
Y950713D03*
X1511871Y966735D03*
X1513721Y963530D03*
X1515571Y979552D03*
X1513721Y982756D03*
X1511871Y973143D03*
X1517421Y969939D03*
X1515571Y973143D03*
X1516004Y1006092D03*
X1516003Y999684D03*
X1512303D03*
Y1006093D03*
X1519705Y1006092D03*
X1525396Y1000648D03*
X1512303Y1012501D03*
Y1025318D03*
X1516003Y1018910D03*
X1517854Y1015705D03*
X1525254D03*
X1521554D03*
X1514154D03*
X1512303Y1018910D03*
Y1031727D03*
X1525254Y1034931D03*
X1521554D03*
X1516004Y1044544D03*
X1516003Y1038136D03*
X1517853Y1034931D03*
X1514153D03*
X1512303Y1038136D03*
X1517853Y1054157D03*
X1514153D03*
X1512303Y1057361D03*
X1521553Y1054157D03*
X1514153Y1060565D03*
X1512303Y1050952D03*
X1525564Y1064850D03*
X1523404Y1070178D03*
X1514153Y1066974D03*
X1517853Y1073383D03*
X1521553Y1066974D03*
X1516003Y1076587D03*
X1512303D03*
X1512304Y1070178D03*
X1514153Y1073383D03*
X1523404Y1082996D03*
X1512304D03*
X1514153Y1092608D03*
X1512303Y1089404D03*
X1521553Y1092608D03*
X1523403Y1095813D03*
X1519703D03*
X1512303D03*
X1521554Y1105426D03*
X1517853D03*
X1516003Y1108630D03*
Y1102221D03*
X1512303D03*
X1517853Y1111834D03*
X1521553D03*
X1514153Y1105426D03*
X1512303Y1108630D03*
X1514153Y1111834D03*
X1519703Y1108630D03*
X1521553Y1124651D03*
Y1118243D03*
X1519704Y1115039D03*
X1516004D03*
X1514153Y1124651D03*
X1512303Y1115039D03*
X1517854Y1131560D03*
X1512304Y1134264D03*
X1527571Y979057D03*
X1526843Y972608D03*
X1527103Y1031726D03*
X1665141Y1051247D03*
X1724541D03*
G54D44*
X333834Y1062790D03*
X329632Y1092168D03*
X335344Y1097289D03*
X549719Y962436D03*
X548146Y965640D03*
X543729Y984866D03*
X1309976Y1062790D03*
X1305774Y1092168D03*
X1311486Y1097289D03*
X1337102Y206675D03*
X1525861Y962436D03*
X1524288Y965640D03*
X1519871Y984866D03*
X1879155Y468898D03*
Y716798D03*
X1889155Y468898D03*
Y716798D03*
X1900275Y840758D03*
X1910275D03*
X1921395Y-19332D03*
X1931395D03*
X1942395Y593048D03*
X1952395D03*
X1963362Y-19190D03*
X1973362D03*
X1984482Y593020D03*
X1994482D03*
X2005452Y-19180D03*
X2015452D03*
X2026452Y593200D03*
X2047419Y-19038D03*
X2036452Y593200D03*
X2057419Y-19038D03*
X2068539Y593172D03*
X2078539D03*
G54D53*
X717313Y-27626D03*
Y-21471D03*
Y-17597D03*
X717298Y-15082D03*
X717313Y-11442D03*
X717298Y-25111D03*
X717313Y-7568D03*
X717298Y-5053D03*
X834273Y2374D03*
X834258Y4889D03*
X834273Y22432D03*
Y8529D03*
Y12403D03*
X834258Y14918D03*
X834273Y18558D03*
X834258Y24947D03*
X1026705Y-27695D03*
Y-38224D03*
X1023437Y-38210D03*
X1026690Y-35709D03*
X1023422Y-35695D03*
X1026705Y-32069D03*
Y-17666D03*
X1026690Y-15151D03*
X1026705Y-11511D03*
X1026690Y-25180D03*
X1026705Y-21540D03*
X1026690Y4907D03*
X1026705Y2392D03*
X1026690Y-5122D03*
X1026705Y-7637D03*
Y-1482D03*
Y22450D03*
Y18576D03*
Y8547D03*
X1026690Y14936D03*
X1026705Y12421D03*
X1026690Y24965D03*
X1336024Y-27695D03*
Y-32069D03*
X1332741Y-35695D03*
X1336009Y-35709D03*
X1332756Y-38210D03*
X1336024Y-38224D03*
Y-11511D03*
X1336009Y-15151D03*
X1336024Y-17666D03*
Y-21540D03*
X1336009Y-25180D03*
X1336024Y2392D03*
X1336009Y4907D03*
X1336024Y-1482D03*
Y-7637D03*
X1336009Y-5122D03*
X1336024Y18576D03*
Y22450D03*
Y12421D03*
X1336009Y14936D03*
X1336024Y8547D03*
X1336009Y24965D03*
G54D63*
X918780Y1684890D03*
Y1694890D03*
Y1714890D03*
X928780Y1684890D03*
X938780D03*
X928780Y1694890D03*
X938780D03*
X928780Y1704890D03*
X938780D03*
X928780Y1714890D03*
X938780D03*
G54D73*
X1879155Y354948D03*
Y458898D03*
Y478898D03*
Y582848D03*
Y602848D03*
Y706798D03*
Y726798D03*
Y830748D03*
X1900275Y-9342D03*
X1889155Y354948D03*
Y458898D03*
Y478898D03*
X1900275Y582858D03*
X1889155Y582848D03*
Y602848D03*
Y706798D03*
X1900275Y726808D03*
X1889155Y726798D03*
X1900275Y830758D03*
X1889155Y830748D03*
X1900275Y850758D03*
Y954708D03*
X1910275Y-9342D03*
Y582858D03*
Y726808D03*
Y830758D03*
Y850758D03*
Y954708D03*
X1921395Y-9332D03*
X1931395D03*
Y582868D03*
X1921395D03*
X1931395Y602868D03*
X1921395D03*
Y1195068D03*
X1931395D03*
X1942395Y-9152D03*
Y583048D03*
Y603048D03*
Y1195248D03*
X1963362Y-9190D03*
X1952395Y-9152D03*
X1963362Y583010D03*
X1952395Y583048D03*
X1963362Y603010D03*
X1952395Y603048D03*
X1963362Y1195210D03*
X1952395Y1195248D03*
X1973362Y-9190D03*
Y583010D03*
Y603010D03*
Y1195210D03*
X1994482Y-9180D03*
X1984482D03*
Y583020D03*
X1994482D03*
X1984482Y603020D03*
X1994482D03*
Y1195220D03*
X1984482D03*
X2005452Y-9180D03*
X2015452D03*
Y583020D03*
X2005452D03*
X2015452Y603020D03*
X2005452D03*
Y1195220D03*
X2015452D03*
X2026452Y-9000D03*
Y583200D03*
Y603200D03*
Y1195400D03*
X2047419Y-9038D03*
X2036452Y-9000D03*
X2047419Y583162D03*
X2036452Y583200D03*
X2047419Y603162D03*
X2036452Y603200D03*
X2047419Y1195362D03*
X2036452Y1195400D03*
X2057419Y-9038D03*
Y583162D03*
Y603162D03*
Y1195362D03*
X2068539Y603172D03*
X2078539D03*
Y1195372D03*
X2068539D03*
G54D74*
X1879155Y468898D03*
Y716798D03*
X1889155Y468898D03*
X1900275Y592858D03*
X1889155Y716798D03*
X1900275Y840758D03*
X1910275Y592858D03*
Y840758D03*
X1921395Y1205068D03*
X1931395D03*
X1942395Y593048D03*
X1952395D03*
X1963362Y1205210D03*
X1984482Y593020D03*
X1973362Y1205210D03*
X1994482Y593020D03*
X2005452Y1205220D03*
X2015452D03*
X2026452Y593200D03*
X2036452D03*
X2047419Y1205362D03*
X2057419D03*
G54D50*
X676508Y224606D03*
G54D24*
X36399Y960892D03*
Y957546D03*
Y967585D03*
Y1054593D03*
X52541Y964239D03*
Y1021129D03*
Y1024475D03*
Y1051247D03*
X66099Y780184D03*
Y773491D03*
Y786877D03*
Y803609D03*
Y796916D03*
Y790223D03*
Y816995D03*
Y810302D03*
Y833727D03*
Y823688D03*
Y827034D03*
Y847113D03*
Y840420D03*
Y853806D03*
Y860499D03*
Y863845D03*
Y883924D03*
Y877231D03*
Y870538D03*
Y890617D03*
Y897310D03*
Y900656D03*
Y914042D03*
Y907349D03*
Y927428D03*
Y920735D03*
Y934121D03*
Y944160D03*
Y937467D03*
Y960892D03*
Y950853D03*
Y957546D03*
Y980971D03*
Y974278D03*
Y967585D03*
Y994357D03*
Y987664D03*
Y1027822D03*
Y1021129D03*
Y1047900D03*
Y1041207D03*
Y1034515D03*
Y1054593D03*
Y1074672D03*
Y1067979D03*
Y1091404D03*
Y1081365D03*
Y1084711D03*
Y1098097D03*
Y1111483D03*
Y1104790D03*
Y1128215D03*
Y1118176D03*
Y1121522D03*
Y1141601D03*
Y1134908D03*
Y1148294D03*
Y1154987D03*
Y1158333D03*
Y1171719D03*
Y1165026D03*
Y1185105D03*
Y1178412D03*
Y1191798D03*
Y1208530D03*
Y1201837D03*
Y1195144D03*
Y1221916D03*
Y1215223D03*
Y1238648D03*
Y1228609D03*
Y1231955D03*
Y1245341D03*
X82241Y770144D03*
Y776837D03*
Y786877D03*
Y783530D03*
Y800263D03*
Y793570D03*
Y813648D03*
Y806955D03*
Y820341D03*
Y830381D03*
Y823688D03*
Y850459D03*
Y843766D03*
Y837074D03*
Y867192D03*
Y860499D03*
Y857152D03*
Y873885D03*
Y880577D03*
Y887270D03*
Y897310D03*
Y893963D03*
Y917389D03*
Y910696D03*
Y904003D03*
Y924081D03*
Y934121D03*
Y930774D03*
Y947507D03*
Y940814D03*
Y964239D03*
Y977625D03*
Y970932D03*
Y991011D03*
Y984318D03*
Y1021129D03*
Y1024475D03*
Y1031168D03*
Y1044554D03*
Y1037861D03*
Y1051247D03*
Y1071326D03*
Y1064633D03*
Y1078018D03*
Y1094751D03*
Y1088058D03*
Y1081365D03*
Y1108137D03*
Y1101444D03*
Y1124869D03*
Y1118176D03*
Y1114829D03*
Y1144948D03*
Y1138255D03*
Y1131562D03*
Y1161680D03*
Y1154987D03*
Y1151641D03*
Y1175066D03*
Y1168373D03*
Y1181759D03*
Y1191798D03*
Y1188452D03*
Y1205184D03*
Y1198491D03*
Y1218570D03*
Y1211877D03*
Y1225263D03*
Y1241995D03*
Y1235302D03*
Y1228609D03*
X95799Y960892D03*
Y957546D03*
Y967585D03*
Y1054593D03*
X125499Y780184D03*
Y773491D03*
Y786877D03*
Y803609D03*
Y796916D03*
Y790223D03*
Y816995D03*
Y810302D03*
Y833727D03*
Y823688D03*
Y827034D03*
Y847113D03*
Y840420D03*
Y853806D03*
Y860499D03*
Y863845D03*
Y883924D03*
Y877231D03*
Y870538D03*
Y890617D03*
Y897310D03*
Y900656D03*
Y914042D03*
Y907349D03*
Y927428D03*
Y920735D03*
Y934121D03*
Y944160D03*
Y937467D03*
Y960892D03*
Y950853D03*
X111941Y964239D03*
X125499Y957546D03*
Y980971D03*
Y974278D03*
Y967585D03*
Y994357D03*
Y987664D03*
X111941Y1021129D03*
Y1024475D03*
X125499Y1027822D03*
Y1021129D03*
Y1047900D03*
Y1041207D03*
Y1034515D03*
X111941Y1051247D03*
X125499Y1054593D03*
Y1074672D03*
Y1067979D03*
Y1091404D03*
Y1081365D03*
Y1084711D03*
Y1098097D03*
Y1111483D03*
Y1104790D03*
Y1128215D03*
Y1118176D03*
Y1121522D03*
Y1141601D03*
Y1134908D03*
Y1148294D03*
Y1154987D03*
Y1158333D03*
Y1171719D03*
Y1165026D03*
Y1185105D03*
Y1178412D03*
Y1191798D03*
Y1208530D03*
Y1201837D03*
Y1195144D03*
Y1221916D03*
Y1215223D03*
Y1238648D03*
Y1228609D03*
Y1231955D03*
Y1245341D03*
X141641Y770144D03*
Y776837D03*
Y786877D03*
Y783530D03*
Y800263D03*
Y793570D03*
Y813648D03*
Y806955D03*
Y820341D03*
Y830381D03*
Y823688D03*
Y850459D03*
Y843766D03*
Y837074D03*
Y867192D03*
Y860499D03*
Y857152D03*
Y873885D03*
Y880577D03*
Y887270D03*
Y897310D03*
Y893963D03*
Y917389D03*
Y910696D03*
Y904003D03*
Y924081D03*
Y934121D03*
Y930774D03*
Y947507D03*
Y940814D03*
Y964239D03*
Y977625D03*
Y970932D03*
Y991011D03*
Y984318D03*
Y1021129D03*
Y1024475D03*
Y1031168D03*
Y1044554D03*
Y1037861D03*
Y1051247D03*
Y1071326D03*
Y1064633D03*
Y1078018D03*
Y1094751D03*
Y1088058D03*
Y1081365D03*
Y1108137D03*
Y1101444D03*
Y1124869D03*
Y1118176D03*
Y1114829D03*
Y1144948D03*
Y1138255D03*
Y1131562D03*
Y1161680D03*
Y1154987D03*
Y1151641D03*
Y1175066D03*
Y1168373D03*
Y1181759D03*
Y1191798D03*
Y1188452D03*
Y1205184D03*
Y1198491D03*
Y1218570D03*
Y1211877D03*
Y1225263D03*
Y1241995D03*
Y1235302D03*
Y1228609D03*
X155199Y960892D03*
Y957546D03*
Y967585D03*
Y1054593D03*
X171341Y964239D03*
Y1021129D03*
Y1024475D03*
Y1051247D03*
X184899Y780184D03*
Y773491D03*
Y786877D03*
Y803609D03*
Y796916D03*
Y790223D03*
Y816995D03*
Y810302D03*
Y833727D03*
Y823688D03*
Y827034D03*
Y847113D03*
Y840420D03*
Y853806D03*
Y860499D03*
Y863845D03*
Y883924D03*
Y877231D03*
Y870538D03*
Y890617D03*
Y897310D03*
Y900656D03*
Y914042D03*
Y907349D03*
Y927428D03*
Y920735D03*
Y934121D03*
Y944160D03*
Y937467D03*
Y960892D03*
Y950853D03*
Y957546D03*
Y980971D03*
Y974278D03*
Y967585D03*
Y994357D03*
Y987664D03*
Y1027822D03*
Y1021129D03*
Y1047900D03*
Y1041207D03*
Y1034515D03*
Y1054593D03*
Y1074672D03*
Y1067979D03*
Y1091404D03*
Y1081365D03*
Y1084711D03*
Y1098097D03*
Y1111483D03*
Y1104790D03*
Y1128215D03*
Y1118176D03*
Y1121522D03*
Y1141601D03*
Y1134908D03*
Y1148294D03*
Y1154987D03*
Y1158333D03*
Y1171719D03*
Y1165026D03*
Y1185105D03*
Y1178412D03*
Y1191798D03*
Y1208530D03*
Y1201837D03*
Y1195144D03*
Y1221916D03*
Y1215223D03*
Y1238648D03*
Y1228609D03*
Y1231955D03*
Y1245341D03*
X201041Y770144D03*
Y776837D03*
Y786877D03*
Y783530D03*
Y800263D03*
Y793570D03*
Y813648D03*
Y806955D03*
Y820341D03*
Y830381D03*
Y823688D03*
Y850459D03*
Y843766D03*
Y837074D03*
Y867192D03*
Y860499D03*
Y857152D03*
Y873885D03*
Y880577D03*
Y887270D03*
Y897310D03*
Y893963D03*
Y917389D03*
Y910696D03*
Y904003D03*
Y924081D03*
Y934121D03*
Y930774D03*
Y947507D03*
Y940814D03*
Y964239D03*
Y977625D03*
Y970932D03*
Y991011D03*
Y984318D03*
X201141Y1021129D03*
Y1024475D03*
Y1031168D03*
Y1044554D03*
Y1037861D03*
Y1051247D03*
Y1071326D03*
Y1064633D03*
Y1078018D03*
Y1094752D03*
Y1088059D03*
Y1081366D03*
Y1108137D03*
Y1101444D03*
X201041Y1124869D03*
X201141Y1118177D03*
Y1114830D03*
Y1144948D03*
Y1138255D03*
X201041Y1131562D03*
X201141Y1161680D03*
Y1154988D03*
Y1151641D03*
Y1175066D03*
Y1168373D03*
Y1181759D03*
Y1191799D03*
Y1188452D03*
Y1205184D03*
Y1198491D03*
Y1218570D03*
Y1211877D03*
Y1225263D03*
Y1241995D03*
Y1235302D03*
Y1228609D03*
X214599Y960892D03*
Y957546D03*
X244299Y883924D03*
Y890617D03*
Y897310D03*
Y900656D03*
Y914042D03*
Y907349D03*
Y960892D03*
Y957546D03*
Y1185105D03*
Y1178412D03*
Y1191798D03*
Y1208530D03*
Y1201837D03*
Y1195144D03*
X260441Y880577D03*
Y887270D03*
Y897310D03*
Y893963D03*
Y910696D03*
Y904003D03*
Y1175066D03*
Y1181759D03*
Y1191798D03*
Y1188452D03*
Y1205184D03*
Y1198491D03*
X337779Y880219D03*
X335928Y883423D03*
X337779Y893036D03*
X335928Y889832D03*
X334079Y886627D03*
X337779D03*
X336361Y1121447D03*
X350727Y851380D03*
X354427Y844971D03*
X348878Y848176D03*
X352578D03*
X350729Y857789D03*
X352578Y860993D03*
X354429Y857789D03*
X341479Y880219D03*
X343329Y883423D03*
X350729Y870606D03*
X354429D03*
X352578Y873810D03*
X348878Y899445D03*
Y893036D03*
X350729Y889832D03*
X354429D03*
X341478Y893036D03*
X343328Y889832D03*
X347029Y896240D03*
X354429D03*
X341479Y886627D03*
X350729Y896240D03*
X345179Y886627D03*
X348878Y912262D03*
X350729Y909057D03*
X354429D03*
X350729Y902649D03*
X354429D03*
X347029Y915466D03*
X354429D03*
X350729D03*
X348879Y931488D03*
X350729Y928283D03*
X354429D03*
Y921875D03*
X350729D03*
X348878Y918670D03*
X350729Y941100D03*
X348878Y937896D03*
X354429Y941100D03*
X347029Y934691D03*
X354429D03*
X350729D03*
Y947509D03*
X354429D03*
X348878Y950713D03*
X350729Y960326D03*
X348878Y957122D03*
X354429Y960326D03*
X350729Y966735D03*
X354429D03*
X350729Y953917D03*
X354429D03*
X347030D03*
X350729Y979552D03*
X354429D03*
X348878Y976347D03*
X347029Y973143D03*
X348878Y969939D03*
X347461Y1006093D03*
X349311Y1002888D03*
X351161Y999684D03*
X354861D03*
X351161Y1012501D03*
X349311Y1009297D03*
X354861Y1012501D03*
X351162Y1031727D03*
X349311Y1028523D03*
X354861Y1031727D03*
X349311Y1022114D03*
X351161Y1018910D03*
X354861D03*
X347461Y1025318D03*
X354862D03*
X351162D03*
X349311Y1047749D03*
Y1041340D03*
X351161Y1038136D03*
X354861D03*
X347461Y1044544D03*
X354861D03*
X351161D03*
X349311Y1060565D03*
X351161Y1057361D03*
X354861D03*
X347461Y1063770D03*
X351161D03*
X354861D03*
X351161Y1050952D03*
X354861D03*
Y1070178D03*
X351162D03*
X349311Y1066974D03*
Y1079791D03*
X351161Y1076587D03*
X354861D03*
X351161Y1089404D03*
X349311Y1086200D03*
X354861Y1089404D03*
X347461Y1082995D03*
X354861D03*
X351161D03*
X341911Y1105426D03*
X343762Y1108630D03*
X345611Y1111834D03*
X351161Y1102221D03*
X349312Y1111834D03*
X353011Y1105426D03*
X345611D03*
X341912Y1111834D03*
X354861Y1102221D03*
X353012Y1111834D03*
X351162Y1108630D03*
X353011Y1124651D03*
X354861Y1127856D03*
X347461Y1115039D03*
X341912Y1118243D03*
X340061Y1127856D03*
X343761D03*
X347461Y1121447D03*
X340061D03*
X343761D03*
X347461Y1127856D03*
X345611Y1124651D03*
X349312Y1137469D03*
X351161Y1134264D03*
X341911Y1131060D03*
X356279Y841467D03*
X361827Y844971D03*
X363679Y841467D03*
X369227Y844971D03*
X371079Y841467D03*
X358127Y844971D03*
X359978Y848176D03*
X365527Y844971D03*
X367378Y848176D03*
X371078Y867401D03*
X356278D03*
X363678D03*
X356278Y854584D03*
X358129Y857789D03*
X363678Y854584D03*
X365529Y857789D03*
X371078Y854584D03*
X359978Y860993D03*
X361829Y857789D03*
X367378Y860993D03*
X369229Y857789D03*
X358129Y870606D03*
X361829D03*
X365529D03*
X359978Y873810D03*
X367378D03*
X369229Y870606D03*
X356278Y899445D03*
Y893036D03*
X358129Y896240D03*
X363678Y899445D03*
X367378D03*
X371078Y893036D03*
X356278Y912262D03*
X358129Y915466D03*
X363678Y912262D03*
X361829Y909057D03*
X367378Y912262D03*
X369229Y909057D03*
X361829Y902649D03*
X369229D03*
X359978Y905853D03*
X367378D03*
X363678D03*
X371078D03*
X356278Y931488D03*
X363678D03*
X356278Y918670D03*
X361829Y928283D03*
X367378Y931488D03*
X369229Y928283D03*
X361829Y921875D03*
X363678Y918670D03*
X369229Y921875D03*
X367378Y918670D03*
X359978Y925079D03*
X367378D03*
X363678D03*
X371078D03*
X356278Y937896D03*
X358129Y934691D03*
X361829Y941100D03*
X363678Y937896D03*
X369229Y941100D03*
X367378Y937896D03*
X361829Y947509D03*
X369229D03*
X367378Y944304D03*
X359978D03*
X371078D03*
X363678D03*
X356278Y950713D03*
Y957122D03*
X358129Y953917D03*
X361829Y966735D03*
X369229D03*
X359978Y963530D03*
X363678Y950713D03*
X367378D03*
X361829Y960326D03*
X363678Y957122D03*
X369229Y960326D03*
X367378Y957122D03*
X371078Y963530D03*
X359978Y982756D03*
X367378D03*
X363678D03*
X371078D03*
X369229Y979552D03*
X367378Y976347D03*
X361829Y979552D03*
X363678Y976347D03*
X356278D03*
Y969939D03*
X358129Y973143D03*
X363678Y969939D03*
X367378D03*
X358562Y1006093D03*
X356711Y1002888D03*
Y1009297D03*
X362262Y1012501D03*
X369662D03*
X364111Y1009297D03*
X367811D03*
X364111Y1002888D03*
X362262Y999684D03*
X371511Y1002888D03*
X369662Y999684D03*
X356711Y1028523D03*
Y1022114D03*
X362262Y1031727D03*
X364111Y1028523D03*
X369662Y1031727D03*
X367811Y1028523D03*
X358562Y1025318D03*
X360411Y1015705D03*
X371511D03*
X364111Y1022114D03*
X362262Y1018910D03*
X367811Y1022114D03*
X369662Y1018910D03*
X356711Y1047749D03*
Y1041340D03*
X364111D03*
X362262Y1038136D03*
X367811Y1041340D03*
X369662Y1038136D03*
X360411Y1034931D03*
X371511D03*
X364111D03*
X358562Y1044544D03*
X367811Y1034931D03*
X364111Y1047749D03*
X367811D03*
X356711Y1060565D03*
X358562Y1063770D03*
X364111Y1060565D03*
X362262Y1057361D03*
X367811Y1060565D03*
X369662Y1057361D03*
X362262Y1050952D03*
X369662D03*
X360411Y1054157D03*
X371511D03*
X364111D03*
X367811D03*
X356711Y1066974D03*
X367811Y1079791D03*
X369662Y1076587D03*
X362262Y1070178D03*
X364111Y1066974D03*
X369662Y1070178D03*
X367811Y1066974D03*
X356711Y1079791D03*
X364111D03*
X362262Y1076587D03*
X360411Y1073383D03*
X371511D03*
X364111D03*
X367811D03*
X356711Y1086200D03*
X358562Y1082995D03*
X362262Y1095813D03*
X369662D03*
X362262Y1089404D03*
X364111Y1086200D03*
X369662Y1089404D03*
X367811Y1086200D03*
X360411Y1092608D03*
X367811D03*
X364111D03*
X371511D03*
X364111Y1099017D03*
X367811D03*
X358561Y1108630D03*
X360412Y1111834D03*
X364112Y1105426D03*
X369661Y1108630D03*
X362261D03*
X365961D03*
X367812Y1111834D03*
X358561Y1121447D03*
X360412Y1124651D03*
X364111D03*
X367811D03*
X371511D03*
X356712D03*
X362262Y1127856D03*
X365962Y1121447D03*
X369662Y1127856D03*
X365961Y1115039D03*
X358561D03*
X369661D03*
X358561Y1134264D03*
X362261Y1140973D03*
X365962Y1134264D03*
X369661Y1140973D03*
X356712Y1137469D03*
X360412D03*
X364112D03*
X367812D03*
X371512D03*
X387727Y844971D03*
X376627D03*
X380327D03*
X384027D03*
X385879Y841467D03*
X372927Y844971D03*
X374778Y848176D03*
X378479Y841467D03*
X382178Y848176D03*
X378478Y867401D03*
X385878D03*
X387729Y857789D03*
X372929D03*
X378478Y854584D03*
X380329Y857789D03*
X384029D03*
X374778Y860993D03*
X376629Y857789D03*
X382178Y860993D03*
X385878Y854584D03*
X387729Y870606D03*
X372929D03*
X380329D03*
X374778Y873810D03*
X376629Y870606D03*
X382178Y873810D03*
X384029Y870606D03*
X374778Y899445D03*
X382178D03*
Y893036D03*
X374778D03*
X385878D03*
X372929Y896240D03*
X380329D03*
X376629D03*
X384029D03*
X376629Y902649D03*
X380329D03*
X374778Y912262D03*
X376629Y909057D03*
X382178Y912262D03*
X380329Y909057D03*
X387729D03*
Y902649D03*
X372929Y915466D03*
X385878Y905853D03*
X380329Y915466D03*
X376629D03*
X384029D03*
X374778Y931488D03*
X376629Y928283D03*
X382178Y931488D03*
X380329Y928283D03*
X387729Y921875D03*
X376629D03*
X374778Y918670D03*
X380329Y921875D03*
X382178Y918670D03*
X387729Y928283D03*
X385878Y925079D03*
X380329Y941100D03*
X382178Y937896D03*
X376629Y947509D03*
X380329D03*
X376629Y941100D03*
X374778Y937896D03*
X372929Y934691D03*
X380329D03*
X376629D03*
X384029D03*
X387729Y947509D03*
Y941100D03*
X385878Y944304D03*
X376629Y960326D03*
X374778Y957122D03*
X380329Y960326D03*
X382178Y957122D03*
X374778Y950713D03*
X382178D03*
X372929Y953917D03*
X380329D03*
X376629D03*
X384029D03*
X387729Y960326D03*
Y966735D03*
X380329D03*
X376629D03*
X385878Y963530D03*
Y982756D03*
X387729Y979552D03*
X376629D03*
X380329D03*
X374778Y976347D03*
X382178D03*
X372929Y973143D03*
X374778Y969939D03*
X382178D03*
X384029Y973143D03*
X373362Y1006093D03*
X380762D03*
X377062D03*
X384462D03*
X375211Y1002888D03*
X377062Y999684D03*
X382611Y1002888D03*
X380762Y999684D03*
X377062Y1012501D03*
X375211Y1009297D03*
X380762Y1012501D03*
X382611Y1009297D03*
X377062Y1031727D03*
X375211Y1028523D03*
X380762Y1031727D03*
X382611Y1028523D03*
X375211Y1022114D03*
X377062Y1018910D03*
X382611Y1022114D03*
X380762Y1018910D03*
X377062Y1025318D03*
X384462D03*
X373360D03*
X380760D03*
X386311Y1015705D03*
X375211Y1047749D03*
X382611D03*
X375211Y1041340D03*
X377062Y1038136D03*
X382611Y1041340D03*
X380762Y1038136D03*
X373362Y1044544D03*
X380762D03*
X377062D03*
X384462D03*
X386311Y1034931D03*
X375211Y1060565D03*
X377062Y1057361D03*
X382611Y1060565D03*
X380762Y1057361D03*
X377062Y1050952D03*
X380762D03*
X373362Y1063770D03*
X384462D03*
X377062D03*
X380762D03*
X386311Y1054157D03*
X380762Y1070178D03*
X382611Y1066974D03*
X377062Y1070178D03*
X375211Y1066974D03*
Y1079791D03*
X377062Y1076587D03*
X382611Y1079791D03*
X380762Y1076587D03*
X386311Y1073383D03*
X377062Y1089404D03*
X375211Y1086200D03*
X380762Y1089404D03*
X382611Y1086200D03*
X373362Y1082995D03*
X386311Y1092608D03*
X384462Y1082995D03*
X377062D03*
X380762D03*
X386311Y1105426D03*
X382611Y1111834D03*
X375211Y1105426D03*
X377062Y1108630D03*
X380762Y1102221D03*
X378911Y1111834D03*
X384462Y1108630D03*
X386311Y1111834D03*
X378912Y1105426D03*
X375211Y1111834D03*
X382611Y1105426D03*
X375211Y1124651D03*
X378911D03*
X382611D03*
X386311D03*
X373362Y1121447D03*
X377062Y1127856D03*
X380762Y1121447D03*
X384462Y1127856D03*
X380762Y1115039D03*
X373362Y1134264D03*
X377061Y1140973D03*
X380762Y1134264D03*
X384461Y1140973D03*
X375212Y1137469D03*
X378912D03*
X382612D03*
X386312D03*
X391427Y844971D03*
X395127D03*
X398827D03*
X400679Y841467D03*
X389578Y848176D03*
X393279Y841467D03*
X396978Y848176D03*
X402527Y844971D03*
X400678Y867401D03*
X393278D03*
Y854584D03*
X395129Y857789D03*
X400678Y854584D03*
X402529Y857789D03*
X389578Y860993D03*
X391429Y857789D03*
X396978Y860993D03*
X398829Y857789D03*
X391429Y870606D03*
X395129D03*
X402529D03*
X389578Y873810D03*
X396978D03*
X398829Y870606D03*
X389578Y899445D03*
X393278D03*
X389578Y912262D03*
X393278D03*
X395129Y909057D03*
Y902649D03*
X393278Y905853D03*
X389578D03*
X396978D03*
X393278Y931488D03*
X395129Y928283D03*
X389578Y918670D03*
X395129Y921875D03*
X393278Y918670D03*
X389578Y931488D03*
X393278Y925079D03*
X389578D03*
X396978D03*
X395129Y947509D03*
X389578Y937896D03*
X395129Y941100D03*
X393278Y937896D03*
Y944304D03*
X389578D03*
X396978D03*
X389578Y957122D03*
X395129Y960326D03*
X393278Y957122D03*
X395129Y966735D03*
X389578Y950713D03*
X393278D03*
X396978Y963530D03*
X393278D03*
X389578D03*
X398829Y973143D03*
X400678Y976347D03*
X402529Y979552D03*
Y973143D03*
X393278Y982756D03*
X389578D03*
X396978D03*
X393278Y976347D03*
X395129Y979552D03*
X389579Y976347D03*
X389578Y969939D03*
X393278D03*
X390011Y1002888D03*
X388162Y999684D03*
X393711Y1002888D03*
X395562Y999684D03*
X388162Y1012501D03*
X395562D03*
X390011Y1009297D03*
X393711D03*
X397411Y1015705D03*
X388162Y1031727D03*
X390011Y1028523D03*
X395562Y1031727D03*
X393711Y1028523D03*
X390011Y1022114D03*
X388162Y1018910D03*
X393711Y1022114D03*
X395562Y1018910D03*
X390011Y1041340D03*
X388162Y1038136D03*
X393711Y1041340D03*
X395562Y1038136D03*
X390011Y1047749D03*
X393711D03*
Y1034931D03*
X390011D03*
X397411D03*
X390011Y1060565D03*
X388162Y1057361D03*
X393711Y1060565D03*
X395562Y1057361D03*
X388162Y1050952D03*
X395562D03*
X393711Y1054157D03*
X390011D03*
X397411D03*
X390011Y1079791D03*
X388162Y1076587D03*
X393711Y1079791D03*
X395562Y1076587D03*
X388162Y1070178D03*
X390011Y1066974D03*
X395562Y1070178D03*
X393711Y1066974D03*
Y1073383D03*
X390011D03*
X397411D03*
X395562Y1095813D03*
X388162Y1089404D03*
X390011Y1086200D03*
X395562Y1089404D03*
X393711Y1086200D03*
X388162Y1095813D03*
X393711Y1092608D03*
X390011D03*
X397411D03*
X402962Y1082995D03*
X402961Y1089404D03*
X393711Y1099017D03*
X390011D03*
X401111D03*
X391862Y1108630D03*
X393711Y1111834D03*
X397411Y1105426D03*
X402962Y1108630D03*
Y1102221D03*
X395562Y1108630D03*
X399262D03*
X401111Y1111834D03*
X390011Y1124651D03*
X395562Y1121447D03*
X397411Y1124651D03*
X401111D03*
X391862Y1127856D03*
X393711Y1124651D03*
X399262Y1127856D03*
X402962Y1121447D03*
X388162D03*
X399262Y1115039D03*
X391862D03*
X402962D03*
X391861Y1140973D03*
X395562Y1134264D03*
X399261Y1140973D03*
X402962Y1134264D03*
X388162D03*
X390012Y1137469D03*
X393712D03*
X397412D03*
X401112D03*
X406227Y844971D03*
X409927D03*
X413627D03*
X417327D03*
X404378Y848176D03*
X408079Y841467D03*
X411778Y848176D03*
X415479Y841467D03*
X419178Y848176D03*
X408078Y867401D03*
X415478D03*
X408078Y854584D03*
X409929Y857789D03*
X415478Y854584D03*
X417329Y857789D03*
X404378Y860993D03*
X406229Y857789D03*
X411778Y860993D03*
X413629Y857789D03*
X419178Y860993D03*
X404378Y873810D03*
X406229Y870606D03*
X419178Y873810D03*
X417329Y870606D03*
X411778Y873810D03*
X413629Y870606D03*
X417329Y883423D03*
X415478Y880219D03*
X413629Y883423D03*
X419178Y886627D03*
X408511Y1079791D03*
X406662Y1089404D03*
X410362D03*
X404811Y1086200D03*
X419611D03*
X414062Y1082995D03*
X410362D03*
X406662D03*
X408511Y1092608D03*
X414062Y1089404D03*
X419611Y1092608D03*
X412211Y1086200D03*
X404811Y1099017D03*
X408511Y1105426D03*
X412211Y1111834D03*
X415911D03*
X414062Y1102221D03*
X417762Y1108630D03*
X419611Y1105426D03*
X408511Y1099017D03*
X410362Y1108630D03*
X408511Y1111834D03*
X412211Y1105426D03*
X419611Y1111834D03*
X415911Y1105426D03*
X404811Y1124651D03*
X408511D03*
X406662Y1127856D03*
X410362Y1121447D03*
X414062Y1115039D03*
X406661Y1140973D03*
X410362Y1134264D03*
X404812Y1137469D03*
X408512D03*
X421027Y844971D03*
X424727D03*
X428427D03*
X433978Y848176D03*
X435829Y844671D03*
X422879Y841467D03*
X426578Y848176D03*
X430278D03*
Y867401D03*
X422878D03*
Y854584D03*
X424729Y857789D03*
X430278Y854584D03*
X433979Y860993D03*
X421029Y857789D03*
X426578Y860993D03*
X428429Y857789D03*
X432129D03*
X435829D03*
X432129Y870606D03*
X426578Y873810D03*
X424729Y870606D03*
X433979Y873810D03*
X428429Y870606D03*
X421029D03*
X435829D03*
X432129Y883423D03*
X430278Y880219D03*
X424729Y883423D03*
X422878Y880219D03*
X428429Y883423D03*
X421029D03*
X435829D03*
X433978Y886627D03*
X426578D03*
X428861Y1076587D03*
X430711Y1079791D03*
X421462Y1089404D03*
X423311Y1092608D03*
X427011D03*
X430710Y1086200D03*
X425162Y1082995D03*
Y1095813D03*
X430711Y1092608D03*
X423311Y1086200D03*
X428861Y1089404D03*
X427012Y1086200D03*
X450628Y844971D03*
X446927Y844671D03*
X452479Y841467D03*
X448778Y848176D03*
X443227Y844671D03*
X437678Y848176D03*
X452478Y867401D03*
X445078D03*
X437678D03*
X437679Y854584D03*
X452478D03*
X450629Y857789D03*
X445078Y854584D03*
X443229Y857789D03*
X448779Y860993D03*
X446929Y857789D03*
X441378Y860993D03*
X448779Y873810D03*
X446929Y870606D03*
X441378Y873810D03*
X439529Y870606D03*
X450629D03*
X443229D03*
X452479Y880219D03*
X446929Y883423D03*
X445078Y880219D03*
X439529Y883423D03*
X437678Y880219D03*
X450629Y883423D03*
X443229D03*
X448778Y886627D03*
X441378D03*
X467279Y841467D03*
X463578Y848176D03*
X459879Y841467D03*
X458027Y844971D03*
X454327D03*
X469127D03*
X465427D03*
X461727D03*
X456178Y848176D03*
X467278Y867401D03*
X459878D03*
X467278Y854584D03*
X465429Y857789D03*
X459878Y854584D03*
X458029Y857789D03*
X469129D03*
X463578Y860993D03*
X461729Y857789D03*
X456178Y860993D03*
X454329Y857789D03*
X469129Y870606D03*
X463578Y873810D03*
X461729Y870606D03*
X456178Y873810D03*
X454329Y870606D03*
X465429D03*
X458029D03*
X469129Y883423D03*
X467278Y880219D03*
X461729Y883423D03*
X459878Y880219D03*
X454329Y883423D03*
X465429D03*
X458029D03*
X463578Y886627D03*
X456178D03*
X483927Y844971D03*
X480227D03*
X476527D03*
X470978Y848176D03*
X482079Y841467D03*
X478378Y848176D03*
X474679Y841467D03*
X472827Y844971D03*
X474678Y867401D03*
X482078D03*
Y854584D03*
X480229Y857789D03*
X474678Y854584D03*
X472829Y857789D03*
X483929D03*
X478378Y860993D03*
X476529Y857789D03*
X470978Y860993D03*
X480229Y870606D03*
X476529D03*
X478378Y873810D03*
X483929Y870606D03*
X482078Y893036D03*
X483929Y896240D03*
X470978Y886627D03*
X483929Y915466D03*
Y934691D03*
Y953917D03*
Y973143D03*
X484362Y1006093D03*
Y1025318D03*
Y1044544D03*
Y1063770D03*
Y1082995D03*
Y1121447D03*
X480662Y1127856D03*
X476962Y1121447D03*
X473262Y1127856D03*
X469562Y1121447D03*
X482511Y1124651D03*
X478811D03*
X475111D03*
X471411D03*
X484362Y1134264D03*
X482512Y1137469D03*
X476962Y1134264D03*
X475112Y1137469D03*
X480661Y1140973D03*
X478812Y1137469D03*
X473261Y1140973D03*
X493178Y848176D03*
X489478Y841467D03*
X487627Y844971D03*
X500578Y848176D03*
X496878Y841467D03*
X495027Y844971D03*
X491327D03*
X485778Y848176D03*
X498727Y844971D03*
X489478Y867401D03*
X496878D03*
X489478Y854584D03*
X487629Y857789D03*
X500578Y860993D03*
X498729Y857789D03*
X495029D03*
X491329D03*
X485778Y860993D03*
X496878Y854584D03*
X493178Y860993D03*
X487629Y870606D03*
X495029D03*
X485778Y873810D03*
X491329Y870606D03*
X493178Y873810D03*
X498729Y870606D03*
X500578Y873810D03*
Y899445D03*
X485778D03*
X493178D03*
Y893036D03*
X496878D03*
X485778D03*
X491329Y896240D03*
X487629D03*
X495029D03*
X485778Y912262D03*
X487629Y909057D03*
X493178Y912262D03*
X491329Y909057D03*
X500578Y912262D03*
X498729Y909057D03*
Y902649D03*
X487629D03*
X491329D03*
X487629Y915466D03*
X500578Y905853D03*
X495029Y915466D03*
X496878Y905853D03*
X491329Y915466D03*
X500578Y931488D03*
X498729Y921875D03*
X500578Y918670D03*
X498729Y928283D03*
X496878Y925079D03*
X500578D03*
X491329Y921875D03*
X493178Y918670D03*
X485778Y931488D03*
X491329Y928283D03*
X493178Y931488D03*
X487629Y928283D03*
Y921875D03*
X485778Y918670D03*
X498729Y947509D03*
Y941100D03*
X500578Y937896D03*
X496878Y944304D03*
X500578D03*
X487629Y947509D03*
X491329D03*
X487629Y941100D03*
X485778Y937896D03*
X491329Y941100D03*
X493178Y937896D03*
X487629Y934691D03*
X495029D03*
X491329D03*
X500578Y950713D03*
X487629Y966735D03*
X491329D03*
X498729D03*
X496878Y963530D03*
X485778Y950713D03*
X493178D03*
X491329Y960326D03*
X493178Y957122D03*
X487629Y960326D03*
X485778Y957122D03*
X500578D03*
X498729Y960326D03*
X495029Y953917D03*
X487629D03*
X491329D03*
X487629Y979552D03*
X485778Y976347D03*
X491329Y979552D03*
X493178Y976347D03*
X500578Y982756D03*
X496878D03*
X498729Y979552D03*
X500578Y976347D03*
X495029Y973143D03*
X487629D03*
X491329D03*
X485778Y969939D03*
X493178D03*
X500578D03*
X501011Y1002888D03*
X499162Y999684D03*
Y1012501D03*
X501011Y1009297D03*
X495462Y1006093D03*
X486211Y1002888D03*
X493611D03*
X488062Y999684D03*
X491762D03*
X491761Y1012501D03*
X493611Y1009297D03*
X488062Y1012501D03*
X486211Y1009297D03*
X497311Y1015705D03*
X499162Y1031727D03*
X501011Y1028523D03*
Y1022114D03*
X499162Y1018910D03*
X488062Y1031727D03*
X486211Y1028523D03*
X491762Y1031727D03*
X493611Y1028523D03*
X486211Y1022114D03*
X488062Y1018910D03*
X493611Y1022114D03*
X491762Y1018910D03*
X488062Y1025318D03*
X495462D03*
X491762D03*
X501011Y1041340D03*
X499162Y1038136D03*
X501011Y1047749D03*
Y1034931D03*
X497311D03*
X486211Y1047749D03*
X493611D03*
X486211Y1041340D03*
X488062Y1038136D03*
X493611Y1041340D03*
X491762Y1038136D03*
X488062Y1044544D03*
X495462D03*
X491762D03*
X501011Y1060565D03*
X499162Y1057361D03*
Y1050952D03*
X501011Y1054157D03*
X497311D03*
X486211Y1060565D03*
X488062Y1057361D03*
X493611Y1060565D03*
X491762Y1057361D03*
X488062Y1050952D03*
X491762D03*
X488062Y1063770D03*
X495462D03*
X491762D03*
X499162Y1070178D03*
X501011Y1066974D03*
Y1079791D03*
X499162Y1076587D03*
X497311Y1073383D03*
X501011D03*
X486211Y1079791D03*
X488062Y1076587D03*
X493611Y1079791D03*
X491762Y1076587D03*
X488062Y1070178D03*
X486211Y1066974D03*
X491762Y1070178D03*
X493611Y1066974D03*
X491762Y1089404D03*
X493611Y1086200D03*
X499162Y1089404D03*
X501011Y1086200D03*
X488062Y1089404D03*
X486211Y1086200D03*
X497311Y1092608D03*
X495462Y1082995D03*
X501011Y1092608D03*
X488062Y1082995D03*
X491762D03*
X488062Y1127856D03*
X499162Y1121447D03*
X495462Y1127856D03*
X491762Y1121447D03*
X489911Y1124651D03*
X486211D03*
X501011D03*
X497311D03*
X493611D03*
X493612Y1137469D03*
X488061Y1140973D03*
X501012Y1137469D03*
X495461Y1140973D03*
X491762Y1134264D03*
X489912Y1137469D03*
X486212D03*
X499162Y1134264D03*
X497312Y1137469D03*
X517227Y844971D03*
X511679Y841467D03*
X509827Y844971D03*
X504279Y841467D03*
X515378Y848176D03*
X513527Y844971D03*
X507978Y848176D03*
X506127Y844971D03*
X502427D03*
X511678Y867401D03*
X504278D03*
X517229Y857789D03*
X513529D03*
X509829D03*
X506129D03*
X515378Y860993D03*
X511678Y854584D03*
X507978Y860993D03*
X504278Y854584D03*
X502429Y857789D03*
X517229Y870606D03*
X502429D03*
X509829D03*
X513529D03*
X515378Y873810D03*
X506129Y870606D03*
X507978Y873810D03*
X511678Y899445D03*
Y893036D03*
X507978D03*
X509829Y896240D03*
X517229D03*
X513529D03*
X504278Y899445D03*
X513529Y902649D03*
X517229D03*
X511678Y912262D03*
X513529Y909057D03*
X517229D03*
X513529Y915466D03*
X509829D03*
X517229D03*
X504278Y912262D03*
X506129Y909057D03*
Y902649D03*
X507978Y905853D03*
X504278D03*
X511678Y931488D03*
X513529Y928283D03*
X517229D03*
X506129D03*
Y921875D03*
X504278Y918670D03*
X513529Y921875D03*
X511678Y918670D03*
X517229Y921875D03*
X504278Y931488D03*
Y925079D03*
X507978D03*
X513529Y941100D03*
X511678Y937896D03*
X517229Y941100D03*
X513529Y934691D03*
X509829D03*
X517229D03*
X513529Y947509D03*
X517229D03*
X506129D03*
Y941100D03*
X504278Y937896D03*
X507978Y944304D03*
X504278D03*
X511678Y950713D03*
X513529Y960326D03*
X511678Y957122D03*
X517229Y960326D03*
Y966735D03*
X513529D03*
X504278Y950713D03*
X513529Y953917D03*
X517229D03*
X509829D03*
X506129Y966735D03*
X504278Y957122D03*
X506129Y960326D03*
X507978Y963530D03*
Y982756D03*
X504278D03*
Y976347D03*
X506129Y979552D03*
X513529D03*
X517229D03*
X511678Y976347D03*
X509829Y973143D03*
X511678Y969939D03*
X504278D03*
X517662Y1006093D03*
X513962D03*
X510262D03*
X517662Y1012501D03*
X504711Y1002888D03*
X506561Y999684D03*
X513962Y1012501D03*
X512111Y1009297D03*
X506562Y1012501D03*
X504711Y1009297D03*
X517661Y999684D03*
X512111Y1002888D03*
X513962Y999684D03*
Y1031727D03*
X512111Y1028523D03*
X517662Y1031727D03*
X512111Y1022114D03*
X513962Y1018910D03*
X517662D03*
X513962Y1025318D03*
X510262D03*
X517662D03*
X508411Y1015705D03*
X506562Y1031727D03*
X504711Y1028523D03*
Y1022114D03*
X506562Y1018910D03*
X504711Y1041340D03*
X506562Y1038136D03*
X512111Y1047749D03*
Y1041340D03*
X513962Y1038136D03*
X517662D03*
X504711Y1047749D03*
X510262Y1044544D03*
X508411Y1034931D03*
X513962Y1044544D03*
X517662D03*
X504711Y1034931D03*
X512111Y1060565D03*
X513962Y1057361D03*
X517662D03*
X510262Y1063770D03*
X513962D03*
X517662D03*
X513962Y1050952D03*
X517662D03*
X504711Y1060565D03*
X506562Y1057361D03*
Y1050952D03*
X508411Y1054157D03*
X504711D03*
X517662Y1070178D03*
X513962D03*
X512111Y1066974D03*
X504711Y1079791D03*
X506562Y1076587D03*
Y1070178D03*
X504711Y1066974D03*
X512111Y1079791D03*
X513962Y1076587D03*
X517662D03*
X508411Y1073383D03*
X504711D03*
X513962Y1089404D03*
X512111Y1086200D03*
X517662Y1089404D03*
X513962Y1082995D03*
X510262D03*
X517662D03*
X510262Y1095813D03*
X506561D03*
X506562Y1089404D03*
X504711Y1086200D03*
X508411Y1092608D03*
X504711D03*
X517662Y1102221D03*
X515811Y1099017D03*
X517662Y1127856D03*
X513962Y1121447D03*
X510262Y1127856D03*
X506562Y1121447D03*
X502862Y1127856D03*
X515811Y1124651D03*
X512111D03*
X508411D03*
X504711D03*
X517661Y1140973D03*
X513962Y1134264D03*
X512112Y1137469D03*
X506562Y1134264D03*
X504712Y1137469D03*
X515812D03*
X510261Y1140973D03*
X508412Y1137469D03*
X502861Y1140973D03*
X532028Y844671D03*
X526478Y848176D03*
X524627Y844971D03*
X519079Y841467D03*
X533878Y848176D03*
X530178D03*
X522778D03*
X520927Y844971D03*
X532029Y864197D03*
X533879Y854584D03*
X519078Y867401D03*
X526479D03*
X528329Y857789D03*
X522778Y860993D03*
X520929Y857789D03*
X526478Y854584D03*
X524629Y857789D03*
X519078Y854584D03*
X524629Y870606D03*
X532029D03*
X520929D03*
X522778Y873810D03*
X528329Y870606D03*
X530178Y873810D03*
X526479Y899445D03*
X530178D03*
X519078D03*
Y893036D03*
X522778D03*
X520929Y896240D03*
X530179Y912262D03*
X532029Y909057D03*
X524629Y902649D03*
X532029D03*
X526479Y912262D03*
X524629Y909057D03*
X526479Y905853D03*
X533879D03*
X522778D03*
X530179D03*
X519078Y912262D03*
X520929Y915466D03*
X526479Y931488D03*
X524629Y928283D03*
X530179Y931488D03*
X532029Y928283D03*
X524629Y921875D03*
X526479Y918670D03*
X532029Y921875D03*
X530179Y918670D03*
X526479Y925079D03*
X533879D03*
X522778D03*
X530179D03*
X519078Y931488D03*
Y918670D03*
X524629Y941100D03*
X526479Y937896D03*
X532029Y941100D03*
X530179Y937896D03*
X524629Y947509D03*
X532029D03*
X519078Y937896D03*
X533879Y944304D03*
X520929Y934691D03*
X526479Y944304D03*
X530178D03*
X522778D03*
X524629Y966735D03*
X532029D03*
X522778Y963530D03*
X526479Y950713D03*
X530178D03*
X532029Y960326D03*
X530178Y957122D03*
X524629Y960326D03*
X526479Y957122D03*
X533879Y963530D03*
X519078Y950713D03*
Y957122D03*
X520929Y953917D03*
X526479Y969939D03*
X530179D03*
X519078Y976347D03*
Y969939D03*
X520929Y973143D03*
X521362Y1006093D03*
X525062Y1012501D03*
X532461D03*
X526911Y1009297D03*
X530611D03*
X519511D03*
X519513Y1002888D03*
X530611D03*
X532461Y999684D03*
X526911Y1002888D03*
X525062Y999684D03*
X523211Y1015705D03*
X534311D03*
X525062Y1031727D03*
X526911Y1028523D03*
X532461Y1031727D03*
X530611Y1028523D03*
Y1022114D03*
X532461Y1018910D03*
X526911Y1022114D03*
X525062Y1018910D03*
X519511Y1028523D03*
Y1022114D03*
X521362Y1025318D03*
X526911Y1041340D03*
X525062Y1038136D03*
X530611Y1041340D03*
X532461Y1038136D03*
X526911Y1047749D03*
X530611D03*
X526911Y1034931D03*
X534311D03*
X523211D03*
X530611D03*
X519511Y1047749D03*
Y1041340D03*
X521362Y1044544D03*
X519511Y1060565D03*
X526911D03*
X525062Y1057361D03*
X530611Y1060565D03*
X532462Y1057361D03*
X525061Y1050952D03*
X532462Y1050953D03*
X523211Y1054157D03*
X521362Y1063770D03*
X534311Y1054157D03*
X526911D03*
X530611D03*
Y1079791D03*
X532462Y1076587D03*
X525062Y1070178D03*
X526911Y1066974D03*
X532462Y1070178D03*
X530611Y1066974D03*
X526911Y1079791D03*
X525062Y1076587D03*
X523211Y1073383D03*
X534311D03*
X526911D03*
X530611D03*
X519511Y1066974D03*
Y1079791D03*
X521362Y1095813D03*
X532461D03*
X525062D03*
Y1089404D03*
X526911Y1086200D03*
X532462Y1089404D03*
X530611Y1086200D03*
X526911Y1092608D03*
X534310D03*
X523211D03*
X530611D03*
X519511Y1086200D03*
X521362Y1082995D03*
X530611Y1099017D03*
X526911Y1124651D03*
X521362Y1121447D03*
X525062Y1127856D03*
X523211Y1124651D03*
X519511D03*
X532462Y1134264D03*
X525061Y1140973D03*
X523212Y1137469D03*
X534312D03*
X526912D03*
X521362Y1134264D03*
X519512Y1137469D03*
X543129Y851380D03*
X539429D03*
X535729Y864197D03*
X543128D03*
X546828D03*
X535729Y857789D03*
X543130D03*
X539429D03*
X541279Y860993D03*
Y854584D03*
X539429Y883423D03*
X537578Y880219D03*
X543129Y883423D03*
X544979Y880219D03*
X537578Y873810D03*
X539429Y870606D03*
X544979Y873810D03*
X543129Y870606D03*
X539428Y877014D03*
X546828D03*
X535729D03*
X543129D03*
X620799Y883924D03*
Y890617D03*
Y897310D03*
Y900656D03*
Y914042D03*
Y907349D03*
Y960892D03*
Y957546D03*
Y1185105D03*
Y1178412D03*
Y1191798D03*
Y1208530D03*
Y1201837D03*
Y1195144D03*
X636941Y880577D03*
Y887270D03*
Y897310D03*
Y893963D03*
Y910696D03*
Y904003D03*
Y1175066D03*
Y1181759D03*
Y1191798D03*
Y1188451D03*
Y1205184D03*
Y1198491D03*
X650499Y960892D03*
Y957546D03*
X680299Y780184D03*
Y773491D03*
Y786877D03*
Y803609D03*
Y796916D03*
Y790223D03*
Y816995D03*
Y810302D03*
Y833727D03*
Y823688D03*
Y827034D03*
Y847113D03*
Y840420D03*
Y853806D03*
Y860499D03*
Y863845D03*
Y883924D03*
Y877231D03*
Y870538D03*
Y890617D03*
Y897310D03*
Y900656D03*
Y914042D03*
Y907349D03*
Y927428D03*
Y920735D03*
Y934121D03*
Y944160D03*
Y937467D03*
Y960892D03*
Y950853D03*
Y957546D03*
Y980971D03*
Y974278D03*
Y967585D03*
Y994357D03*
Y987664D03*
X679999Y1027822D03*
X680299Y1021129D03*
X679999Y1047900D03*
Y1041207D03*
Y1034514D03*
Y1054593D03*
X680299Y1074672D03*
Y1067979D03*
Y1091404D03*
Y1081365D03*
Y1084711D03*
Y1098097D03*
Y1111483D03*
Y1104790D03*
Y1128215D03*
Y1118176D03*
Y1121522D03*
Y1141601D03*
Y1134908D03*
Y1148294D03*
Y1154987D03*
Y1158333D03*
Y1171719D03*
Y1165026D03*
Y1185105D03*
Y1178412D03*
Y1191798D03*
Y1208530D03*
Y1201837D03*
Y1195144D03*
Y1221916D03*
Y1215223D03*
Y1238648D03*
Y1228609D03*
Y1231955D03*
Y1245341D03*
X696441Y770144D03*
Y776837D03*
Y786877D03*
Y783530D03*
Y800263D03*
Y793570D03*
Y813648D03*
Y806955D03*
Y820341D03*
Y830381D03*
Y823688D03*
Y850459D03*
Y843766D03*
Y837074D03*
Y867192D03*
Y860499D03*
Y857152D03*
Y873885D03*
Y880577D03*
Y887270D03*
Y897310D03*
Y893963D03*
Y917389D03*
Y910696D03*
Y904003D03*
Y924081D03*
Y934121D03*
Y930774D03*
Y947507D03*
Y940814D03*
Y964239D03*
Y977625D03*
Y970932D03*
Y991011D03*
Y984318D03*
Y1021129D03*
Y1024475D03*
Y1031168D03*
X696141Y1044554D03*
Y1037861D03*
X696441Y1051247D03*
Y1071325D03*
Y1064633D03*
Y1078018D03*
Y1094751D03*
Y1088058D03*
Y1081365D03*
Y1108136D03*
Y1101444D03*
Y1124869D03*
Y1118176D03*
Y1114829D03*
Y1144947D03*
Y1138255D03*
Y1131562D03*
Y1161680D03*
Y1154987D03*
Y1151640D03*
Y1175066D03*
Y1168373D03*
Y1181758D03*
Y1191798D03*
Y1188451D03*
Y1205184D03*
Y1198491D03*
Y1218569D03*
Y1211877D03*
Y1225262D03*
Y1241995D03*
Y1235302D03*
Y1228609D03*
X709899Y960892D03*
Y957546D03*
X709999Y967585D03*
Y1054593D03*
X726141Y964239D03*
Y1021129D03*
Y1024475D03*
Y1051247D03*
X739699Y780184D03*
Y773491D03*
Y786877D03*
Y803609D03*
Y796916D03*
Y790223D03*
Y816995D03*
Y810302D03*
Y833727D03*
Y823688D03*
Y827034D03*
Y847113D03*
Y840420D03*
Y853806D03*
Y860499D03*
Y863845D03*
Y883924D03*
Y877231D03*
Y870538D03*
Y890617D03*
Y897310D03*
Y900656D03*
Y914042D03*
Y907349D03*
Y927428D03*
Y920735D03*
Y934121D03*
Y944160D03*
Y937467D03*
Y960892D03*
Y950853D03*
Y957546D03*
Y980971D03*
Y974278D03*
Y967585D03*
Y994357D03*
Y987664D03*
Y1027822D03*
Y1021129D03*
Y1047900D03*
Y1041207D03*
Y1034514D03*
Y1054593D03*
Y1074672D03*
Y1067979D03*
Y1091404D03*
Y1081365D03*
Y1084711D03*
Y1098097D03*
Y1111483D03*
Y1104790D03*
Y1128215D03*
Y1118176D03*
Y1121522D03*
Y1141601D03*
Y1134908D03*
Y1148294D03*
Y1154987D03*
Y1158333D03*
Y1171719D03*
Y1165026D03*
Y1185105D03*
Y1178412D03*
Y1191798D03*
Y1208530D03*
Y1201837D03*
Y1195144D03*
Y1221916D03*
Y1215223D03*
Y1238648D03*
Y1228609D03*
Y1231955D03*
Y1245341D03*
X755841Y770144D03*
Y776837D03*
Y786877D03*
Y783530D03*
Y800263D03*
Y793570D03*
Y813648D03*
Y806955D03*
Y820341D03*
Y830381D03*
Y823688D03*
Y850459D03*
Y843766D03*
Y837074D03*
Y867192D03*
Y860499D03*
Y857152D03*
Y873885D03*
Y880577D03*
Y887270D03*
Y897310D03*
Y893963D03*
Y917389D03*
Y910696D03*
Y904003D03*
Y924081D03*
Y934121D03*
Y930774D03*
Y947507D03*
Y940814D03*
Y964239D03*
Y977625D03*
X755741Y970932D03*
X755841Y991011D03*
Y984318D03*
Y1021129D03*
Y1024475D03*
Y1031168D03*
X755541Y1044554D03*
Y1037861D03*
X755841Y1051247D03*
X755676Y1071326D03*
X755741Y1064633D03*
X755841Y1078018D03*
Y1094751D03*
Y1088058D03*
Y1081365D03*
X755676Y1108137D03*
X755841Y1101444D03*
Y1124869D03*
Y1118176D03*
Y1114829D03*
Y1144947D03*
Y1138255D03*
Y1131562D03*
Y1161680D03*
Y1154987D03*
Y1151640D03*
Y1175066D03*
Y1168373D03*
X755676Y1181759D03*
X755841Y1191798D03*
X755676Y1188452D03*
X755841Y1205184D03*
Y1198491D03*
Y1218569D03*
Y1211877D03*
Y1225262D03*
Y1241995D03*
Y1235302D03*
Y1228609D03*
X769399Y960892D03*
Y957546D03*
Y967585D03*
Y1054593D03*
X785541Y964239D03*
Y1021129D03*
Y1024475D03*
Y1051247D03*
X799099Y780184D03*
Y773491D03*
Y786877D03*
Y803609D03*
Y796916D03*
Y790223D03*
Y816995D03*
Y810302D03*
Y833727D03*
Y823688D03*
Y827034D03*
Y847113D03*
Y840420D03*
Y853806D03*
Y860499D03*
Y863845D03*
Y883924D03*
Y877231D03*
Y870538D03*
Y890617D03*
Y897310D03*
Y900656D03*
Y914042D03*
Y907349D03*
Y927428D03*
Y920735D03*
Y934121D03*
Y944160D03*
Y937467D03*
Y960892D03*
Y950853D03*
Y957546D03*
Y980971D03*
Y974278D03*
Y967585D03*
Y994357D03*
Y987664D03*
Y1027822D03*
Y1021129D03*
Y1047900D03*
Y1041207D03*
Y1034515D03*
Y1054593D03*
Y1074672D03*
Y1067979D03*
Y1091404D03*
Y1081365D03*
Y1084711D03*
Y1098097D03*
Y1111483D03*
Y1104790D03*
Y1128215D03*
Y1118176D03*
Y1121522D03*
Y1141601D03*
Y1134908D03*
Y1148294D03*
Y1154987D03*
Y1158333D03*
Y1171719D03*
Y1165026D03*
Y1185105D03*
Y1178412D03*
Y1191798D03*
Y1208530D03*
Y1201837D03*
Y1195144D03*
Y1221916D03*
Y1215223D03*
Y1238648D03*
Y1228609D03*
Y1231955D03*
Y1245341D03*
X815241Y770144D03*
Y776837D03*
Y786877D03*
Y783530D03*
Y800263D03*
Y793570D03*
Y813648D03*
Y806955D03*
Y820341D03*
Y830381D03*
Y823688D03*
Y850459D03*
Y843766D03*
Y837074D03*
Y867192D03*
Y860499D03*
Y857152D03*
Y873885D03*
Y880577D03*
Y887270D03*
Y897310D03*
Y893963D03*
Y917389D03*
Y910696D03*
Y904003D03*
Y924081D03*
Y934121D03*
Y930774D03*
Y947507D03*
Y940814D03*
Y964239D03*
Y977625D03*
Y970932D03*
Y991011D03*
Y984318D03*
Y1021129D03*
Y1024475D03*
Y1031168D03*
Y1044554D03*
Y1037861D03*
X814941Y1051247D03*
X815241Y1071325D03*
Y1064633D03*
Y1078018D03*
Y1094751D03*
Y1088058D03*
Y1081365D03*
Y1108136D03*
Y1101444D03*
Y1124869D03*
Y1118176D03*
Y1114829D03*
Y1144947D03*
Y1138255D03*
Y1131562D03*
Y1161680D03*
Y1154987D03*
Y1151640D03*
Y1175066D03*
Y1168373D03*
Y1181758D03*
Y1191798D03*
Y1188451D03*
Y1205184D03*
Y1198491D03*
Y1218570D03*
Y1211877D03*
Y1225263D03*
Y1241995D03*
Y1235302D03*
Y1228609D03*
X828799Y960892D03*
Y957546D03*
Y967585D03*
Y1054593D03*
X844941Y964239D03*
Y1021129D03*
Y1024475D03*
Y1051247D03*
X1012541Y960892D03*
Y957546D03*
Y967585D03*
Y1054593D03*
X1028683Y964239D03*
Y1021129D03*
Y1024475D03*
Y1051247D03*
X1042241Y780184D03*
Y773491D03*
Y786877D03*
Y803609D03*
Y796916D03*
Y790223D03*
Y816995D03*
Y810302D03*
Y833727D03*
Y823688D03*
Y827034D03*
Y847113D03*
Y840420D03*
Y853806D03*
Y860499D03*
Y863845D03*
Y883924D03*
Y877231D03*
Y870538D03*
Y890617D03*
Y897310D03*
Y900656D03*
Y914042D03*
Y907349D03*
Y927428D03*
Y920735D03*
Y934121D03*
Y944160D03*
Y937467D03*
Y960892D03*
Y950853D03*
Y957546D03*
Y980971D03*
Y974278D03*
Y967585D03*
Y994357D03*
Y987664D03*
Y1027822D03*
Y1021129D03*
Y1047900D03*
Y1041207D03*
Y1034515D03*
Y1054593D03*
Y1074672D03*
Y1067979D03*
Y1091404D03*
Y1081365D03*
Y1084711D03*
Y1098097D03*
Y1111483D03*
Y1104790D03*
Y1128215D03*
Y1118176D03*
Y1121522D03*
Y1141601D03*
Y1134908D03*
Y1148294D03*
Y1154987D03*
Y1158333D03*
Y1171719D03*
Y1165026D03*
Y1185105D03*
Y1178412D03*
Y1191798D03*
Y1208530D03*
Y1201837D03*
Y1195144D03*
Y1221916D03*
Y1215223D03*
Y1238648D03*
Y1228609D03*
Y1231955D03*
Y1245341D03*
X1058383Y770144D03*
Y776837D03*
Y786877D03*
Y783530D03*
Y800263D03*
Y793570D03*
Y813648D03*
Y806955D03*
Y820341D03*
Y830381D03*
Y823688D03*
Y850459D03*
Y843766D03*
Y837074D03*
Y867192D03*
Y860499D03*
Y857152D03*
Y873885D03*
Y880577D03*
Y887270D03*
Y897310D03*
Y893963D03*
Y917389D03*
Y910696D03*
Y904003D03*
Y924081D03*
Y934121D03*
Y930774D03*
Y947507D03*
Y940814D03*
Y964239D03*
Y977625D03*
Y970932D03*
Y991011D03*
Y984318D03*
Y1021129D03*
Y1024475D03*
Y1031168D03*
Y1044554D03*
Y1037861D03*
Y1051247D03*
Y1071326D03*
Y1064633D03*
Y1078018D03*
Y1094751D03*
Y1088058D03*
Y1081365D03*
Y1108137D03*
Y1101444D03*
Y1124869D03*
Y1118176D03*
Y1114829D03*
Y1144948D03*
Y1138255D03*
Y1131562D03*
Y1161680D03*
Y1154987D03*
Y1151641D03*
Y1175066D03*
Y1168373D03*
Y1181759D03*
Y1191798D03*
Y1188452D03*
Y1205184D03*
Y1198491D03*
Y1218570D03*
Y1211877D03*
Y1225263D03*
Y1241995D03*
Y1235302D03*
Y1228609D03*
X1071941Y960892D03*
Y957546D03*
Y967585D03*
Y1054593D03*
X1101641Y780184D03*
Y773491D03*
Y786877D03*
Y803609D03*
Y796916D03*
Y790223D03*
Y816995D03*
Y810302D03*
Y833727D03*
Y823688D03*
Y827034D03*
Y847113D03*
Y840420D03*
Y853806D03*
Y860499D03*
Y863845D03*
Y883924D03*
Y877231D03*
Y870538D03*
Y890617D03*
Y897310D03*
Y900656D03*
Y914042D03*
Y907349D03*
Y927428D03*
Y920735D03*
Y934121D03*
Y944160D03*
Y937467D03*
Y960892D03*
Y950853D03*
X1088083Y964239D03*
X1101641Y957546D03*
Y980971D03*
Y974278D03*
Y967585D03*
Y994357D03*
Y987664D03*
X1088083Y1021129D03*
Y1024475D03*
X1101641Y1027822D03*
Y1021129D03*
Y1047900D03*
Y1041207D03*
Y1034515D03*
X1088083Y1051247D03*
X1101641Y1054593D03*
Y1074672D03*
Y1067979D03*
Y1091404D03*
Y1081365D03*
Y1084711D03*
Y1098097D03*
Y1111483D03*
Y1104790D03*
Y1128215D03*
Y1118176D03*
Y1121522D03*
Y1141601D03*
Y1134908D03*
Y1148294D03*
Y1154987D03*
Y1158333D03*
Y1171719D03*
Y1165026D03*
Y1185105D03*
Y1178412D03*
Y1191798D03*
Y1208530D03*
Y1201837D03*
Y1195144D03*
Y1221916D03*
Y1215223D03*
Y1238648D03*
Y1228609D03*
Y1231955D03*
Y1245341D03*
X1117783Y770144D03*
Y776837D03*
Y786877D03*
Y783530D03*
Y800263D03*
Y793570D03*
Y813648D03*
Y806955D03*
Y820341D03*
Y830381D03*
Y823688D03*
Y850459D03*
Y843766D03*
Y837074D03*
Y867192D03*
Y860499D03*
Y857152D03*
Y873885D03*
Y880577D03*
Y887270D03*
Y897310D03*
Y893963D03*
Y917389D03*
Y910696D03*
Y904003D03*
Y924081D03*
Y934121D03*
Y930774D03*
Y947507D03*
Y940814D03*
Y964239D03*
Y977625D03*
Y970932D03*
Y991011D03*
Y984318D03*
Y1021129D03*
Y1024475D03*
Y1031168D03*
Y1044554D03*
Y1037861D03*
Y1051247D03*
Y1071326D03*
Y1064633D03*
Y1078018D03*
Y1094751D03*
Y1088058D03*
Y1081365D03*
Y1108137D03*
Y1101444D03*
Y1124869D03*
Y1118176D03*
Y1114829D03*
Y1144948D03*
Y1138255D03*
Y1131562D03*
Y1161680D03*
Y1154987D03*
Y1151641D03*
Y1175066D03*
Y1168373D03*
Y1181759D03*
Y1191798D03*
Y1188452D03*
Y1205184D03*
Y1198491D03*
Y1218570D03*
Y1211877D03*
Y1225263D03*
Y1241995D03*
Y1235302D03*
Y1228609D03*
X1131341Y960892D03*
Y957546D03*
Y967585D03*
Y1054593D03*
X1147483Y964239D03*
Y1021129D03*
Y1024475D03*
Y1051247D03*
X1161041Y780184D03*
Y773491D03*
Y786877D03*
Y803609D03*
Y796916D03*
Y790223D03*
Y816995D03*
Y810302D03*
Y833727D03*
Y823688D03*
Y827034D03*
Y847113D03*
Y840420D03*
Y853806D03*
Y860499D03*
Y863845D03*
Y883924D03*
Y877231D03*
Y870538D03*
Y890617D03*
Y897310D03*
Y900656D03*
Y914042D03*
Y907349D03*
Y927428D03*
Y920735D03*
Y934121D03*
Y944160D03*
Y937467D03*
Y960892D03*
Y950853D03*
Y957546D03*
Y980971D03*
Y974278D03*
Y967585D03*
Y994357D03*
Y987664D03*
Y1027822D03*
Y1021129D03*
Y1047900D03*
Y1041207D03*
Y1034515D03*
Y1054593D03*
Y1074672D03*
Y1067979D03*
Y1091404D03*
Y1081365D03*
Y1084711D03*
Y1098097D03*
Y1111483D03*
Y1104790D03*
Y1128215D03*
Y1118176D03*
Y1121522D03*
Y1141601D03*
Y1134908D03*
Y1148294D03*
Y1154987D03*
Y1158333D03*
Y1171719D03*
Y1165026D03*
Y1185105D03*
Y1178412D03*
Y1191798D03*
Y1208530D03*
Y1201837D03*
Y1195144D03*
Y1221916D03*
Y1215223D03*
Y1238648D03*
Y1228609D03*
Y1231955D03*
Y1245341D03*
X1177183Y770144D03*
Y776837D03*
Y786877D03*
Y783530D03*
Y800263D03*
Y793570D03*
Y813648D03*
Y806955D03*
Y820341D03*
Y830381D03*
Y823688D03*
Y850459D03*
Y843766D03*
Y837074D03*
Y867192D03*
Y860499D03*
Y857152D03*
Y873885D03*
Y880577D03*
Y887270D03*
Y897310D03*
Y893963D03*
Y917389D03*
Y910696D03*
Y904003D03*
Y924081D03*
Y934121D03*
Y930774D03*
Y947507D03*
Y940814D03*
Y964239D03*
Y977625D03*
Y970932D03*
Y991011D03*
Y984318D03*
X1177283Y1021129D03*
Y1024475D03*
Y1031168D03*
Y1044554D03*
Y1037861D03*
Y1051247D03*
Y1071326D03*
Y1064633D03*
Y1078018D03*
Y1094752D03*
Y1088059D03*
Y1081366D03*
Y1108137D03*
Y1101444D03*
X1177183Y1124869D03*
X1177283Y1118177D03*
Y1114830D03*
Y1144948D03*
Y1138255D03*
X1177183Y1131562D03*
X1177283Y1161680D03*
Y1154988D03*
Y1151641D03*
Y1175066D03*
Y1168373D03*
Y1181759D03*
Y1191799D03*
Y1188452D03*
Y1205184D03*
Y1198491D03*
Y1218570D03*
Y1211877D03*
Y1225263D03*
X1177250Y1241995D03*
X1177283Y1235302D03*
Y1228609D03*
X1190741Y960892D03*
Y957546D03*
X1220441Y883924D03*
Y890617D03*
Y897310D03*
Y900656D03*
Y914042D03*
Y907349D03*
Y960892D03*
Y957546D03*
Y1185105D03*
Y1178412D03*
Y1191798D03*
Y1208530D03*
Y1201837D03*
Y1195144D03*
X1236583Y880577D03*
Y887270D03*
Y897310D03*
Y893963D03*
Y910696D03*
Y904003D03*
Y1175066D03*
Y1181759D03*
Y1191798D03*
Y1188452D03*
Y1205184D03*
Y1198491D03*
X1313921Y880219D03*
X1312070Y883423D03*
X1313921Y893036D03*
X1312070Y889832D03*
X1310221Y886627D03*
X1313921D03*
X1312503Y1121447D03*
X1326869Y851380D03*
X1330569Y844971D03*
X1325020Y848176D03*
X1328720D03*
X1326871Y857789D03*
X1328720Y860993D03*
X1330571Y857789D03*
X1317621Y880219D03*
X1319471Y883423D03*
X1326871Y870606D03*
X1330571D03*
X1328720Y873810D03*
X1325020Y899445D03*
Y893036D03*
X1326871Y889832D03*
X1330571D03*
X1317620Y893036D03*
X1319470Y889832D03*
X1323171Y896240D03*
X1330571D03*
X1317621Y886627D03*
X1326871Y896240D03*
X1321321Y886627D03*
X1325020Y912262D03*
X1326871Y909057D03*
X1330571D03*
X1326871Y902649D03*
X1330571D03*
X1323171Y915466D03*
X1330571D03*
X1326871D03*
X1325021Y931488D03*
X1326871Y928283D03*
X1330571D03*
Y921875D03*
X1326871D03*
X1325020Y918670D03*
X1326871Y941100D03*
X1325020Y937896D03*
X1330571Y941100D03*
X1323171Y934691D03*
X1330571D03*
X1326871D03*
Y947509D03*
X1330571D03*
X1325020Y950713D03*
X1326871Y960326D03*
X1325020Y957122D03*
X1330571Y960326D03*
X1326871Y966735D03*
X1330571D03*
X1326871Y953917D03*
X1330571D03*
X1323172D03*
X1326871Y979552D03*
X1330571D03*
X1325020Y976347D03*
X1323171Y973143D03*
X1325020Y969939D03*
X1323603Y1006093D03*
X1325453Y1002888D03*
X1327303Y999684D03*
X1331003D03*
X1327303Y1012501D03*
X1325453Y1009297D03*
X1331003Y1012501D03*
X1327304Y1031727D03*
X1325453Y1028523D03*
X1331003Y1031727D03*
X1325453Y1022114D03*
X1327303Y1018910D03*
X1331003D03*
X1323603Y1025318D03*
X1331004D03*
X1327304D03*
X1325453Y1047749D03*
Y1041340D03*
X1327303Y1038136D03*
X1331003D03*
X1323603Y1044544D03*
X1331003D03*
X1327303D03*
X1325453Y1060565D03*
X1327303Y1057361D03*
X1331003D03*
X1323603Y1063770D03*
X1327303D03*
X1331003D03*
X1327303Y1050952D03*
X1331003D03*
Y1070178D03*
X1327304D03*
X1325453Y1066974D03*
Y1079791D03*
X1327303Y1076587D03*
X1331003D03*
X1327303Y1089404D03*
X1325453Y1086200D03*
X1331003Y1089404D03*
X1323603Y1082995D03*
X1331003D03*
X1327303D03*
X1329153Y1105426D03*
X1325454Y1111834D03*
X1327303Y1102221D03*
X1321753Y1111834D03*
X1318054D03*
X1318053Y1105426D03*
X1327304Y1108630D03*
X1329154Y1111834D03*
X1331003Y1102221D03*
X1319904Y1108630D03*
X1321753Y1105426D03*
X1329153Y1124651D03*
X1331003Y1127856D03*
X1323603Y1121447D03*
X1319903Y1127856D03*
X1316203D03*
X1318054Y1118243D03*
X1321753Y1124651D03*
X1323603Y1127856D03*
X1319903Y1121447D03*
X1316203D03*
X1323603Y1115039D03*
X1325452Y1137469D03*
X1327303Y1134264D03*
X1318053Y1131060D03*
X1346137Y175949D03*
X1342937Y177799D03*
X1346137Y179649D03*
X1332421Y841467D03*
X1337969Y844971D03*
X1339821Y841467D03*
X1345369Y844971D03*
X1347221Y841467D03*
X1334269Y844971D03*
X1336120Y848176D03*
X1341669Y844971D03*
X1343520Y848176D03*
X1347220Y867401D03*
X1332420D03*
X1339820D03*
X1332420Y854584D03*
X1334271Y857789D03*
X1337971D03*
X1341671D03*
X1345371D03*
X1336120Y860993D03*
X1339820Y854584D03*
X1343520Y860993D03*
X1347220Y854584D03*
X1334271Y870606D03*
X1337971D03*
X1341671D03*
X1336120Y873810D03*
X1343520D03*
X1345371Y870606D03*
X1332420Y899445D03*
Y893036D03*
X1334271Y896240D03*
X1339820Y899445D03*
X1343520D03*
X1347220Y893036D03*
X1332420Y912262D03*
X1334271Y915466D03*
X1339820Y912262D03*
X1337971Y909057D03*
X1343520Y912262D03*
X1345371Y909057D03*
X1337971Y902649D03*
X1345371D03*
X1336120Y905853D03*
X1343520D03*
X1339820D03*
X1347220D03*
X1332420Y931488D03*
X1339820D03*
X1332420Y918670D03*
X1337971Y928283D03*
X1343520Y931488D03*
X1345371Y928283D03*
X1337971Y921875D03*
X1339820Y918670D03*
X1345371Y921875D03*
X1343520Y918670D03*
X1336120Y925079D03*
X1343520D03*
X1339820D03*
X1347220D03*
X1332420Y937896D03*
X1334271Y934691D03*
X1337971Y941100D03*
X1339820Y937896D03*
X1345371Y941100D03*
X1343520Y937896D03*
X1337971Y947509D03*
X1345371D03*
X1343520Y944304D03*
X1336120D03*
X1347220D03*
X1339820D03*
X1332420Y950713D03*
Y957122D03*
X1334271Y953917D03*
X1337971Y966735D03*
X1345371D03*
X1336120Y963530D03*
X1339820Y950713D03*
X1343520D03*
X1337971Y960326D03*
X1339820Y957122D03*
X1345371Y960326D03*
X1343520Y957122D03*
X1347220Y963530D03*
X1336120Y982756D03*
X1343520D03*
X1339820D03*
X1347220D03*
X1345371Y979552D03*
X1343520Y976347D03*
X1337971Y979552D03*
X1339820Y976347D03*
X1332420D03*
Y969939D03*
X1334271Y973143D03*
X1339820Y969939D03*
X1343520D03*
X1334704Y1006093D03*
X1332853Y1002888D03*
Y1009297D03*
X1338404Y1012501D03*
X1345804D03*
X1340253Y1009297D03*
X1343953D03*
X1340253Y1002888D03*
X1338404Y999684D03*
X1347653Y1002888D03*
X1345804Y999684D03*
X1332853Y1028523D03*
Y1022114D03*
X1338404Y1031727D03*
X1340253Y1028523D03*
X1345804Y1031727D03*
X1343953Y1028523D03*
X1334704Y1025318D03*
X1336553Y1015705D03*
X1347653D03*
X1340253Y1022114D03*
X1338404Y1018910D03*
X1343953Y1022114D03*
X1345804Y1018910D03*
X1332853Y1047749D03*
Y1041340D03*
X1340253D03*
X1338404Y1038136D03*
X1343953Y1041340D03*
X1345804Y1038136D03*
X1336553Y1034931D03*
X1347653D03*
X1340253D03*
X1334704Y1044544D03*
X1343953Y1034931D03*
X1340253Y1047749D03*
X1343953D03*
X1332853Y1060565D03*
X1334704Y1063770D03*
X1340253Y1060565D03*
X1338404Y1057361D03*
X1343953Y1060565D03*
X1345804Y1057361D03*
X1338404Y1050952D03*
X1345804D03*
X1336553Y1054157D03*
X1347653D03*
X1340253D03*
X1343953D03*
X1332853Y1066974D03*
X1343953Y1079791D03*
X1345804Y1076587D03*
X1338404Y1070178D03*
X1340253Y1066974D03*
X1345804Y1070178D03*
X1343953Y1066974D03*
X1332853Y1079791D03*
X1340253D03*
X1338404Y1076587D03*
X1336553Y1073383D03*
X1347653D03*
X1340253D03*
X1343953D03*
X1332853Y1086200D03*
X1334704Y1082995D03*
X1338404Y1095813D03*
X1345804D03*
X1338404Y1089404D03*
X1340253Y1086200D03*
X1345804Y1089404D03*
X1343953Y1086200D03*
X1336553Y1092608D03*
X1343953D03*
X1340253D03*
X1347653D03*
X1340253Y1099017D03*
X1343953D03*
X1345803Y1108630D03*
X1340254Y1105426D03*
X1336554Y1111834D03*
X1334703Y1108630D03*
X1343954Y1111834D03*
X1342103Y1108630D03*
X1338403D03*
X1334703Y1121447D03*
X1336554Y1124651D03*
X1340253D03*
X1343953D03*
X1347653D03*
X1332854D03*
X1338404Y1127856D03*
X1342104Y1121447D03*
X1345804Y1127856D03*
X1342103Y1115039D03*
X1345803D03*
X1334703D03*
Y1134264D03*
X1338403Y1140973D03*
X1342104Y1134264D03*
X1345803Y1140973D03*
X1332854Y1137469D03*
X1336554D03*
X1340254D03*
X1343954D03*
X1347654D03*
X1352557Y168548D03*
X1355762Y166698D03*
X1352557Y172248D03*
X1349351Y177798D03*
Y170398D03*
Y174098D03*
X1352557Y175948D03*
X1349351Y181498D03*
X1355761Y185198D03*
X1349351D03*
X1355761Y174098D03*
Y181498D03*
X1352557Y183348D03*
X1352561Y198148D03*
X1355771Y196298D03*
X1355765Y199999D03*
Y203699D03*
X1363869Y844971D03*
X1352769D03*
X1356469D03*
X1360169D03*
X1362021Y841467D03*
X1349069Y844971D03*
X1350920Y848176D03*
X1354621Y841467D03*
X1358320Y848176D03*
X1354620Y867401D03*
X1362020D03*
X1349071Y857789D03*
X1354620Y854584D03*
X1356471Y857789D03*
X1360171D03*
X1363871D03*
X1350920Y860993D03*
X1352771Y857789D03*
X1358320Y860993D03*
X1362020Y854584D03*
X1363871Y870606D03*
X1349071D03*
X1356471D03*
X1350920Y873810D03*
X1352771Y870606D03*
X1358320Y873810D03*
X1360171Y870606D03*
X1350920Y899445D03*
X1358320D03*
Y893036D03*
X1350920D03*
X1362020D03*
X1349071Y896240D03*
X1356471D03*
X1352771D03*
X1360171D03*
X1352771Y902649D03*
X1356471D03*
X1350920Y912262D03*
X1352771Y909057D03*
X1358320Y912262D03*
X1356471Y909057D03*
X1363871D03*
Y902649D03*
X1349071Y915466D03*
X1362020Y905853D03*
X1356471Y915466D03*
X1352771D03*
X1360171D03*
X1350920Y931488D03*
X1352771Y928283D03*
X1358320Y931488D03*
X1356471Y928283D03*
X1363871Y921875D03*
X1352771D03*
X1350920Y918670D03*
X1356471Y921875D03*
X1358320Y918670D03*
X1363871Y928283D03*
X1362020Y925079D03*
X1356471Y941100D03*
X1358320Y937896D03*
X1352771Y947509D03*
X1356471D03*
X1352771Y941100D03*
X1350920Y937896D03*
X1349071Y934691D03*
X1356471D03*
X1352771D03*
X1360171D03*
X1363871Y947509D03*
Y941100D03*
X1362020Y944304D03*
X1352771Y960326D03*
X1350920Y957122D03*
X1356471Y960326D03*
X1358320Y957122D03*
X1350920Y950713D03*
X1358320D03*
X1349071Y953917D03*
X1356471D03*
X1352771D03*
X1360171D03*
X1363871Y960326D03*
Y966735D03*
X1356471D03*
X1352771D03*
X1362020Y963530D03*
Y982756D03*
X1363871Y979552D03*
X1352771D03*
X1356471D03*
X1350920Y976347D03*
X1358320D03*
X1349071Y973143D03*
X1350920Y969939D03*
X1358320D03*
X1360171Y973143D03*
X1349504Y1006093D03*
X1356904D03*
X1353204D03*
X1360604D03*
X1351353Y1002888D03*
X1353204Y999684D03*
X1358753Y1002888D03*
X1356904Y999684D03*
X1353204Y1012501D03*
X1351353Y1009297D03*
X1356904Y1012501D03*
X1358753Y1009297D03*
X1353204Y1031727D03*
X1351353Y1028523D03*
X1356904Y1031727D03*
X1358753Y1028523D03*
X1351353Y1022114D03*
X1353204Y1018910D03*
X1358753Y1022114D03*
X1356904Y1018910D03*
X1353204Y1025318D03*
X1360604D03*
X1349502D03*
X1356902D03*
X1362453Y1015705D03*
X1351353Y1047749D03*
X1358753D03*
X1351353Y1041340D03*
X1353204Y1038136D03*
X1358753Y1041340D03*
X1356904Y1038136D03*
X1349504Y1044544D03*
X1356904D03*
X1353204D03*
X1360604D03*
X1362453Y1034931D03*
X1351353Y1060565D03*
X1353204Y1057361D03*
X1358753Y1060565D03*
X1356904Y1057361D03*
X1353204Y1050952D03*
X1356904D03*
X1349504Y1063770D03*
X1360604D03*
X1353204D03*
X1356904D03*
X1362453Y1054157D03*
X1356904Y1070178D03*
X1358753Y1066974D03*
X1353204Y1070178D03*
X1351353Y1066974D03*
Y1079791D03*
X1353204Y1076587D03*
X1358753Y1079791D03*
X1356904Y1076587D03*
X1362453Y1073383D03*
X1353204Y1089404D03*
X1351353Y1086200D03*
X1356904Y1089404D03*
X1358753Y1086200D03*
X1349504Y1082995D03*
X1362453Y1092608D03*
X1360604Y1082995D03*
X1353204D03*
X1356904D03*
X1362453Y1111834D03*
Y1105426D03*
X1358753D03*
X1351353Y1111834D03*
Y1105426D03*
X1358753Y1111834D03*
X1360604Y1108630D03*
X1355053Y1111834D03*
X1356904Y1102221D03*
X1353204Y1108630D03*
X1355054Y1105426D03*
X1351353Y1124651D03*
X1355053D03*
X1358753D03*
X1362453D03*
X1349504Y1121447D03*
X1353204Y1127856D03*
X1356904Y1121447D03*
X1360604Y1127856D03*
X1356904Y1115039D03*
X1349504Y1134264D03*
X1353203Y1140973D03*
X1356904Y1134264D03*
X1360603Y1140973D03*
X1351354Y1137469D03*
X1355054D03*
X1358754D03*
X1362454D03*
X1367569Y844971D03*
X1369421Y841467D03*
X1373120Y848176D03*
X1376821Y841467D03*
X1365720Y848176D03*
X1371269Y844971D03*
X1374969D03*
X1378669D03*
X1376820Y867401D03*
X1369420D03*
X1365720Y860993D03*
X1367571Y857789D03*
X1373120Y860993D03*
X1374971Y857789D03*
X1369420Y854584D03*
X1371271Y857789D03*
X1376820Y854584D03*
X1378671Y857789D03*
X1367571Y870606D03*
X1371271D03*
X1378671D03*
X1365720Y873810D03*
X1373120D03*
X1374971Y870606D03*
X1365720Y899445D03*
X1369420D03*
X1365720Y912262D03*
X1369420D03*
X1371271Y909057D03*
Y902649D03*
X1369420Y905853D03*
X1365720D03*
X1373120D03*
X1369420Y931488D03*
X1371271Y928283D03*
X1365720Y918670D03*
X1371271Y921875D03*
X1369420Y918670D03*
X1365720Y931488D03*
X1369420Y925079D03*
X1365720D03*
X1373120D03*
X1371271Y947509D03*
X1365720Y937896D03*
X1371271Y941100D03*
X1369420Y937896D03*
Y944304D03*
X1365720D03*
X1373120D03*
X1365720Y957122D03*
X1371271Y960326D03*
X1369420Y957122D03*
X1371271Y966735D03*
X1365720Y950713D03*
X1369420D03*
X1373120Y963530D03*
X1369420D03*
X1365720D03*
X1374971Y973143D03*
X1376820Y976347D03*
X1378671Y979552D03*
Y973143D03*
X1369420Y982756D03*
X1365720D03*
X1373120D03*
X1369420Y976347D03*
X1371271Y979552D03*
X1365721Y976347D03*
X1365720Y969939D03*
X1369420D03*
X1366153Y1002888D03*
X1364304Y999684D03*
X1369853Y1002888D03*
X1371704Y999684D03*
X1364304Y1012501D03*
X1371704D03*
X1366153Y1009297D03*
X1369853D03*
X1373553Y1015705D03*
X1364304Y1031727D03*
X1366153Y1028523D03*
X1371704Y1031727D03*
X1369853Y1028523D03*
X1366153Y1022114D03*
X1364304Y1018910D03*
X1369853Y1022114D03*
X1371704Y1018910D03*
X1366153Y1041340D03*
X1364304Y1038136D03*
X1369853Y1041340D03*
X1371704Y1038136D03*
X1366153Y1047749D03*
X1369853D03*
Y1034931D03*
X1366153D03*
X1373553D03*
X1366153Y1060565D03*
X1364304Y1057361D03*
X1369853Y1060565D03*
X1371704Y1057361D03*
X1364304Y1050952D03*
X1371704D03*
X1369853Y1054157D03*
X1366153D03*
X1373553D03*
X1366153Y1079791D03*
X1364304Y1076587D03*
X1369853Y1079791D03*
X1371704Y1076587D03*
X1364304Y1070178D03*
X1366153Y1066974D03*
X1371704Y1070178D03*
X1369853Y1066974D03*
Y1073383D03*
X1366153D03*
X1373553D03*
X1371704Y1095813D03*
X1364304Y1089404D03*
X1366153Y1086200D03*
X1371704Y1089404D03*
X1369853Y1086200D03*
X1364304Y1095813D03*
X1369853Y1092608D03*
X1366153D03*
X1373553D03*
X1379104Y1082995D03*
X1379103Y1089404D03*
X1369853Y1099017D03*
X1366153D03*
X1369853Y1111834D03*
X1368004Y1108630D03*
X1377253Y1099017D03*
X1379104Y1108630D03*
X1373553Y1105426D03*
X1371704Y1108630D03*
X1379104Y1102221D03*
X1377253Y1111834D03*
X1375404Y1108630D03*
X1366153Y1124651D03*
X1371704Y1121447D03*
X1373553Y1124651D03*
X1377253D03*
X1368004Y1127856D03*
X1369853Y1124651D03*
X1375404Y1127856D03*
X1379104Y1121447D03*
X1364304D03*
X1375404Y1115039D03*
X1368004D03*
X1379104D03*
X1368003Y1140973D03*
X1371704Y1134264D03*
X1375403Y1140973D03*
X1379104Y1134264D03*
X1364304D03*
X1366154Y1137469D03*
X1369854D03*
X1373554D03*
X1377254D03*
X1380520Y848176D03*
X1386069Y844971D03*
X1389769D03*
X1393469D03*
X1382369D03*
X1384221Y841467D03*
X1387920Y848176D03*
X1391621Y841467D03*
X1395320Y848176D03*
X1384220Y867401D03*
X1391620D03*
X1380520Y860993D03*
X1382371Y857789D03*
X1387920Y860993D03*
X1389771Y857789D03*
X1395320Y860993D03*
X1384220Y854584D03*
X1386071Y857789D03*
X1391620Y854584D03*
X1393471Y857789D03*
X1380520Y873810D03*
X1382371Y870606D03*
X1395320Y873810D03*
X1393471Y870606D03*
X1387920Y873810D03*
X1389771Y870606D03*
X1393471Y883423D03*
X1391620Y880219D03*
X1389771Y883423D03*
X1386071Y896240D03*
X1389771D03*
X1393471D03*
X1387920Y899445D03*
X1391620Y893036D03*
X1395320Y899445D03*
Y886627D03*
X1384653Y1079791D03*
X1388353Y1086200D03*
X1386504Y1082995D03*
X1390204Y1089404D03*
X1382804D03*
X1390204Y1082995D03*
X1382804D03*
X1395753Y1086200D03*
Y1092608D03*
X1380953Y1086200D03*
X1386504Y1089404D03*
X1384653Y1092608D03*
X1380953Y1099017D03*
X1395753Y1105426D03*
X1393904Y1108630D03*
X1390204Y1102221D03*
X1392053Y1111834D03*
X1388353D03*
X1384653Y1105426D03*
Y1099017D03*
X1392053Y1105426D03*
X1395753Y1111834D03*
X1388353Y1105426D03*
X1384653Y1111834D03*
X1386504Y1108630D03*
X1380953Y1124651D03*
X1384653D03*
X1382804Y1127856D03*
X1386504Y1121447D03*
X1390204Y1115039D03*
X1382803Y1140973D03*
X1386504Y1134264D03*
X1380954Y1137469D03*
X1384654D03*
X1397169Y844971D03*
X1399021Y841467D03*
X1402720Y848176D03*
X1406420D03*
X1411969Y844971D03*
X1400869D03*
X1404569D03*
X1410120Y848176D03*
X1406420Y867401D03*
X1399020D03*
X1397171Y857789D03*
X1402720Y860993D03*
X1404571Y857789D03*
X1410121Y860993D03*
X1411971Y857789D03*
X1399020Y854584D03*
X1400871Y857789D03*
X1406420Y854584D03*
X1408271Y857789D03*
Y870606D03*
X1402720Y873810D03*
X1400871Y870606D03*
X1410121Y873810D03*
X1404571Y870606D03*
X1397171D03*
X1411971D03*
X1408271Y883423D03*
X1406420Y880219D03*
X1400871Y883423D03*
X1399020Y880219D03*
X1404571Y883423D03*
X1397171D03*
X1411971D03*
X1397171Y896240D03*
X1402720Y899445D03*
X1404571Y896240D03*
X1410120Y899445D03*
X1399020Y893036D03*
X1400871Y896240D03*
X1406420Y893036D03*
X1408271Y896240D03*
X1411971D03*
X1410120Y886627D03*
X1402720D03*
X1405003Y1076587D03*
X1406853Y1079791D03*
X1401304Y1082995D03*
X1405003Y1089404D03*
X1399453Y1086200D03*
X1406853Y1092608D03*
X1399453D03*
X1397604Y1089404D03*
X1403154Y1086200D03*
X1406852D03*
X1403153Y1092608D03*
X1401304Y1095813D03*
X1413820Y848176D03*
X1428620Y867401D03*
X1421220D03*
X1413820D03*
X1424921Y860993D03*
X1421220Y854584D03*
X1417520Y860993D03*
X1428620Y854584D03*
X1426771Y857789D03*
X1423071D03*
X1419371D03*
X1413821Y854584D03*
X1424921Y873810D03*
X1423071Y870606D03*
X1417520Y873810D03*
X1415671Y870606D03*
X1426771D03*
X1419371D03*
X1428621Y880219D03*
X1423071Y883423D03*
X1421220Y880219D03*
X1415671Y883423D03*
X1413820Y880219D03*
X1426771Y883423D03*
X1419371D03*
X1413820Y893036D03*
X1421220Y899445D03*
X1419371Y896240D03*
X1424920Y899445D03*
X1426772Y896240D03*
X1417520Y899445D03*
X1421220Y893036D03*
X1423071Y896240D03*
X1428621Y893036D03*
X1424920Y886627D03*
X1417520D03*
X1443420Y867401D03*
X1436020D03*
X1445271Y857789D03*
X1439720Y860993D03*
X1437871Y857789D03*
X1432320Y860993D03*
X1430471Y857789D03*
X1443420Y854584D03*
X1441571Y857789D03*
X1436020Y854584D03*
X1434171Y857789D03*
X1445271Y870606D03*
X1439720Y873810D03*
X1437871Y870606D03*
X1432320Y873810D03*
X1430471Y870606D03*
X1441571D03*
X1434171D03*
X1445271Y883423D03*
X1443420Y880219D03*
X1437871Y883423D03*
X1436020Y880219D03*
X1430471Y883423D03*
X1441571D03*
X1434171D03*
X1430471Y896240D03*
X1436020Y893036D03*
X1437871Y896240D03*
X1441571D03*
X1432320Y899445D03*
X1434171Y896240D03*
X1439720Y899445D03*
X1443420Y893036D03*
X1439720Y886627D03*
X1432320D03*
X1450820Y867401D03*
X1458220D03*
X1460071Y857789D03*
X1454520Y860993D03*
X1452671Y857789D03*
X1447120Y860993D03*
X1458220Y854584D03*
X1456371Y857789D03*
X1450820Y854584D03*
X1448971Y857789D03*
X1456371Y870606D03*
X1452671D03*
X1454520Y873810D03*
X1460071Y870606D03*
X1458220Y893036D03*
X1460071Y896240D03*
X1447120Y886627D03*
X1460071Y915466D03*
Y934691D03*
Y953917D03*
Y973143D03*
X1460504Y1006093D03*
Y1025318D03*
Y1044544D03*
Y1063770D03*
Y1082995D03*
Y1121447D03*
X1456804Y1127856D03*
X1453104Y1121447D03*
X1449404Y1127856D03*
X1445704Y1121447D03*
X1458653Y1124651D03*
X1454953D03*
X1451253D03*
X1447553D03*
X1460504Y1134264D03*
X1458654Y1137469D03*
X1453104Y1134264D03*
X1451254Y1137469D03*
X1456803Y1140973D03*
X1454954Y1137469D03*
X1449403Y1140973D03*
X1465620Y867401D03*
X1473020D03*
X1467471Y857789D03*
X1461920Y860993D03*
X1476720D03*
X1474871Y857789D03*
X1471171D03*
X1465620Y854584D03*
X1463771Y857789D03*
X1473020Y854584D03*
X1469320Y860993D03*
X1463771Y870606D03*
X1471171D03*
X1461920Y873810D03*
X1467471Y870606D03*
X1469320Y873810D03*
X1474871Y870606D03*
X1476720Y873810D03*
Y899445D03*
X1461920D03*
X1469320D03*
Y893036D03*
X1473020D03*
X1461920D03*
X1467471Y896240D03*
X1463771D03*
X1471171D03*
X1461920Y912262D03*
X1463771Y909057D03*
X1469320Y912262D03*
X1467471Y909057D03*
X1476720Y912262D03*
X1474871Y909057D03*
Y902649D03*
X1463771D03*
X1467471D03*
X1463771Y915466D03*
X1476720Y905853D03*
X1471171Y915466D03*
X1473020Y905853D03*
X1467471Y915466D03*
X1476720Y931488D03*
X1474871Y921875D03*
X1476720Y918670D03*
X1474871Y928283D03*
X1473020Y925079D03*
X1476720D03*
X1467471Y921875D03*
X1469320Y918670D03*
X1461920Y931488D03*
X1467471Y928283D03*
X1469320Y931488D03*
X1463771Y928283D03*
Y921875D03*
X1461920Y918670D03*
X1474871Y947509D03*
Y941100D03*
X1476720Y937896D03*
X1473020Y944304D03*
X1476720D03*
X1463771Y947509D03*
X1467471D03*
X1463771Y941100D03*
X1461920Y937896D03*
X1467471Y941100D03*
X1469320Y937896D03*
X1463771Y934691D03*
X1471171D03*
X1467471D03*
X1476720Y950713D03*
X1463771Y966735D03*
X1467471D03*
X1474871D03*
X1473020Y963530D03*
X1461920Y950713D03*
X1469320D03*
X1467471Y960326D03*
X1469320Y957122D03*
X1463771Y960326D03*
X1461920Y957122D03*
X1476720D03*
X1474871Y960326D03*
X1471171Y953917D03*
X1463771D03*
X1467471D03*
X1463771Y979552D03*
X1461920Y976347D03*
X1467471Y979552D03*
X1469320Y976347D03*
X1476720Y982756D03*
X1473020D03*
X1474871Y979552D03*
X1476720Y976347D03*
X1471171Y973143D03*
X1463771D03*
X1467471D03*
X1461920Y969939D03*
X1469320D03*
X1476720D03*
X1477153Y1002888D03*
X1475304Y999684D03*
Y1012501D03*
X1477153Y1009297D03*
X1471604Y1006093D03*
X1462353Y1002888D03*
X1469753D03*
X1464204Y999684D03*
X1467904D03*
X1467903Y1012501D03*
X1469753Y1009297D03*
X1464204Y1012501D03*
X1462353Y1009297D03*
X1473453Y1015705D03*
X1475304Y1031727D03*
X1477153Y1028523D03*
Y1022114D03*
X1475304Y1018910D03*
X1464204Y1031727D03*
X1462353Y1028523D03*
X1467904Y1031727D03*
X1469753Y1028523D03*
X1462353Y1022114D03*
X1464204Y1018910D03*
X1469753Y1022114D03*
X1467904Y1018910D03*
X1464204Y1025318D03*
X1471604D03*
X1467904D03*
X1477153Y1041340D03*
X1475304Y1038136D03*
X1477153Y1047749D03*
Y1034931D03*
X1473453D03*
X1462353Y1047749D03*
X1469753D03*
X1462353Y1041340D03*
X1464204Y1038136D03*
X1469753Y1041340D03*
X1467904Y1038136D03*
X1464204Y1044544D03*
X1471604D03*
X1467904D03*
X1477153Y1060565D03*
X1475304Y1057361D03*
Y1050952D03*
X1477153Y1054157D03*
X1473453D03*
X1462353Y1060565D03*
X1464204Y1057361D03*
X1469753Y1060565D03*
X1467904Y1057361D03*
X1464204Y1050952D03*
X1467904D03*
X1464204Y1063770D03*
X1471604D03*
X1467904D03*
X1475304Y1070178D03*
X1477153Y1066974D03*
Y1079791D03*
X1475304Y1076587D03*
X1473453Y1073383D03*
X1477153D03*
X1462353Y1079791D03*
X1464204Y1076587D03*
X1469753Y1079791D03*
X1467904Y1076587D03*
X1464204Y1070178D03*
X1462353Y1066974D03*
X1467904Y1070178D03*
X1469753Y1066974D03*
X1467904Y1089404D03*
X1469753Y1086200D03*
X1475304Y1089404D03*
X1477153Y1086200D03*
X1464204Y1089404D03*
X1462353Y1086200D03*
X1473453Y1092608D03*
X1471604Y1082995D03*
X1477153Y1092608D03*
X1464204Y1082995D03*
X1467904D03*
X1464204Y1127856D03*
X1475304Y1121447D03*
X1471604Y1127856D03*
X1467904Y1121447D03*
X1466053Y1124651D03*
X1462353D03*
X1477153D03*
X1473453D03*
X1469753D03*
X1469754Y1137469D03*
X1464203Y1140973D03*
X1477154Y1137469D03*
X1471603Y1140973D03*
X1467904Y1134264D03*
X1466054Y1137469D03*
X1462354D03*
X1475304Y1134264D03*
X1473454Y1137469D03*
X1487820Y867401D03*
X1480420D03*
X1491520Y860993D03*
X1489671Y857789D03*
X1484120Y860993D03*
X1482271Y857789D03*
X1493371D03*
X1487820Y854584D03*
X1485971Y857789D03*
X1480420Y854584D03*
X1478571Y857789D03*
X1493371Y870606D03*
X1478571D03*
X1485971D03*
X1489671D03*
X1491520Y873810D03*
X1482271Y870606D03*
X1484120Y873810D03*
X1487820Y899445D03*
Y893036D03*
X1484120D03*
X1485971Y896240D03*
X1493371D03*
X1489671D03*
X1480420Y899445D03*
X1489671Y902649D03*
X1493371D03*
X1487820Y912262D03*
X1489671Y909057D03*
X1493371D03*
X1489671Y915466D03*
X1485971D03*
X1493371D03*
X1480420Y912262D03*
X1482271Y909057D03*
Y902649D03*
X1484120Y905853D03*
X1480420D03*
X1487820Y931488D03*
X1489671Y928283D03*
X1493371D03*
X1482271D03*
Y921875D03*
X1480420Y918670D03*
X1489671Y921875D03*
X1487820Y918670D03*
X1493371Y921875D03*
X1480420Y931488D03*
Y925079D03*
X1484120D03*
X1489671Y941100D03*
X1487820Y937896D03*
X1493371Y941100D03*
X1489671Y934691D03*
X1485971D03*
X1493371D03*
X1489671Y947509D03*
X1493371D03*
X1482271D03*
Y941100D03*
X1480420Y937896D03*
X1484120Y944304D03*
X1480420D03*
X1487820Y950713D03*
X1489671Y960326D03*
X1487820Y957122D03*
X1493371Y960326D03*
Y966735D03*
X1489671D03*
X1480420Y950713D03*
X1489671Y953917D03*
X1493371D03*
X1485971D03*
X1482271Y966735D03*
X1480420Y957122D03*
X1482271Y960326D03*
X1484120Y963530D03*
Y982756D03*
X1480420D03*
Y976347D03*
X1482271Y979552D03*
X1489671D03*
X1493371D03*
X1487820Y976347D03*
X1485971Y973143D03*
X1487820Y969939D03*
X1480420D03*
X1493804Y1006093D03*
X1490104D03*
X1486404D03*
X1493804Y1012501D03*
X1480853Y1002888D03*
X1482703Y999684D03*
X1490104Y1012501D03*
X1488253Y1009297D03*
X1482704Y1012501D03*
X1480853Y1009297D03*
X1493803Y999684D03*
X1488253Y1002888D03*
X1490104Y999684D03*
Y1031727D03*
X1488253Y1028523D03*
X1493804Y1031727D03*
X1488253Y1022114D03*
X1490104Y1018910D03*
X1493804D03*
X1490104Y1025318D03*
X1486404D03*
X1493804D03*
X1484553Y1015705D03*
X1482704Y1031727D03*
X1480853Y1028523D03*
Y1022114D03*
X1482704Y1018910D03*
X1480853Y1041340D03*
X1482704Y1038136D03*
X1488253Y1047749D03*
Y1041340D03*
X1490104Y1038136D03*
X1493804D03*
X1480853Y1047749D03*
X1486404Y1044544D03*
X1484553Y1034931D03*
X1490104Y1044544D03*
X1493804D03*
X1480853Y1034931D03*
X1488253Y1060565D03*
X1490104Y1057361D03*
X1493804D03*
X1486404Y1063770D03*
X1490104D03*
X1493804D03*
X1490104Y1050952D03*
X1493804D03*
X1480853Y1060565D03*
X1482704Y1057361D03*
Y1050952D03*
X1484553Y1054157D03*
X1480853D03*
X1493804Y1070178D03*
X1490104D03*
X1488253Y1066974D03*
X1480853Y1079791D03*
X1482704Y1076587D03*
Y1070178D03*
X1480853Y1066974D03*
X1488253Y1079791D03*
X1490104Y1076587D03*
X1493804D03*
X1484553Y1073383D03*
X1480853D03*
X1490104Y1089404D03*
X1488253Y1086200D03*
X1493804Y1089404D03*
X1490104Y1082995D03*
X1486404D03*
X1493804D03*
X1486404Y1095813D03*
X1482703D03*
X1482704Y1089404D03*
X1480853Y1086200D03*
X1484553Y1092608D03*
X1480853D03*
X1493804Y1102221D03*
X1491953Y1099017D03*
X1493804Y1127856D03*
X1490104Y1121447D03*
X1486404Y1127856D03*
X1482704Y1121447D03*
X1479004Y1127856D03*
X1491953Y1124651D03*
X1488253D03*
X1484553D03*
X1480853D03*
X1493803Y1140973D03*
X1490104Y1134264D03*
X1488254Y1137469D03*
X1482704Y1134264D03*
X1480854Y1137469D03*
X1491954D03*
X1486403Y1140973D03*
X1484554Y1137469D03*
X1479003Y1140973D03*
X1508171Y864197D03*
X1510021Y854584D03*
X1495220Y867401D03*
X1502621D03*
X1504471Y857789D03*
X1498920Y860993D03*
X1497071Y857789D03*
X1502620Y854584D03*
X1500771Y857789D03*
X1495220Y854584D03*
X1500771Y870606D03*
X1508171D03*
X1497071D03*
X1498920Y873810D03*
X1504471Y870606D03*
X1506321Y873810D03*
X1502621Y899445D03*
X1506320D03*
X1495220D03*
Y893036D03*
X1498920D03*
X1497071Y896240D03*
X1506321Y912262D03*
X1508171Y909057D03*
X1500771Y902649D03*
X1508171D03*
X1502621Y912262D03*
X1500771Y909057D03*
X1502621Y905853D03*
X1510021D03*
X1498920D03*
X1506321D03*
X1495220Y912262D03*
X1497071Y915466D03*
X1502621Y931488D03*
X1500771Y928283D03*
X1506321Y931488D03*
X1508171Y928283D03*
X1500771Y921875D03*
X1502621Y918670D03*
X1508171Y921875D03*
X1506321Y918670D03*
X1502621Y925079D03*
X1510021D03*
X1498920D03*
X1506321D03*
X1495220Y931488D03*
Y918670D03*
X1500771Y941100D03*
X1502621Y937896D03*
X1508171Y941100D03*
X1506321Y937896D03*
X1500771Y947509D03*
X1508171D03*
X1495220Y937896D03*
X1510021Y944304D03*
X1497071Y934691D03*
X1502621Y944304D03*
X1506320D03*
X1498920D03*
X1500771Y966735D03*
X1508171D03*
X1498920Y963530D03*
X1502621Y950713D03*
X1506320D03*
X1508171Y960326D03*
X1506320Y957122D03*
X1500771Y960326D03*
X1502621Y957122D03*
X1510021Y963530D03*
X1495220Y950713D03*
Y957122D03*
X1497071Y953917D03*
X1502621Y969939D03*
X1506321D03*
X1495220Y976347D03*
Y969939D03*
X1497071Y973143D03*
X1497504Y1006093D03*
X1501204Y1012501D03*
X1508603D03*
X1503053Y1009297D03*
X1506753D03*
X1495653D03*
X1495655Y1002888D03*
X1506753D03*
X1508603Y999684D03*
X1503053Y1002888D03*
X1501204Y999684D03*
X1499353Y1015705D03*
X1510453D03*
X1501204Y1031727D03*
X1503053Y1028523D03*
X1508603Y1031727D03*
X1506753Y1028523D03*
Y1022114D03*
X1508603Y1018910D03*
X1503053Y1022114D03*
X1501204Y1018910D03*
X1495653Y1028523D03*
Y1022114D03*
X1497504Y1025318D03*
X1503053Y1041340D03*
X1501204Y1038136D03*
X1506753Y1041340D03*
X1508603Y1038136D03*
X1503053Y1047749D03*
X1506753D03*
X1503053Y1034931D03*
X1510453D03*
X1499353D03*
X1506753D03*
X1495653Y1047749D03*
Y1041340D03*
X1497504Y1044544D03*
X1495653Y1060565D03*
X1503053D03*
X1501204Y1057361D03*
X1506753Y1060565D03*
X1508604Y1057361D03*
X1501203Y1050952D03*
X1508604Y1050953D03*
X1499353Y1054157D03*
X1497504Y1063770D03*
X1510453Y1054157D03*
X1503053D03*
X1506753D03*
Y1079791D03*
X1508604Y1076587D03*
X1501204Y1070178D03*
X1503053Y1066974D03*
X1508604Y1070178D03*
X1506753Y1066974D03*
X1503053Y1079791D03*
X1501204Y1076587D03*
X1499353Y1073383D03*
X1510453D03*
X1503053D03*
X1506753D03*
X1495653Y1066974D03*
Y1079791D03*
X1497504Y1095813D03*
X1508603D03*
X1501204D03*
Y1089404D03*
X1503053Y1086200D03*
X1508604Y1089404D03*
X1506753Y1086200D03*
X1503053Y1092608D03*
X1510452D03*
X1499353D03*
X1506753D03*
X1495653Y1086200D03*
X1497504Y1082995D03*
X1506753Y1099017D03*
X1503053Y1124651D03*
X1497504Y1121447D03*
X1501204Y1127856D03*
X1499353Y1124651D03*
X1495653D03*
X1508604Y1134264D03*
X1501203Y1140973D03*
X1499354Y1137469D03*
X1510454D03*
X1503054D03*
X1497504Y1134264D03*
X1495654Y1137469D03*
X1519271Y851380D03*
X1515571D03*
X1511871Y864197D03*
X1519270D03*
X1522970D03*
X1511871Y857789D03*
X1519271D03*
X1515571D03*
X1517421Y860993D03*
Y854584D03*
X1515571Y883423D03*
X1513720Y880219D03*
X1519271Y883423D03*
X1521121Y880219D03*
X1513720Y873810D03*
X1515571Y870606D03*
X1521121Y873810D03*
X1519271Y870606D03*
X1515570Y877014D03*
X1522970D03*
X1511871D03*
X1519271D03*
X1596941Y883924D03*
Y890617D03*
Y897310D03*
Y900656D03*
Y914042D03*
Y907349D03*
Y960892D03*
Y957546D03*
Y1185105D03*
Y1178412D03*
Y1191798D03*
Y1208530D03*
Y1201837D03*
Y1195144D03*
X1613083Y880577D03*
Y887270D03*
Y897310D03*
Y893963D03*
Y910696D03*
Y904003D03*
Y1175066D03*
Y1181759D03*
Y1191798D03*
Y1188451D03*
Y1205184D03*
Y1198491D03*
X1626641Y960892D03*
Y957546D03*
X1656441Y780184D03*
Y773491D03*
Y786877D03*
Y803609D03*
Y796916D03*
Y790223D03*
Y816995D03*
Y810302D03*
Y833727D03*
Y823688D03*
Y827034D03*
Y847113D03*
Y840420D03*
Y853806D03*
Y860499D03*
Y863845D03*
Y883924D03*
Y877231D03*
Y870538D03*
Y890617D03*
Y897310D03*
Y900656D03*
Y914042D03*
Y907349D03*
Y927428D03*
Y920735D03*
Y934121D03*
Y944160D03*
Y937467D03*
Y960892D03*
Y950853D03*
Y957546D03*
Y980971D03*
Y974278D03*
Y967585D03*
Y994357D03*
Y987664D03*
X1656141Y1027822D03*
X1656441Y1021129D03*
X1656141Y1047900D03*
Y1041207D03*
Y1034514D03*
Y1054593D03*
X1656441Y1074672D03*
Y1067979D03*
Y1091404D03*
Y1081365D03*
Y1084711D03*
Y1098097D03*
Y1111483D03*
Y1104790D03*
Y1128215D03*
Y1118176D03*
Y1121522D03*
Y1141601D03*
Y1134908D03*
Y1148294D03*
Y1154987D03*
Y1158333D03*
Y1171719D03*
Y1165026D03*
Y1185105D03*
Y1178412D03*
Y1191798D03*
Y1208530D03*
Y1201837D03*
Y1195144D03*
Y1221916D03*
Y1215223D03*
Y1238648D03*
Y1228609D03*
Y1231955D03*
Y1245341D03*
X1672583Y770144D03*
Y776837D03*
Y786877D03*
Y783530D03*
Y800263D03*
Y793570D03*
Y813648D03*
Y806955D03*
Y820341D03*
Y830381D03*
Y823688D03*
Y850459D03*
Y843766D03*
Y837074D03*
Y867192D03*
Y860499D03*
Y857152D03*
Y873885D03*
Y880577D03*
Y887270D03*
Y897310D03*
Y893963D03*
Y917389D03*
Y910696D03*
Y904003D03*
Y924081D03*
Y934121D03*
Y930774D03*
Y947507D03*
Y940814D03*
Y964239D03*
Y977625D03*
Y970932D03*
Y991011D03*
Y984318D03*
Y1021129D03*
Y1024475D03*
Y1031168D03*
X1672283Y1044554D03*
Y1037861D03*
X1672583Y1051247D03*
Y1071325D03*
Y1064633D03*
Y1078018D03*
Y1094751D03*
Y1088058D03*
Y1081365D03*
Y1108136D03*
Y1101444D03*
Y1124869D03*
Y1118176D03*
Y1114829D03*
Y1144947D03*
Y1138255D03*
Y1131562D03*
Y1161680D03*
Y1154987D03*
Y1151640D03*
Y1175066D03*
Y1168373D03*
Y1181758D03*
Y1191798D03*
Y1188451D03*
Y1205184D03*
Y1198491D03*
Y1218569D03*
Y1211877D03*
Y1225262D03*
Y1241995D03*
Y1235302D03*
Y1228609D03*
X1686041Y960892D03*
Y957546D03*
X1686141Y967585D03*
Y1054593D03*
X1702283Y964239D03*
Y1021129D03*
Y1024475D03*
Y1051247D03*
X1715841Y780184D03*
Y773491D03*
Y786877D03*
Y803609D03*
Y796916D03*
Y790223D03*
Y816995D03*
Y810302D03*
Y833727D03*
Y823688D03*
Y827034D03*
Y847113D03*
Y840420D03*
Y853806D03*
Y860499D03*
Y863845D03*
Y883924D03*
Y877231D03*
Y870538D03*
Y890617D03*
Y897310D03*
Y900656D03*
Y914042D03*
Y907349D03*
Y927428D03*
Y920735D03*
Y934121D03*
Y944160D03*
Y937467D03*
Y960892D03*
Y950853D03*
Y957546D03*
Y980971D03*
Y974278D03*
Y967585D03*
Y994357D03*
Y987664D03*
Y1027822D03*
Y1021129D03*
Y1047900D03*
Y1041207D03*
Y1034514D03*
Y1054593D03*
Y1074672D03*
Y1067979D03*
Y1091404D03*
Y1081365D03*
Y1084711D03*
Y1098097D03*
Y1111483D03*
Y1104790D03*
Y1128215D03*
Y1118176D03*
Y1121522D03*
Y1141601D03*
Y1134908D03*
Y1148294D03*
Y1154987D03*
Y1158333D03*
Y1171719D03*
Y1165026D03*
Y1185105D03*
Y1178412D03*
Y1191798D03*
Y1208530D03*
Y1201837D03*
Y1195144D03*
Y1221916D03*
Y1215223D03*
Y1238648D03*
Y1228609D03*
Y1231955D03*
Y1245341D03*
X1731983Y770144D03*
Y776837D03*
Y786877D03*
Y783530D03*
Y800263D03*
Y793570D03*
Y813648D03*
Y806955D03*
Y820341D03*
Y830381D03*
Y823688D03*
Y850459D03*
Y843766D03*
Y837074D03*
Y867192D03*
Y860499D03*
Y857152D03*
Y873885D03*
Y880577D03*
Y887270D03*
Y897310D03*
Y893963D03*
Y917389D03*
Y910696D03*
Y904003D03*
Y924081D03*
Y934121D03*
Y930774D03*
Y947507D03*
Y940814D03*
Y964239D03*
Y977625D03*
X1731883Y970932D03*
X1731983Y991011D03*
Y984318D03*
Y1021129D03*
Y1024475D03*
Y1031168D03*
X1731683Y1044554D03*
Y1037861D03*
X1731983Y1051247D03*
X1731818Y1071326D03*
X1731883Y1064633D03*
X1731983Y1078018D03*
Y1094751D03*
Y1088058D03*
Y1081365D03*
X1731818Y1108137D03*
X1731983Y1101444D03*
Y1124869D03*
Y1118176D03*
Y1114829D03*
Y1144947D03*
Y1138255D03*
Y1131562D03*
Y1161680D03*
Y1154987D03*
Y1151640D03*
Y1175066D03*
Y1168373D03*
X1731818Y1181759D03*
X1731983Y1191798D03*
X1731818Y1188452D03*
X1731983Y1205184D03*
Y1198491D03*
Y1218569D03*
Y1211877D03*
Y1225262D03*
Y1241995D03*
Y1235302D03*
Y1228609D03*
X1745541Y960892D03*
Y957546D03*
Y967585D03*
Y1054593D03*
X1761683Y964239D03*
Y1021129D03*
Y1024475D03*
Y1051247D03*
X1775241Y780184D03*
Y773491D03*
Y786877D03*
Y803609D03*
Y796916D03*
Y790223D03*
Y816995D03*
Y810302D03*
Y833727D03*
Y823688D03*
Y827034D03*
Y847113D03*
Y840420D03*
Y853806D03*
Y860499D03*
Y863845D03*
Y883924D03*
Y877231D03*
Y870538D03*
Y890617D03*
Y897310D03*
Y900656D03*
Y914042D03*
Y907349D03*
Y927428D03*
Y920735D03*
Y934121D03*
Y944160D03*
Y937467D03*
Y960892D03*
Y950853D03*
Y957546D03*
Y980971D03*
Y974278D03*
Y967585D03*
Y994357D03*
Y987664D03*
Y1027822D03*
Y1021129D03*
Y1047900D03*
Y1041207D03*
Y1034515D03*
Y1054593D03*
Y1074672D03*
Y1067979D03*
Y1091404D03*
Y1081365D03*
Y1084711D03*
Y1098097D03*
Y1111483D03*
Y1104790D03*
Y1128215D03*
Y1118176D03*
Y1121522D03*
Y1141601D03*
Y1134908D03*
Y1148294D03*
Y1154987D03*
Y1158333D03*
Y1171719D03*
Y1165026D03*
Y1185105D03*
Y1178412D03*
Y1191798D03*
Y1208530D03*
Y1201837D03*
Y1195144D03*
Y1221916D03*
Y1215223D03*
Y1238648D03*
Y1228609D03*
Y1231955D03*
Y1245341D03*
X1791383Y770144D03*
Y776837D03*
Y786877D03*
Y783530D03*
Y800263D03*
Y793570D03*
Y813648D03*
Y806955D03*
Y820341D03*
Y830381D03*
Y823688D03*
Y850459D03*
Y843766D03*
Y837074D03*
Y867192D03*
Y860499D03*
Y857152D03*
Y873885D03*
Y880577D03*
Y887270D03*
Y897310D03*
Y893963D03*
Y917389D03*
Y910696D03*
Y904003D03*
Y924081D03*
Y934121D03*
Y930774D03*
Y947507D03*
Y940814D03*
Y964239D03*
Y977625D03*
Y970932D03*
Y991011D03*
Y984318D03*
Y1021129D03*
Y1024475D03*
Y1031168D03*
Y1044554D03*
Y1037861D03*
X1791083Y1051247D03*
X1791383Y1071325D03*
Y1064633D03*
Y1078018D03*
Y1094751D03*
Y1088058D03*
Y1081365D03*
Y1108136D03*
Y1101444D03*
Y1124869D03*
Y1118176D03*
Y1114829D03*
Y1144947D03*
Y1138255D03*
Y1131562D03*
Y1161680D03*
Y1154987D03*
Y1151640D03*
Y1175066D03*
Y1168373D03*
Y1181758D03*
Y1191798D03*
Y1188451D03*
Y1205184D03*
Y1198491D03*
Y1218570D03*
Y1211877D03*
Y1225263D03*
Y1241995D03*
Y1235302D03*
Y1228609D03*
X1804941Y960892D03*
Y957546D03*
Y967585D03*
Y1054593D03*
X1821083Y964239D03*
Y1021129D03*
Y1024475D03*
Y1051247D03*
G54D49*
X676508Y145866D03*
G54D35*
X238780Y1643661D03*
X230906Y1649173D03*
X238780Y1653110D03*
Y1657834D03*
X230906Y1653897D03*
Y1663346D03*
X238780Y1667283D03*
Y1672007D03*
X230906Y1668070D03*
Y1734212D03*
X254528Y1643661D03*
X246654Y1649173D03*
X254528Y1653110D03*
Y1657834D03*
X246654Y1653897D03*
Y1663346D03*
X254528Y1667283D03*
Y1672007D03*
X246654Y1668070D03*
Y1734212D03*
X270276Y1643661D03*
X262402Y1649173D03*
X270276Y1653110D03*
Y1657834D03*
X262402Y1653897D03*
Y1663346D03*
X270276Y1667283D03*
Y1672007D03*
X262402Y1668070D03*
Y1734212D03*
X286024Y1643661D03*
X278150Y1649173D03*
X286024Y1653110D03*
Y1657834D03*
X278150Y1653897D03*
Y1663346D03*
X286024Y1667283D03*
Y1672007D03*
X278150Y1668070D03*
Y1734212D03*
X305709Y1672007D03*
X297835Y1734212D03*
X321457Y1672007D03*
X313583Y1734212D03*
X337205Y1672007D03*
X329331Y1734212D03*
X352953Y1672007D03*
X345079Y1734212D03*
X495079D03*
X502953Y1672007D03*
X510827Y1734212D03*
X518701Y1672007D03*
X534449D03*
X526575Y1734212D03*
X550197Y1672007D03*
X542323Y1734212D03*
X562008D03*
X569882Y1672007D03*
X577756Y1734212D03*
X585630Y1672007D03*
X593504Y1734212D03*
X601378Y1672007D03*
X609252Y1734212D03*
X617126Y1672007D03*
X1246654D03*
X1238780Y1734212D03*
X1262402Y1672007D03*
X1254528Y1734212D03*
X1278150Y1672007D03*
X1270276Y1734212D03*
X1293898Y1672007D03*
X1286024Y1734212D03*
X1313583Y1672007D03*
X1305709Y1734212D03*
X1329331Y1672007D03*
X1321457Y1734212D03*
X1345079Y1672007D03*
X1337205Y1734212D03*
X1360827Y1672007D03*
X1352953Y1734212D03*
X1510827Y1672007D03*
X1502953Y1734212D03*
X1526575Y1672007D03*
X1518701Y1734212D03*
X1542323Y1672007D03*
X1534449Y1734212D03*
X1558071Y1672007D03*
X1550197Y1734212D03*
X1569882D03*
X1577756Y1672007D03*
X1585630Y1734212D03*
X1593504Y1672007D03*
X1601378Y1734212D03*
X1609252Y1672007D03*
X1617126Y1734212D03*
X1625000Y1672007D03*
G54D76*
X1886720Y1001463D03*
X1876720D03*
X1875836Y1303980D03*
X1885836D03*
X1886211Y1364167D03*
X1876211D03*
X1876165Y1669023D03*
X1886165D03*
X1897608Y1001506D03*
X1898086Y1305044D03*
X1897682Y1364479D03*
X1897402Y1670072D03*
X1907608Y1001506D03*
X1908086Y1305044D03*
X1907682Y1364479D03*
X1907402Y1670072D03*
X1935200Y1362732D03*
X1925200D03*
X1924695Y1670036D03*
X1934695D03*
X1946178Y1362781D03*
X1945484Y1670313D03*
X1967697Y1362790D03*
X1956178Y1362781D03*
X1966555Y1669946D03*
X1955484Y1670313D03*
X1977697Y1362790D03*
X1976555Y1669946D03*
X1988618Y1363081D03*
X1998618D03*
X1998147Y1669691D03*
X1988147D03*
G54D22*
X45812Y451602D03*
X61157Y69340D03*
X61470Y84622D03*
X62812Y412708D03*
X62813Y415750D03*
X49212Y451602D03*
X78269Y26474D03*
X74869D03*
X64557Y69340D03*
X72157Y75340D03*
X75557D03*
X64870Y84622D03*
X78120Y1515436D03*
Y1518836D03*
X77618Y1572504D03*
X74218D03*
X64410Y1599102D03*
Y1602502D03*
X85374Y19538D03*
X81974D03*
X92442Y26474D03*
X89042D03*
X86557Y69340D03*
X83157D03*
X94157Y75340D03*
X90998Y1518937D03*
Y1515537D03*
X99547Y19538D03*
X110320D03*
X96147D03*
X106615Y26474D03*
X103215D03*
X108557Y69340D03*
X105157D03*
X97557Y75340D03*
X113720Y19538D03*
X127894D03*
X124494D03*
X120789Y26474D03*
X117389D03*
X127157Y69340D03*
X116157Y75340D03*
X119557D03*
X130557Y69340D03*
X138157Y75340D03*
X141557D03*
X160360Y19538D03*
X156655Y26474D03*
X153255D03*
X152557Y69340D03*
X149157D03*
X163760Y19538D03*
X174533D03*
X170828Y26474D03*
X167428D03*
X175761Y69340D03*
X172361D03*
X161361Y75340D03*
X164761D03*
X167266Y1569968D03*
X170666D03*
X177933Y19538D03*
X183361Y75340D03*
X186761D03*
X188897Y1590094D03*
X192297D03*
X207894Y19538D03*
X204494D03*
X200789Y26474D03*
X197389D03*
X197761Y69340D03*
X194361D03*
X205495Y75340D03*
X208895D03*
X200957Y1590094D03*
X204357D03*
X194197Y1614292D03*
X197597D03*
X206257D03*
X194197Y1602380D03*
X197597D03*
X206257D03*
X222067Y19538D03*
X218667D03*
X214962Y26474D03*
X211562D03*
X219895Y69340D03*
X216495D03*
X225077Y1590094D03*
X213017D03*
X216417D03*
X209657Y1614292D03*
X218317D03*
X221717D03*
X209657Y1602380D03*
X218317D03*
X221717D03*
X227495Y75340D03*
X230895D03*
X237137Y1590094D03*
X240537D03*
X228477D03*
X230377Y1614292D03*
X233777D03*
X230377Y1602380D03*
X233777D03*
X249197Y1590094D03*
X252597D03*
X242437Y1614292D03*
X254497D03*
X245837D03*
X242437Y1602380D03*
X254497D03*
X245837D03*
X273317Y1590094D03*
X261257D03*
X264657D03*
X266557Y1614292D03*
X257897D03*
X269957D03*
X266557Y1602380D03*
X257897D03*
X269957D03*
X285377Y1590094D03*
X288777D03*
X276717D03*
X278617Y1614292D03*
X282017D03*
X278617Y1602380D03*
X282017D03*
X297437Y1590094D03*
X300837D03*
X290677Y1614292D03*
X302737D03*
X294077D03*
X306137D03*
X290677Y1602380D03*
X302737D03*
X294077D03*
X306137D03*
X321557Y1590094D03*
X309497D03*
X312897D03*
X314797Y1614292D03*
X318197D03*
X314797Y1602380D03*
X318197D03*
X333617Y1590094D03*
X337017D03*
X324957D03*
X330257Y1614292D03*
X338917D03*
X326857D03*
X330257Y1602380D03*
X338917D03*
X326857D03*
X345677Y1590094D03*
X349077D03*
X350977Y1614292D03*
X342317D03*
X354377D03*
X350977Y1602380D03*
X342317D03*
X354377D03*
X369797Y1590094D03*
X357737D03*
X361137D03*
X363037Y1614292D03*
X366437D03*
X363037Y1602380D03*
X366437D03*
X373197Y1590094D03*
X375097Y1614292D03*
X378497D03*
X375097Y1602380D03*
X378497D03*
X476451Y1590094D03*
X485111D03*
X473051D03*
X478351Y1614292D03*
X481751D03*
X478351Y1602380D03*
X481751D03*
X500571Y1590094D03*
X488511D03*
X497171D03*
X490411Y1614292D03*
X493811D03*
X490411Y1602380D03*
X493811D03*
X512631Y1590094D03*
X509231D03*
X514531Y1614292D03*
X502471D03*
X517931D03*
X505871D03*
X514531Y1602380D03*
X502471D03*
X517931D03*
X505871D03*
X519764Y40328D03*
X523164D03*
X519742Y71436D03*
X523142D03*
X524691Y1590094D03*
X533351D03*
X521291D03*
X526591Y1614292D03*
X529991D03*
X526591Y1602380D03*
X529991D03*
X536751Y1590094D03*
X548811D03*
X545411D03*
X538651Y1614292D03*
X542051D03*
X538651Y1602380D03*
X542051D03*
X555175Y71436D03*
X558575D03*
X560871Y1590094D03*
X557471D03*
X562771Y1614292D03*
X550711D03*
X566171D03*
X554111D03*
X562771Y1602380D03*
X550711D03*
X566171D03*
X554111D03*
X572931Y1590094D03*
X581591D03*
X569531D03*
X574831Y1614292D03*
X578231D03*
X574831Y1602380D03*
X578231D03*
X597051Y1590094D03*
X584991D03*
X593651D03*
X598951Y1614292D03*
X586891D03*
X590291D03*
X598951Y1602380D03*
X586891D03*
X590291D03*
X613970Y188752D03*
X609111Y1590094D03*
X605711D03*
X611011Y1614292D03*
X614411D03*
X602351D03*
X611011Y1602380D03*
X614411D03*
X602351D03*
X617370Y188752D03*
X630040D03*
X626640D03*
X621171Y1590094D03*
X629831D03*
X617771D03*
X623071Y1614292D03*
X626471D03*
X623071Y1602380D03*
X626471D03*
X645291Y1590094D03*
X633231D03*
X641891D03*
X647191Y1614292D03*
X635131D03*
X638531D03*
X647191Y1602380D03*
X635131D03*
X638531D03*
X656439Y47264D03*
X659839D03*
X657351Y1590094D03*
X653951D03*
X662651Y1614292D03*
X659251D03*
X650591D03*
X662651Y1602380D03*
X659251D03*
X650591D03*
X723041Y-13200D03*
Y-9800D03*
X716698Y185687D03*
Y173687D03*
Y177087D03*
Y197187D03*
Y200587D03*
Y189087D03*
Y209021D03*
Y212421D03*
X840001Y20200D03*
Y16800D03*
X902350Y208294D03*
X907470Y211980D03*
X902350Y204894D03*
X907470Y215380D03*
X902350Y219068D03*
X907470Y226154D03*
X902350Y222468D03*
X907470Y229554D03*
X953970Y208275D03*
X947496Y215397D03*
X953970Y204875D03*
X947496Y211997D03*
X957156Y227163D03*
X947496Y226135D03*
X957156Y230563D03*
X947496Y229535D03*
X980899Y-13200D03*
Y-9800D03*
Y20200D03*
Y16800D03*
X1032433Y-23211D03*
Y-19811D03*
Y-13211D03*
Y-9811D03*
Y-3211D03*
Y189D03*
X1156770Y638192D03*
X1153370D03*
X1161860Y642112D03*
X1165260D03*
X1173220Y636052D03*
X1169820D03*
X1183360Y642062D03*
X1186760D03*
X1196772Y1578182D03*
X1200172D03*
X1196772Y1590094D03*
X1200172D03*
X1212232Y1578182D03*
X1208832D03*
X1212232Y1590094D03*
X1208832D03*
X1214132Y1614292D03*
X1202072D03*
X1217532D03*
X1205472D03*
X1220892Y1578182D03*
X1232952D03*
X1224292D03*
X1220892Y1590094D03*
X1232952D03*
X1224292D03*
X1226192Y1614292D03*
X1229592D03*
X1245012Y1578182D03*
X1236352D03*
X1248412D03*
X1245012Y1590094D03*
X1236352D03*
X1248412D03*
X1238252Y1614292D03*
X1241652D03*
X1257072Y1578182D03*
X1260472D03*
X1257072Y1590094D03*
X1260472D03*
X1262372Y1614292D03*
X1250312D03*
X1265772D03*
X1253712D03*
X1269132Y1578182D03*
X1281192D03*
X1272532D03*
X1269132Y1590094D03*
X1281192D03*
X1272532D03*
X1274432Y1614292D03*
X1277832D03*
X1290291Y-23211D03*
Y-19811D03*
Y-13211D03*
Y-9811D03*
Y-3211D03*
Y189D03*
X1293252Y1578182D03*
X1284592D03*
X1296652D03*
X1293252Y1590094D03*
X1284592D03*
X1296652D03*
X1298552Y1614292D03*
X1286492D03*
X1289892D03*
X1305312Y1578182D03*
X1308712D03*
X1305312Y1590094D03*
X1308712D03*
X1310612Y1614292D03*
X1314012D03*
X1301952D03*
X1317372Y1578182D03*
X1320772D03*
X1329432D03*
X1317372Y1590094D03*
X1320772D03*
X1329432D03*
X1322672Y1614292D03*
X1326072D03*
X1341752Y-19811D03*
Y-23211D03*
Y-9811D03*
Y-13211D03*
Y189D03*
Y-3211D03*
X1344684Y280259D03*
X1332832Y1578182D03*
X1341492D03*
X1344892D03*
X1332832Y1590094D03*
X1341492D03*
X1344892D03*
X1346792Y1614292D03*
X1334732D03*
X1338132D03*
X1348084Y280259D03*
X1358624Y284644D03*
X1355224D03*
X1353552Y1578182D03*
X1356952D03*
X1353552Y1590094D03*
X1356952D03*
X1358852Y1614292D03*
X1362252D03*
X1350192D03*
X1380522Y260236D03*
Y263636D03*
X1368524Y282744D03*
X1365124D03*
X1378306Y657608D03*
X1374668Y659708D03*
X1378306Y669608D03*
X1374668Y671708D03*
Y683708D03*
X1378306Y681608D03*
X1374668Y695708D03*
X1378306Y693608D03*
Y705608D03*
X1374668Y707708D03*
Y719708D03*
X1378306Y717608D03*
X1365612Y1578182D03*
X1377672D03*
X1369012D03*
X1365612Y1590094D03*
X1377672D03*
X1369012D03*
X1370912Y1614292D03*
X1374312D03*
X1384002Y197668D03*
X1389256D03*
X1380602D03*
X1392656D03*
X1380638Y245694D03*
X1386630Y238651D03*
X1380638Y249094D03*
X1386630Y242051D03*
X1388754Y253803D03*
Y257203D03*
X1386273Y268670D03*
Y272070D03*
X1393206Y664708D03*
X1389568Y662608D03*
X1393206Y679208D03*
X1389568Y677108D03*
X1393206Y693708D03*
X1389568Y691608D03*
Y706108D03*
X1393206Y708208D03*
X1393199Y722708D03*
X1389561Y720608D03*
X1385338Y735098D03*
X1388976Y737198D03*
X1381072Y1578182D03*
Y1590094D03*
X1382972Y1614292D03*
X1386372D03*
X1412284Y171696D03*
X1398006Y197668D03*
X1406786D03*
X1401406D03*
X1410186D03*
X1407420Y220018D03*
X1410820D03*
X1404385Y240929D03*
X1400985D03*
X1415684Y171696D03*
X1436060Y220018D03*
X1432660D03*
X1457176Y656992D03*
X1460814Y654892D03*
Y666892D03*
X1457176Y668992D03*
X1460814Y678892D03*
X1457176Y680992D03*
X1460814Y690892D03*
X1457176Y704992D03*
Y692992D03*
X1460814Y702892D03*
X1457176Y716992D03*
X1460814Y714892D03*
X1472076Y657392D03*
Y671892D03*
X1475714Y659492D03*
Y673992D03*
X1472076Y686392D03*
X1475714Y688492D03*
X1472076Y700892D03*
X1475714Y702992D03*
X1472076Y715392D03*
X1475714Y717492D03*
X1468876Y728392D03*
X1472514Y730492D03*
X1477755Y1590094D03*
X1462295D03*
X1474355D03*
X1465695D03*
X1467595Y1614292D03*
X1470995D03*
X1467595Y1602380D03*
X1470995D03*
X1482650Y-19811D03*
Y-23211D03*
Y-9811D03*
Y-13211D03*
Y189D03*
Y-3211D03*
X1489815Y1590094D03*
X1486415D03*
X1491715Y1614292D03*
X1479655D03*
X1483055D03*
X1491715Y1602380D03*
X1479655D03*
X1483055D03*
X1501875Y1590094D03*
X1498475D03*
X1503775Y1614292D03*
X1507175D03*
X1495115D03*
X1503775Y1602380D03*
X1507175D03*
X1495115D03*
X1525995Y1590094D03*
X1513935D03*
X1522595D03*
X1510535D03*
X1515835Y1614292D03*
X1519235D03*
X1515835Y1602380D03*
X1519235D03*
X1538996Y69297D03*
X1535596D03*
X1538055Y1590094D03*
X1534655D03*
X1527895Y1614292D03*
X1539955D03*
X1531295D03*
X1527895Y1602380D03*
X1539955D03*
X1531295D03*
X1556413Y19495D03*
X1549308Y26431D03*
X1552708D03*
X1557596Y69297D03*
X1546596Y75297D03*
X1549996D03*
X1550115Y1590094D03*
X1558775D03*
X1546715D03*
X1552015Y1614292D03*
X1555415D03*
X1543355D03*
X1552015Y1602380D03*
X1555415D03*
X1543355D03*
X1570586Y19495D03*
X1573986D03*
X1559813D03*
X1563481Y26431D03*
X1566881D03*
X1560996Y69297D03*
X1568596Y75297D03*
X1571996D03*
X1574235Y1590094D03*
X1562175D03*
X1570835D03*
X1564075Y1614292D03*
X1567475D03*
X1564075Y1602380D03*
X1567475D03*
X1584759Y19495D03*
X1588159D03*
X1577654Y26431D03*
X1591828D03*
X1581054D03*
X1582996Y69297D03*
X1579596D03*
X1590596Y75297D03*
X1586295Y1590094D03*
X1582895D03*
X1588195Y1614292D03*
X1576135D03*
X1591595D03*
X1579535D03*
X1588195Y1602380D03*
X1576135D03*
X1591595D03*
X1579535D03*
X1598933Y19495D03*
X1602333D03*
X1595228Y26431D03*
X1604996Y69297D03*
X1601596D03*
X1593996Y75297D03*
X1598355Y1590094D03*
X1607015D03*
X1594955D03*
X1600255Y1614292D03*
X1603655D03*
X1600255Y1602380D03*
X1603655D03*
X1623596Y69297D03*
X1612596Y75297D03*
X1615996D03*
X1622475Y1590094D03*
X1610415D03*
X1619075D03*
X1612315Y1614292D03*
X1615715D03*
X1612315Y1602380D03*
X1615715D03*
X1634799Y19495D03*
X1638199D03*
X1627694Y26431D03*
X1631094D03*
X1626996Y69297D03*
X1635800Y75297D03*
X1639200D03*
X1634535Y1590094D03*
X1631135D03*
X1636435Y1614292D03*
X1624375D03*
X1639835D03*
X1627775D03*
X1636435Y1602380D03*
X1624375D03*
X1639835D03*
X1627775D03*
X1648972Y19495D03*
X1652372D03*
X1641867Y26431D03*
X1645267D03*
X1650200Y69297D03*
X1646800D03*
X1646595Y1590094D03*
X1643195D03*
X1651895Y1614292D03*
X1648495D03*
X1651895Y1602380D03*
X1648495D03*
X1671828Y26431D03*
X1672200Y69297D03*
X1668800D03*
X1657800Y75297D03*
X1661200D03*
X1678933Y19495D03*
X1682333D03*
X1686001Y26431D03*
X1689401D03*
X1675228D03*
X1679934Y75297D03*
X1683334D03*
X1696506Y19495D03*
X1693106D03*
X1694334Y69297D03*
X1690934D03*
X1705334Y75297D03*
X1701934D03*
G54D41*
X338042Y849978D03*
X331284Y978814D03*
X338211Y1118243D03*
Y1131060D03*
X345178Y854584D03*
X348879Y860993D03*
X354429Y883423D03*
X348879Y873810D03*
X347029Y877014D03*
X348878Y880219D03*
X343761Y999684D03*
X349311Y1105426D03*
X351162Y1127856D03*
X353011Y1118243D03*
X354861Y1121447D03*
X347461Y1134264D03*
X354861D03*
X356278Y848176D03*
X371078D03*
X363678D03*
X356278Y860993D03*
X371078D03*
X363678D03*
X356278Y880219D03*
X358129Y883423D03*
X363678Y880219D03*
X365529Y883423D03*
X371078Y880219D03*
X361829Y883423D03*
X369229D03*
X371078Y873810D03*
X356278D03*
X363678D03*
X363679Y893036D03*
X367379D03*
X359978Y886627D03*
X367378D03*
X363678D03*
X371078D03*
X367811Y1002888D03*
Y1105426D03*
X369661Y1102221D03*
X358562D03*
X360412Y1105426D03*
X369662Y1121447D03*
X362261D03*
X369662Y1134264D03*
X362262D03*
X385878Y848176D03*
X378478D03*
Y860993D03*
X385878D03*
X372929Y883423D03*
X378478Y880219D03*
X380329Y883423D03*
X385878Y880219D03*
X387729Y883423D03*
X376629D03*
X384029D03*
X378478Y873810D03*
X385878D03*
X374778Y886627D03*
X382178D03*
X378478D03*
X385878D03*
X375211Y1099017D03*
X380762Y1095813D03*
X382611Y1099017D03*
X384462Y1121447D03*
X377062D03*
X384462Y1134264D03*
X377062D03*
X400678Y848176D03*
X393278D03*
X400678Y860993D03*
X393278D03*
Y880219D03*
X395129Y883423D03*
X400678Y880219D03*
X402529Y883423D03*
X391429D03*
X398829D03*
X393278Y873810D03*
X400678D03*
X402529Y896240D03*
X400678Y899445D03*
X393279Y893036D03*
X396979D03*
X396978Y886627D03*
X389578D03*
X398829Y896240D03*
X400678Y893036D03*
X393278Y886627D03*
X400678D03*
X404378Y899445D03*
X400678Y905853D03*
X402529Y915466D03*
Y909057D03*
X406229Y915466D03*
X400678Y912262D03*
X402529Y902649D03*
X400678Y931488D03*
X402529Y928283D03*
Y921875D03*
X398829Y934691D03*
X402529D03*
Y941100D03*
X400679Y944304D03*
X402529Y947509D03*
Y966735D03*
Y960326D03*
X398829Y953917D03*
X402529D03*
X400680Y950713D03*
X399262Y1006093D03*
X402962D03*
X399262Y999684D03*
X402962D03*
X401111Y1009297D03*
X402962Y1012501D03*
Y1031727D03*
X401111Y1028523D03*
Y1022114D03*
X402960Y1018910D03*
X402962Y1025318D03*
X399262D03*
X401111Y1015705D03*
Y1047749D03*
X399262Y1044544D03*
X402962D03*
X401111Y1041340D03*
X402962Y1038136D03*
X406662Y1057361D03*
X402962D03*
Y1063770D03*
X401113Y1060565D03*
X399262Y1063770D03*
X401111Y1054157D03*
X402962Y1050952D03*
Y1076587D03*
Y1070178D03*
X401112Y1066974D03*
X399262Y1082995D03*
X391862Y1102221D03*
X393711Y1105426D03*
X391862Y1121447D03*
X399262D03*
X391862Y1134264D03*
X399262D03*
X408078Y848176D03*
X415478D03*
Y860993D03*
X408078D03*
Y880219D03*
X409929Y883423D03*
X406229D03*
X415478Y873810D03*
X408078D03*
X404378Y886627D03*
X411778D03*
X404378Y893036D03*
X415478Y886627D03*
X408078D03*
X406229Y896240D03*
X408078Y899445D03*
X415478D03*
X409929Y896240D03*
X415478Y893036D03*
X417329Y896240D03*
X422878Y893036D03*
X411778Y899445D03*
X413629Y896240D03*
X419178Y899445D03*
X422878Y912262D03*
X417329Y909057D03*
X406229D03*
X413629D03*
Y915466D03*
X411778Y905853D03*
X408078D03*
Y912262D03*
X406229Y902649D03*
X415478Y905853D03*
X411778Y912262D03*
X415478D03*
X417329Y915466D03*
X411779Y918670D03*
X406229Y921875D03*
X408078Y918670D03*
X408569Y929108D03*
X406308Y928626D03*
X417329Y921875D03*
X411872Y925264D03*
X415479Y918670D03*
X407589Y942164D03*
X405289D03*
X409889D03*
X415185Y956620D03*
X411685D03*
X409385D03*
X417685D03*
X404785Y971100D03*
X407085D03*
X409385D03*
X411685D03*
X420205D03*
X412365Y985610D03*
X410065D03*
X420145Y985550D03*
X409385Y1014540D03*
X407085D03*
X411685D03*
X412385Y1000080D03*
X410085D03*
X420215Y1000040D03*
X420405Y1014470D03*
X414461Y1028855D03*
X411961D03*
X416961D03*
X419461D03*
X415911Y1047749D03*
X419611D03*
X406662Y1044544D03*
X410362D03*
X408511Y1047749D03*
X414062Y1044544D03*
X404811Y1041340D03*
X412211D03*
X415911D03*
X419611D03*
X406662Y1050952D03*
X414060D03*
X417762Y1057361D03*
X421462Y1050952D03*
X419611Y1054157D03*
X406662Y1063770D03*
X408511Y1060565D03*
X410362Y1063770D03*
X412211Y1054157D03*
X404811D03*
X414062Y1057361D03*
X410362D03*
X417762Y1063770D03*
X414062D03*
X419611Y1060565D03*
Y1079791D03*
X408511Y1073383D03*
X406662Y1070178D03*
X404811Y1073383D03*
X417762Y1076587D03*
X408511Y1066974D03*
X415911Y1079791D03*
X412211Y1073383D03*
X415911D03*
X414062Y1070178D03*
X417762D03*
X412211Y1066974D03*
X419611D03*
X419612Y1099017D03*
X404811Y1092608D03*
X417762Y1095813D03*
X414061D03*
X415912Y1124651D03*
X419612D03*
Y1118243D03*
X417761Y1121447D03*
Y1127856D03*
X406661Y1121447D03*
X414062Y1127856D03*
X406662Y1134264D03*
X415912Y1137469D03*
Y1131060D03*
X414061Y1140973D03*
X419612Y1137469D03*
Y1131060D03*
X417761Y1134264D03*
Y1140973D03*
X412212Y1137469D03*
X422878Y848176D03*
X430278Y860993D03*
X422878D03*
Y873810D03*
X430278D03*
X422878Y886627D03*
X430278D03*
Y899445D03*
X422878D03*
X424729Y896240D03*
X430278Y893036D03*
X432129Y896240D03*
X437678Y893036D03*
X421029Y896240D03*
X426578Y899445D03*
X428429Y896240D03*
X433978Y899445D03*
X435829Y896240D03*
X424729Y915466D03*
X426578Y912262D03*
X430278D03*
X432129Y915466D03*
X421029Y909057D03*
X435829D03*
Y915466D03*
X432128Y909057D03*
X433978Y905853D03*
X424728Y909057D03*
X422878Y905853D03*
X430278D03*
X426578D03*
X421029Y915466D03*
X433979Y912262D03*
X430278Y918670D03*
X432129Y921875D03*
X433979Y918670D03*
X435829Y921875D03*
X424927Y927255D03*
X423176Y929465D03*
X422427Y927255D03*
X425676Y929465D03*
X424729Y921875D03*
X422878Y918670D03*
X421029Y921875D03*
X426578Y918670D03*
X430279Y925079D03*
X432130Y928283D03*
X430279Y931487D03*
X432130Y934692D03*
X435830Y928283D03*
X427875Y941930D03*
Y944230D03*
X430280Y944305D03*
X432130Y941101D03*
X435830D03*
X432129Y947510D03*
X435830D03*
Y934692D03*
X427875Y956373D03*
Y954073D03*
X422685Y956620D03*
X425185D03*
X430280Y957123D03*
X432129Y960327D03*
Y953918D03*
X430280Y950714D03*
X435830Y960327D03*
Y953918D03*
X432129Y966736D03*
X430280Y963531D03*
X435830Y966736D03*
X430268Y976348D03*
X432129Y973144D03*
X430280Y969940D03*
X427875Y971267D03*
X422685Y971100D03*
X427875Y968967D03*
X435830Y973144D03*
X430280Y982757D03*
X432129Y979553D03*
X427875Y983111D03*
X435830Y979553D03*
X422685Y985580D03*
X427875Y985411D03*
Y997521D03*
X430712Y1009298D03*
X427875Y1012152D03*
X430712Y1002889D03*
X427875Y999821D03*
X422685Y1000060D03*
X436263Y1006094D03*
Y999685D03*
X432562Y1006094D03*
Y999685D03*
X427875Y1014452D03*
X423015Y1014470D03*
X436263Y1012502D03*
X432562D03*
X421961Y1028855D03*
X430712Y1022115D03*
Y1015706D03*
X427875Y1026704D03*
X430712Y1028524D03*
X436263Y1018911D03*
X432562D03*
Y1025319D03*
X436263D03*
X427875Y1029004D03*
Y1031304D03*
X436263Y1031728D03*
X432562D03*
X427011Y1047749D03*
X427012Y1041340D03*
X423312D03*
X425162Y1044544D03*
X423285Y1036884D03*
X430711Y1041340D03*
X430712Y1034932D03*
X427875Y1033604D03*
X423285Y1032284D03*
Y1034584D03*
X436262Y1038137D03*
X436261Y1044544D03*
X432562Y1038137D03*
X434412Y1041340D03*
X432561Y1044544D03*
X434412Y1047749D03*
X421462Y1044544D03*
X427011Y1054157D03*
X430711D03*
X428861Y1057361D03*
X432561D03*
X421462D03*
X425162Y1050952D03*
X423311Y1054157D03*
X428862Y1050952D03*
X436262Y1057361D03*
Y1050952D03*
Y1063770D03*
X425162D03*
X423311Y1060565D03*
X427011D03*
X428861Y1063770D03*
X430711Y1060565D03*
X423311Y1073383D03*
X432560Y1070178D03*
X421462Y1076587D03*
X423311Y1079791D03*
X436262Y1070178D03*
Y1076587D03*
X421462Y1070178D03*
X425162D03*
X428862D03*
X430711Y1066974D03*
X436262Y1082995D03*
Y1089404D03*
X436261Y1095813D03*
X421462Y1102221D03*
X423311Y1099017D03*
X428861Y1108630D03*
X427012Y1105426D03*
X425162Y1108630D03*
X430711Y1105426D03*
Y1099017D03*
X428861Y1102221D03*
X436262Y1108630D03*
Y1102221D03*
X432561Y1108630D03*
Y1102221D03*
X434412Y1099017D03*
X430711Y1111834D03*
X427012D03*
X430711Y1124651D03*
X428861Y1121447D03*
X427012Y1124651D03*
X425162Y1121447D03*
X421461D03*
X430711Y1118243D03*
X428861Y1115039D03*
X427012Y1118243D03*
X425162Y1115039D03*
X436262Y1121447D03*
Y1115039D03*
X432561Y1121447D03*
Y1115039D03*
X428861Y1127856D03*
X425162D03*
X421461D03*
X436262D03*
X432561D03*
X430711Y1137769D03*
X427012Y1137569D03*
X430711Y1131060D03*
X428861Y1134264D03*
X427012Y1131060D03*
X425162Y1134264D03*
X421461D03*
X428861Y1140973D03*
X425161D03*
X421461D03*
X436261Y1134264D03*
X432561D03*
X445078Y860993D03*
X452479D03*
X437679Y873810D03*
X452479D03*
X445078D03*
X452478Y886627D03*
X445078D03*
X452478Y899445D03*
X441378D03*
X445078Y893036D03*
X446929Y896240D03*
X452479Y893036D03*
X445078Y899445D03*
X443229Y896240D03*
X448778Y899445D03*
X450630Y896240D03*
X443229Y909057D03*
X439529Y915466D03*
X445079Y905853D03*
X441379D03*
X450630Y909057D03*
X452479Y905853D03*
X448779D03*
X448780Y912262D03*
X441380D03*
X439529Y909057D03*
X445080Y912262D03*
X443229Y915466D03*
X450629D03*
X452478Y912262D03*
X448779Y918670D03*
X454329Y915466D03*
X439529Y921875D03*
X441378Y918670D03*
X450629Y921875D03*
X445078Y918670D03*
X443229Y921875D03*
X452478Y918670D03*
X446930Y934692D03*
X443230Y928283D03*
X448780Y931487D03*
X437679D03*
X450630Y928283D03*
X448780Y925079D03*
X445079Y931487D03*
X439530Y934692D03*
X445079Y925079D03*
X439530Y928283D03*
X437679Y925079D03*
X437680Y944305D03*
X441380D03*
X443230Y941101D03*
X445079Y944305D03*
X439530Y941101D03*
X450630D03*
X448780Y944305D03*
X443229Y947510D03*
X439529D03*
X450630D03*
X443230Y934692D03*
X445079Y957123D03*
X437680D03*
X441380D03*
X439529Y960327D03*
X443229D03*
Y953918D03*
X439529D03*
X437680Y950714D03*
X441380D03*
X445079D03*
X448780Y957123D03*
X450630Y953918D03*
Y960327D03*
X448780Y950714D03*
X445079Y963531D03*
X437680D03*
X441380D03*
X439529Y966736D03*
X443229D03*
X448780Y963531D03*
X450630Y966736D03*
X445079Y976348D03*
Y969940D03*
X439529Y973144D03*
X443229D03*
X437680Y976348D03*
X441380D03*
X437680Y969940D03*
X441380D03*
X450630Y973144D03*
X448780Y976348D03*
Y969940D03*
X445079Y982757D03*
X437680D03*
X441380D03*
X439529Y979553D03*
X443229D03*
X448780Y982757D03*
X450630Y979553D03*
X439962Y1006094D03*
X443662D03*
X445511Y1009298D03*
X438113D03*
X441813D03*
X445512Y1002889D03*
X438113D03*
X441813D03*
X439962Y999685D03*
X443662D03*
X451062Y1006094D03*
X449213Y1009298D03*
Y1002889D03*
X451062Y999685D03*
X439962Y1012502D03*
X443662D03*
X451062D03*
X445511Y1022115D03*
X438113D03*
X441813D03*
X445512Y1015706D03*
X438113D03*
X439962Y1018911D03*
X441813Y1015706D03*
X443662Y1018911D03*
Y1025319D03*
X439962D03*
X445511Y1028524D03*
X441813D03*
X438113D03*
X449213Y1022115D03*
X451062Y1018911D03*
X449213Y1015706D03*
X451062Y1025319D03*
X449213Y1028524D03*
X439962Y1031728D03*
X443662D03*
X451062D03*
X452911Y1047749D03*
X439962Y1038137D03*
X443662D03*
X438112Y1041340D03*
X439961Y1044544D03*
X441812Y1041340D03*
X443661Y1044544D03*
X447361D03*
X445511Y1041340D03*
X445512Y1034932D03*
X438113D03*
X441813D03*
X451062Y1038137D03*
X449211Y1041340D03*
X449213Y1034932D03*
X445510Y1047749D03*
X441812D03*
X438112D03*
X449211Y1054157D03*
X449213Y1060565D03*
X438112D03*
Y1054157D03*
X439961Y1057361D03*
X441812Y1054157D03*
Y1060565D03*
X443661Y1057361D03*
X445511Y1060565D03*
Y1054157D03*
X439961Y1050952D03*
X443661D03*
X439961Y1063770D03*
X443661D03*
X451061D03*
X452911Y1054157D03*
X451062Y1050952D03*
X454762D03*
Y1057361D03*
X451062D03*
X451061Y1076587D03*
X452911Y1073383D03*
X439961Y1076587D03*
Y1070178D03*
X441812Y1073383D03*
X438112D03*
X443661Y1070178D03*
Y1076587D03*
X445511Y1073383D03*
X441812Y1066974D03*
X438112D03*
X445511D03*
X441812Y1079791D03*
X438112D03*
X445511D03*
X452911Y1066974D03*
X449211D03*
X451062Y1070178D03*
X452911Y1086200D03*
X443661Y1082995D03*
X439961D03*
X441812Y1086200D03*
X445511D03*
X439961Y1089404D03*
X441812Y1092608D03*
X438112D03*
X443661Y1089404D03*
X445511Y1092608D03*
X447361Y1089404D03*
X438112Y1086200D03*
X449211Y1092608D03*
X439961Y1095813D03*
X443661D03*
X447361D03*
X451060Y1082995D03*
X441812Y1105426D03*
X438112D03*
X439961Y1108630D03*
X443661D03*
X445511Y1105426D03*
X439961Y1102221D03*
X441812Y1099017D03*
X438112D03*
X443661Y1102221D03*
X445511Y1099017D03*
X452912Y1105426D03*
X451061Y1108630D03*
X449212Y1105426D03*
X451061Y1102221D03*
X449212Y1099017D03*
X441812Y1111834D03*
X438112D03*
X445511D03*
X452912D03*
X449212D03*
X438112Y1124651D03*
X439961Y1121447D03*
X441812Y1124651D03*
X445511D03*
X443661Y1121447D03*
X438112Y1118243D03*
X441812D03*
X439961Y1115039D03*
X445511Y1118243D03*
X443661Y1115039D03*
X452912Y1124651D03*
Y1118243D03*
X451061Y1121447D03*
X449212Y1124651D03*
Y1118243D03*
X451061Y1115039D03*
X439961Y1127856D03*
X443661D03*
X451061D03*
X441812Y1137769D03*
X438112D03*
X445511D03*
X443661Y1134264D03*
X441812Y1131060D03*
X439961Y1134264D03*
X438112Y1131060D03*
X445511D03*
X452912Y1137769D03*
Y1131060D03*
X449212Y1137769D03*
Y1131060D03*
X451061Y1134264D03*
X459878Y848176D03*
X467278D03*
X459878Y860993D03*
X467278D03*
Y873810D03*
X459878D03*
Y886627D03*
X467278D03*
X459878Y899445D03*
X467278D03*
X454329Y896240D03*
X459878Y893036D03*
X461729Y896240D03*
X467278Y893036D03*
X456178Y899445D03*
X458029Y896240D03*
X463578Y899445D03*
X465429Y896240D03*
X470978Y899445D03*
X463578Y905853D03*
X470980Y912262D03*
X469129Y902649D03*
X454329Y909057D03*
X470978Y918670D03*
X467278Y912262D03*
X469129Y915466D03*
X458029Y909057D03*
X459878Y905853D03*
X461729Y915466D03*
X467278Y905853D03*
X461729Y909057D03*
X458029Y915466D03*
X459878Y918670D03*
X463578Y912262D03*
X459878D03*
X469129Y909057D03*
X467278Y918670D03*
X454329Y921875D03*
X468236Y928349D03*
X465936D03*
X463636D03*
X461336D03*
X459036D03*
X469129Y921875D03*
X463578Y918670D03*
X465429Y921875D03*
X458029D03*
X469251Y942246D03*
X453585Y942238D03*
Y939938D03*
Y944538D03*
X453403Y956999D03*
X461424Y956620D03*
X458404D03*
X453403Y959299D03*
X468904Y956620D03*
Y971100D03*
X458404D03*
X461424Y971140D03*
X453403Y973099D03*
Y970799D03*
Y986899D03*
X461424Y985580D03*
X458404D03*
X453403Y984599D03*
X468904Y985580D03*
X453403Y998399D03*
Y1012199D03*
X458404Y1000080D03*
X461424D03*
X453403Y1000699D03*
X468904Y1000080D03*
X458404Y1014540D03*
X461295Y1014510D03*
X453403Y1014499D03*
X465680Y1028855D03*
X463180D03*
X460680D03*
X458180D03*
X457942Y1031909D03*
X467711Y1047750D03*
X460311D03*
X471411Y1041340D03*
X467711D03*
X454762Y1044544D03*
Y1038136D03*
X460971Y1037069D03*
X463271D03*
X458671D03*
X457942Y1034409D03*
X456611Y1041340D03*
X464011D03*
X462162Y1044544D03*
X458462D03*
X464011Y1054157D03*
X465860Y1050952D03*
X456611Y1060565D03*
X462161Y1057361D03*
Y1063770D03*
X460312Y1054157D03*
X458462Y1057361D03*
X467712Y1054157D03*
Y1060565D03*
X454761Y1063770D03*
X464012Y1060565D03*
X458460Y1050952D03*
X460311Y1060565D03*
Y1073383D03*
X458460Y1070178D03*
X460311Y1066974D03*
X464011D03*
X465860Y1070178D03*
X469560D03*
X464012Y1079791D03*
X460312D03*
X462162Y1076587D03*
X456611Y1066974D03*
X465862Y1076587D03*
X464011Y1073383D03*
X458462Y1076587D03*
X465862Y1082995D03*
X462162D03*
X462161Y1095812D03*
X458461D03*
X465861Y1089403D03*
X456612Y1092607D03*
X454761Y1089403D03*
X460311Y1086200D03*
X454760Y1082995D03*
X465861Y1095812D03*
X464012Y1092607D03*
X454761Y1095812D03*
X458461Y1089403D03*
X462161D03*
X467711Y1099017D03*
X462162Y1102221D03*
X458461Y1108630D03*
X456612Y1105426D03*
X454761Y1108630D03*
Y1102221D03*
X460312Y1111834D03*
X456611D03*
X460312Y1099016D03*
X464012Y1124651D03*
X462161Y1121447D03*
X460312Y1124651D03*
X456611D03*
X454761Y1121447D03*
X464011Y1118243D03*
X462161Y1115039D03*
X460312Y1118243D03*
X456611D03*
X454761Y1115039D03*
X462161Y1127856D03*
X454761D03*
X465861D03*
X464012Y1137469D03*
X460312D03*
X456612D03*
X464012Y1131060D03*
X462161Y1134264D03*
X460312Y1131060D03*
X456611D03*
X454761Y1134264D03*
X462161Y1140973D03*
X458461D03*
X454761D03*
X467712Y1137469D03*
X465861Y1134264D03*
X467712Y1131060D03*
X465861Y1140973D03*
X474678Y848176D03*
X482078D03*
X474678Y860993D03*
X482078D03*
X474678Y880219D03*
X476529Y883423D03*
X482078Y880219D03*
X483929Y883423D03*
X472829D03*
X480229D03*
X474678Y873810D03*
X482078D03*
X474678Y893036D03*
X472829Y896240D03*
X478378Y886627D03*
Y899445D03*
X474678Y886627D03*
X482078D03*
X476529Y896240D03*
Y915466D03*
X478380Y912262D03*
X478379Y918670D03*
X480229Y902649D03*
Y915466D03*
X472828D03*
X472829Y902649D03*
X480228Y909057D03*
X482078Y905853D03*
X476529Y902649D03*
X470978Y905853D03*
X478378D03*
X472829Y909057D03*
X476529D03*
X480229Y928283D03*
X478378Y931488D03*
Y925079D03*
X482078D03*
X472829Y921875D03*
X470536Y928349D03*
X478378Y937896D03*
X480229Y941100D03*
Y947509D03*
X471550Y942152D03*
X473851Y942246D03*
X478378Y963530D03*
X480228Y960326D03*
X478378Y950713D03*
X480229Y953917D03*
X478378Y957122D03*
X471404Y956620D03*
X480229Y966735D03*
X482078Y963529D03*
Y982756D03*
X478379Y969939D03*
X476285Y973826D03*
Y971526D03*
X471404Y971100D03*
X473904D03*
X480229Y979552D03*
X478378Y982756D03*
X480229Y973143D03*
X478378Y976347D03*
X471404Y985580D03*
X480662Y999684D03*
X478811Y1002888D03*
Y1009297D03*
X480662Y1012501D03*
X471404Y1000080D03*
X480662Y1031727D03*
X482511Y1015705D03*
X480661Y1018910D03*
X478811Y1022114D03*
Y1028523D03*
Y1015705D03*
X476325Y1031795D03*
Y1027195D03*
Y1029495D03*
X470724Y1028827D03*
X480662Y1025318D03*
X475111Y1047749D03*
X469562Y1044544D03*
X478811Y1034931D03*
X480662Y1038136D03*
X478811Y1041340D03*
X480662Y1044544D03*
X473262D03*
X476962D03*
X478811Y1047749D03*
X473261Y1057361D03*
X471412Y1060565D03*
X475112Y1054157D03*
X469562Y1063770D03*
X469561Y1057361D03*
X473262Y1063770D03*
X469561Y1050952D03*
X473262D03*
X482511Y1054157D03*
X480662Y1063770D03*
X480661Y1057361D03*
X478812Y1060565D03*
X476962Y1063770D03*
Y1057361D03*
X478812Y1054157D03*
X476961Y1050952D03*
X478811Y1066974D03*
X471411D03*
X476962Y1076587D03*
X480662D03*
Y1070178D03*
X476962D03*
X473262Y1076587D03*
X469562D03*
X471411Y1073383D03*
Y1079791D03*
X475111Y1073383D03*
X482511D03*
X473262Y1095813D03*
X469562Y1082995D03*
X480662Y1089404D03*
X478812Y1092607D03*
X475112D03*
X473261Y1089403D03*
X471412Y1086199D03*
X476961Y1082994D03*
X482512Y1092607D03*
X476961Y1095812D03*
X471412Y1092607D03*
X475112Y1086199D03*
X478812D03*
X480662Y1102221D03*
X473262Y1121447D03*
X480662D03*
Y1134264D03*
X469561D03*
X489478Y848176D03*
X496878D03*
X489478Y860993D03*
X496878D03*
X489478Y880219D03*
X491329Y883423D03*
X496878Y880219D03*
X498729Y883423D03*
X487629D03*
X495029D03*
X496878Y873810D03*
X489478D03*
X485778Y886627D03*
X493178D03*
X500578D03*
X489478D03*
X496878D03*
X488062Y1095813D03*
X501012Y1105426D03*
Y1111833D03*
X488062Y1115039D03*
Y1121447D03*
X495462Y1134264D03*
X488062D03*
X511678Y848176D03*
X504278D03*
X511678Y860993D03*
X504278D03*
X511678Y880219D03*
X513529Y883423D03*
X504278Y880219D03*
X506129Y883423D03*
X509829D03*
X517229D03*
X502429D03*
X511678Y873810D03*
X504278D03*
X515378Y886627D03*
X507978D03*
X511678D03*
X504278D03*
X502862Y1006093D03*
X510262Y1102221D03*
X502861Y1108629D03*
X512112Y1105426D03*
X508412Y1111833D03*
X506561Y1102220D03*
X504712Y1111833D03*
Y1105426D03*
X510261Y1108630D03*
X512112Y1111833D03*
X508412Y1105426D03*
X502862Y1115039D03*
X510262Y1121447D03*
X502862D03*
X517662D03*
X506561Y1115038D03*
X510262Y1134264D03*
X502862D03*
X517662D03*
X519078Y848176D03*
X526479Y860993D03*
X519078D03*
Y880219D03*
X520929Y883423D03*
X526479Y880219D03*
X528329Y883423D03*
X524629D03*
X526479Y873810D03*
X519078D03*
X530178Y893036D03*
X522778Y886627D03*
X530179D03*
X526479D03*
X519078D03*
X533879D03*
X528762Y1102221D03*
X525062D03*
X523212Y1099017D03*
X530611Y1105426D03*
X526911Y1118243D03*
X525062Y1121447D03*
X534311Y1118243D03*
X532461Y1121446D03*
X534311Y1124650D03*
X532461Y1127855D03*
X525062Y1134264D03*
X528761Y1140973D03*
X532461D03*
X541711Y1118243D03*
X538010Y1118242D03*
X543561Y1121446D03*
X539861Y1127855D03*
X536161D03*
Y1121446D03*
X539861D03*
X541711Y1124650D03*
X543561Y1127855D03*
X538012Y1131059D03*
X650599Y766798D03*
X918264Y506011D03*
X1030780Y1266532D03*
X1074480Y1263742D03*
X1181941Y766798D03*
X1297012Y157449D03*
X1293802Y159299D03*
Y166699D03*
X1293511Y179048D03*
X1296999Y183349D03*
X1297007Y172249D03*
X1296999Y175949D03*
X1293802Y170399D03*
X1294163Y175865D03*
X1296999Y179649D03*
Y194449D03*
Y198149D03*
Y190749D03*
Y187049D03*
Y201849D03*
X1293805Y211099D03*
X1293798Y205833D03*
X1296999Y216649D03*
X1293807Y218499D03*
Y214799D03*
X1296999Y212949D03*
Y205549D03*
X1294357Y224688D03*
X1296999Y224049D03*
X1293807Y222199D03*
X1300393Y235762D03*
X1303417Y164849D03*
X1300213Y162999D03*
X1300212Y166699D03*
X1306622D03*
X1309832Y157449D03*
X1306626Y162999D03*
Y159299D03*
X1313037Y162999D03*
X1309832Y164849D03*
X1313037Y159299D03*
X1303417Y157449D03*
X1300217Y159299D03*
X1313033Y166699D03*
X1300212Y170399D03*
X1306626D03*
X1303407Y183349D03*
X1309817Y175949D03*
X1300212Y174099D03*
X1313037Y170399D03*
X1306617Y185199D03*
X1309832Y172249D03*
X1313027Y181499D03*
Y185199D03*
X1303407Y175949D03*
Y179649D03*
X1306617Y177799D03*
X1309817Y179649D03*
X1300204Y181499D03*
X1309817Y194449D03*
X1306617Y188899D03*
X1303407Y194449D03*
X1306617Y196299D03*
X1300207D03*
X1303407Y190749D03*
Y187049D03*
X1300204Y188899D03*
X1313027Y192599D03*
X1309817Y190749D03*
X1313025Y188899D03*
X1309817Y198149D03*
X1303407D03*
X1300207Y203699D03*
Y207399D03*
X1309832Y209249D03*
X1313027Y203699D03*
X1300220Y218499D03*
X1309833Y220349D03*
X1303416Y205549D03*
X1306614Y203699D03*
X1306627Y214799D03*
X1316242Y209249D03*
X1300207Y211099D03*
X1303422Y220349D03*
X1300220Y222199D03*
X1313033D03*
X1303425Y224049D03*
X1300493Y238062D03*
X1314184Y849978D03*
X1307426Y978814D03*
X1314353Y1118243D03*
Y1131060D03*
X1319452Y162999D03*
X1316242Y168549D03*
X1319442Y159299D03*
X1316241Y157449D03*
X1316242Y164849D03*
X1322652D03*
X1329062D03*
X1326918Y161161D03*
X1329062Y157449D03*
X1322652D03*
X1325853Y174099D03*
X1331102Y179724D03*
Y182874D03*
Y186024D03*
X1325085Y176402D03*
X1324802Y179724D03*
Y186024D03*
Y182874D03*
X1315352Y186024D03*
Y179724D03*
X1319442Y174099D03*
X1332268D03*
X1324802Y195474D03*
X1327952D03*
X1318502D03*
X1321652D03*
X1327952Y201774D03*
X1321652D03*
X1331102Y189174D03*
X1315405Y189227D03*
X1329062Y212949D03*
X1325852Y211099D03*
X1319442D03*
X1324802Y204924D03*
X1327952D03*
X1318502D03*
X1315352D03*
X1322652Y209249D03*
X1325857Y218499D03*
X1322652Y216649D03*
X1329062Y220349D03*
X1325856Y222199D03*
X1322652Y224049D03*
Y220349D03*
X1321320Y854584D03*
X1325021Y860993D03*
X1330571Y883423D03*
X1325020Y873810D03*
X1323171Y877014D03*
X1325020Y880219D03*
X1319903Y999684D03*
X1325453Y1105426D03*
X1327304Y1127856D03*
X1329153Y1118243D03*
X1331003Y1121447D03*
Y1134264D03*
X1323603D03*
X1339727Y161149D03*
X1341992Y156897D03*
X1332268Y162999D03*
X1342903Y170399D03*
X1339727Y168549D03*
X1335472Y164849D03*
X1346140Y161149D03*
X1342937Y162999D03*
X1335472Y157449D03*
X1346140D03*
X1339727D03*
X1332268Y170399D03*
X1334252Y176574D03*
X1339727Y183349D03*
X1346137D03*
X1337901Y196035D03*
X1339727Y187049D03*
X1337345Y201831D03*
X1339727Y201849D03*
X1337402Y198624D03*
X1342937Y192599D03*
X1346137Y187049D03*
X1346147Y201849D03*
Y198149D03*
X1336527Y214799D03*
X1339727Y216649D03*
X1346147Y212949D03*
Y216649D03*
X1336527Y218499D03*
X1342937D03*
Y214799D03*
X1332262Y211099D03*
X1339686Y205478D03*
X1332262Y207399D03*
X1339727Y209249D03*
Y220349D03*
X1336527Y222199D03*
X1346147Y220349D03*
X1347220Y848176D03*
X1339820D03*
X1332420D03*
X1339820Y860993D03*
X1347220D03*
X1332420D03*
Y880219D03*
X1334271Y883423D03*
X1339820Y880219D03*
X1341671Y883423D03*
X1347220Y880219D03*
X1337971Y883423D03*
X1345371D03*
X1339820Y873810D03*
X1332420D03*
X1347220D03*
X1339821Y893036D03*
X1343521D03*
X1336120Y886627D03*
X1343520D03*
X1347220D03*
X1339820D03*
X1343953Y1002888D03*
X1334704Y1102221D03*
X1345803D03*
X1343953Y1105426D03*
X1336554D03*
X1345804Y1121447D03*
X1338403D03*
X1338404Y1134264D03*
X1345804D03*
X1352550Y157449D03*
X1355961Y155458D03*
X1349344Y162999D03*
X1348386Y156646D03*
X1352551Y161148D03*
X1349351Y192598D03*
X1352551Y187048D03*
X1355761Y188898D03*
X1349361Y199998D03*
X1352561Y201848D03*
X1355766Y214798D03*
X1349351Y218498D03*
X1352561Y216648D03*
X1355766Y218498D03*
X1352561Y220348D03*
X1355766Y222198D03*
X1360186Y226264D03*
X1362020Y848176D03*
X1354620D03*
X1362020Y860993D03*
X1354620D03*
X1349071Y883423D03*
X1354620Y880219D03*
X1356471Y883423D03*
X1362020Y880219D03*
X1363871Y883423D03*
X1352771D03*
X1360171D03*
X1354620Y873810D03*
X1362020D03*
X1350920Y886627D03*
X1358320D03*
X1354620D03*
X1362020D03*
X1351354Y1099017D03*
X1356904Y1095813D03*
X1358753Y1099017D03*
X1360604Y1121447D03*
X1353204D03*
Y1134264D03*
X1360604D03*
X1376820Y848176D03*
X1369420D03*
X1376820Y860993D03*
X1369420D03*
Y880219D03*
X1371271Y883423D03*
X1376820Y880219D03*
X1378671Y883423D03*
X1367571D03*
X1374971D03*
X1369420Y873810D03*
X1376820D03*
X1378671Y896240D03*
X1376820Y899445D03*
X1369421Y893036D03*
X1373121D03*
X1373120Y886627D03*
X1365720D03*
X1374971Y896240D03*
X1376820Y893036D03*
X1369420Y886627D03*
X1376820D03*
X1380520Y899445D03*
X1376820Y905853D03*
X1378671Y915466D03*
Y909057D03*
X1376820Y912262D03*
X1378671Y902649D03*
X1376820Y931488D03*
X1378671Y928283D03*
Y921875D03*
X1374971Y934691D03*
X1378671D03*
Y947509D03*
Y966735D03*
Y960326D03*
Y953917D03*
X1374971D03*
X1376822Y950713D03*
X1375404Y1006093D03*
X1379104D03*
X1375404Y999684D03*
X1379104D03*
X1377253Y1009297D03*
X1379104Y1012501D03*
Y1031727D03*
X1377253Y1028523D03*
X1375404Y1025318D03*
X1377253Y1022114D03*
X1379102Y1018910D03*
X1379104Y1025318D03*
X1377253Y1015705D03*
X1375404Y1044544D03*
X1377253Y1041340D03*
X1379104Y1044544D03*
Y1038136D03*
X1377253Y1047749D03*
X1379104Y1057361D03*
Y1063770D03*
X1377255Y1060565D03*
X1375404Y1063770D03*
X1377253Y1054157D03*
X1379104Y1050952D03*
X1380953Y1054157D03*
X1379104Y1076587D03*
Y1070178D03*
X1377254Y1066974D03*
X1375404Y1082995D03*
X1368004Y1102221D03*
X1369853Y1105426D03*
X1368004Y1121447D03*
X1375404D03*
X1368004Y1134264D03*
X1375404D03*
X1374847Y1153069D03*
X1391620Y848176D03*
X1384220D03*
Y860993D03*
X1391620D03*
X1384220Y880219D03*
X1386071Y883423D03*
X1382371D03*
X1391620Y873810D03*
X1384220D03*
X1380520Y886627D03*
X1387920D03*
X1380520Y893036D03*
X1382371Y896240D03*
X1384220Y886627D03*
X1391620D03*
Y899445D03*
X1384221Y899446D03*
X1393471Y909057D03*
X1382371D03*
X1389771D03*
Y915466D03*
X1399020Y905853D03*
X1382371Y915466D03*
X1384220Y918670D03*
X1387920Y905853D03*
X1384220D03*
Y912262D03*
X1382371Y902649D03*
X1391620Y905853D03*
X1387920Y912262D03*
X1391620D03*
X1393471Y915466D03*
X1391621Y918670D03*
X1382371Y921875D03*
X1382809Y927986D03*
X1385070Y928468D03*
X1393471Y921875D03*
X1391550Y925219D03*
X1387921Y918670D03*
X1386030Y942163D03*
X1383730D03*
X1381430D03*
X1392534Y942097D03*
X1394834D03*
X1393826Y956619D03*
X1387826D03*
X1391326D03*
X1385526D03*
X1380926Y971099D03*
X1383226D03*
X1387826D03*
X1385526D03*
X1396346D03*
X1396286Y985549D03*
X1388506Y985609D03*
X1386206D03*
X1385526Y1014539D03*
X1387826D03*
X1383226D03*
X1386226Y1000079D03*
X1396356Y1000039D03*
X1388526Y1000079D03*
X1396546Y1014469D03*
X1388102Y1028854D03*
X1390602D03*
X1393102D03*
X1395602D03*
X1380953Y1041340D03*
X1388353D03*
X1392053D03*
X1395753D03*
Y1047749D03*
X1392053D03*
X1382804Y1044544D03*
X1386504D03*
X1384653Y1047749D03*
X1390204Y1044544D03*
X1382804Y1050952D03*
Y1057361D03*
X1386504D03*
X1390204Y1050952D03*
X1393904Y1057361D03*
X1395753Y1054157D03*
X1382804Y1063770D03*
X1384653Y1060565D03*
X1386504Y1063770D03*
X1388353Y1054157D03*
X1390204Y1057361D03*
X1393904Y1063770D03*
X1390204D03*
X1395753Y1060565D03*
Y1079791D03*
X1384653Y1073383D03*
X1382804Y1070178D03*
X1380953Y1073383D03*
X1393904Y1076587D03*
X1392053Y1079791D03*
X1384653Y1066974D03*
X1388353Y1073383D03*
X1392053D03*
X1390204Y1070178D03*
X1393904D03*
X1388353Y1066974D03*
X1395753D03*
X1395754Y1099017D03*
X1380953Y1092608D03*
X1393904Y1095813D03*
X1390203D03*
X1392054Y1124651D03*
X1393903Y1121447D03*
Y1127856D03*
X1395754Y1118243D03*
Y1124651D03*
X1382803Y1121447D03*
X1390204Y1127856D03*
X1382804Y1134264D03*
X1390203Y1140973D03*
X1392054Y1131060D03*
Y1137469D03*
X1393903Y1134264D03*
Y1140973D03*
X1395754Y1131060D03*
Y1137469D03*
X1388354D03*
X1399020Y848176D03*
X1406420Y860993D03*
X1399020D03*
Y873810D03*
X1406420D03*
Y886627D03*
X1399020D03*
X1406420Y899445D03*
X1399020D03*
Y912262D03*
X1400871Y915466D03*
X1402720Y912262D03*
X1406420D03*
X1408271Y915466D03*
X1397171Y909057D03*
X1411971D03*
Y915466D03*
X1408270Y909057D03*
X1410120Y905853D03*
X1400870Y909057D03*
X1406420Y905853D03*
X1402720D03*
X1397171Y915466D03*
X1410121Y912262D03*
X1406420Y918670D03*
X1408271Y921875D03*
X1410121Y918670D03*
X1411971Y921875D03*
X1401528Y927155D03*
X1399028D03*
X1401817Y929464D03*
X1399317D03*
X1400871Y921875D03*
X1399020Y918670D03*
X1397171Y921875D03*
X1402720Y918670D03*
X1411971Y934691D03*
X1406420Y925079D03*
X1408271Y928283D03*
X1406420Y931488D03*
X1411971Y928283D03*
X1406421Y944304D03*
X1408271Y941100D03*
X1411971D03*
X1404016Y944229D03*
Y941929D03*
X1408270Y947509D03*
X1411971D03*
X1408271Y934691D03*
X1406421Y950713D03*
Y957122D03*
X1408270Y953917D03*
Y960326D03*
X1411971Y953917D03*
Y960326D03*
X1404016Y954072D03*
Y956372D03*
X1401326Y956619D03*
X1398826D03*
X1406421Y963530D03*
X1408270Y966735D03*
X1411971D03*
X1406421Y969939D03*
X1406409Y976347D03*
X1408270Y973143D03*
X1411971D03*
X1404016Y971266D03*
Y968966D03*
X1398826Y971099D03*
X1406421Y982756D03*
X1408270Y979552D03*
X1411971D03*
X1404016Y983110D03*
Y985410D03*
X1398826Y985579D03*
X1404016Y997520D03*
X1412404Y999684D03*
Y1006093D03*
Y1012501D03*
X1406853Y1002888D03*
Y1009297D03*
X1408703Y999684D03*
Y1006093D03*
Y1012501D03*
X1404016Y1012151D03*
Y999820D03*
X1398826Y1000059D03*
X1404016Y1014451D03*
X1399156Y1014469D03*
X1398102Y1028854D03*
X1406853Y1028523D03*
X1412404Y1018910D03*
X1406853Y1015705D03*
Y1022114D03*
X1408703Y1018910D03*
X1412404Y1025318D03*
X1408703D03*
X1404016Y1026703D03*
X1412404Y1031727D03*
X1408703D03*
X1404016Y1029003D03*
Y1031303D03*
X1403153Y1047749D03*
X1403154Y1041340D03*
X1399454D03*
X1401304Y1044544D03*
X1412403Y1038136D03*
Y1044544D03*
X1406853Y1034931D03*
Y1041340D03*
X1408703Y1038136D03*
Y1044544D03*
X1410554Y1041340D03*
X1404016Y1033603D03*
X1399426Y1036883D03*
Y1034583D03*
Y1032283D03*
X1410554Y1047749D03*
X1397604Y1044544D03*
X1403153Y1054157D03*
X1406853D03*
X1405003Y1057361D03*
X1408703D03*
Y1063770D03*
X1412404Y1050952D03*
Y1057361D03*
Y1063770D03*
X1397604Y1057361D03*
X1401304Y1050952D03*
X1399453Y1054157D03*
X1405004Y1050952D03*
X1397604D03*
X1401304Y1063770D03*
X1399453Y1060565D03*
X1403153D03*
X1405003Y1063770D03*
X1406853Y1060565D03*
X1397604Y1076587D03*
X1408702Y1070178D03*
X1399453Y1073383D03*
Y1079791D03*
X1412404Y1070178D03*
Y1076587D03*
X1397604Y1070178D03*
X1401304D03*
X1405004D03*
X1406853Y1066974D03*
X1412404Y1082995D03*
Y1089404D03*
X1412403Y1095813D03*
X1397604Y1102221D03*
X1399453Y1099017D03*
X1412404Y1102221D03*
Y1108630D03*
X1401304D03*
X1403154Y1105426D03*
Y1111834D03*
X1405003Y1102221D03*
Y1108630D03*
X1406853Y1099017D03*
Y1105426D03*
Y1111834D03*
X1408703Y1102221D03*
Y1108630D03*
X1410554Y1099017D03*
X1412404Y1115039D03*
Y1121447D03*
Y1127856D03*
X1397603Y1121447D03*
Y1127856D03*
X1401304Y1115039D03*
Y1121447D03*
Y1127856D03*
X1403154Y1118243D03*
Y1124651D03*
X1405003Y1115039D03*
Y1121447D03*
Y1127856D03*
X1406853Y1118243D03*
Y1124651D03*
X1408703Y1115039D03*
Y1121447D03*
Y1127856D03*
X1412403Y1134264D03*
X1397603D03*
Y1140973D03*
X1401304Y1134264D03*
X1401303Y1140973D03*
X1403154Y1131060D03*
Y1137569D03*
X1405003Y1134264D03*
Y1140973D03*
X1406853Y1131060D03*
Y1137769D03*
X1408703Y1134264D03*
X1421220Y860993D03*
X1428621D03*
X1413821Y873810D03*
X1428621D03*
X1421220D03*
X1428620Y899445D03*
Y886627D03*
X1421220D03*
X1419371Y909057D03*
X1415671Y915466D03*
X1421221Y905853D03*
X1417521D03*
X1430471Y909057D03*
X1426772D03*
X1428621Y905853D03*
X1424921D03*
X1424922Y912262D03*
X1417522D03*
X1415671Y909057D03*
X1421222Y912262D03*
X1419371Y915466D03*
X1426771D03*
X1428620Y912262D03*
X1424921Y918670D03*
X1430471Y915466D03*
X1415671Y921875D03*
X1417520Y918670D03*
X1426771Y921875D03*
X1421220Y918670D03*
X1419371Y921875D03*
X1428620Y918670D03*
X1424921Y931488D03*
X1419371Y928283D03*
X1413820Y931488D03*
X1424921Y925079D03*
X1419371Y934691D03*
X1421220Y931488D03*
Y925079D03*
X1415671Y928283D03*
X1413820Y925079D03*
X1426771Y928283D03*
X1413821Y944304D03*
X1415671Y941100D03*
X1417521Y944304D03*
X1419371Y941100D03*
X1421220Y944304D03*
X1424921D03*
X1426771Y941100D03*
X1415670Y947509D03*
X1419370D03*
X1426771D03*
X1423071Y934691D03*
X1415671D03*
X1413821Y950713D03*
Y957122D03*
X1415670Y953917D03*
Y960326D03*
X1417521Y950713D03*
Y957122D03*
X1419370Y953917D03*
Y960326D03*
X1421220Y950713D03*
Y957122D03*
X1424921Y950713D03*
Y957122D03*
X1426771Y953917D03*
Y960326D03*
X1413821Y963530D03*
X1415670Y966735D03*
X1417521Y963530D03*
X1419370Y966735D03*
X1421220Y963530D03*
X1424921D03*
X1426771Y966735D03*
X1413821Y969939D03*
Y976347D03*
X1415670Y973143D03*
X1417521Y969939D03*
Y976347D03*
X1419370Y973143D03*
X1421220Y969939D03*
Y976347D03*
X1424921Y969939D03*
Y976347D03*
X1426771Y973143D03*
X1413821Y982756D03*
X1415670Y979552D03*
X1417521Y982756D03*
X1419370Y979552D03*
X1421220Y982756D03*
X1424921D03*
X1426771Y979552D03*
X1414254Y1002888D03*
Y1009297D03*
X1416103Y999684D03*
Y1006093D03*
Y1012501D03*
X1417954Y1002888D03*
Y1009297D03*
X1419803Y999684D03*
Y1006093D03*
Y1012501D03*
X1421653Y1002888D03*
Y1009297D03*
X1425354Y1002888D03*
Y1009297D03*
X1427203Y999684D03*
Y1006093D03*
Y1012501D03*
X1421653Y1028523D03*
X1414254D03*
X1417954D03*
X1425354D03*
X1414254Y1015705D03*
Y1022114D03*
X1416103Y1018910D03*
X1417954Y1015705D03*
Y1022114D03*
X1419803Y1018910D03*
X1421653Y1015705D03*
Y1022114D03*
X1425354Y1015705D03*
Y1022114D03*
X1427203Y1018910D03*
X1416103Y1025318D03*
X1419803D03*
X1427203D03*
X1416103Y1031727D03*
X1419803D03*
X1427203D03*
X1429053Y1047749D03*
X1414254Y1034931D03*
Y1041340D03*
X1416103Y1038136D03*
Y1044544D03*
X1417954Y1034931D03*
Y1041340D03*
X1419803Y1038136D03*
Y1044544D03*
X1421653Y1034931D03*
Y1041340D03*
X1423503Y1044544D03*
X1425354Y1034931D03*
X1425353Y1041340D03*
X1427203Y1038136D03*
X1421653Y1047749D03*
X1414254D03*
X1417954D03*
X1425353Y1054157D03*
X1425355Y1060565D03*
X1414254Y1054157D03*
X1416103Y1050952D03*
X1417954Y1054157D03*
X1419803Y1050952D03*
X1421653Y1054157D03*
X1414254Y1060565D03*
X1416103Y1057361D03*
X1417954Y1060565D03*
X1419803Y1057361D03*
X1421653Y1060565D03*
X1416103Y1063770D03*
X1419803D03*
X1427203D03*
X1429053Y1054157D03*
X1427203Y1050952D03*
X1430903D03*
X1430904Y1057361D03*
X1427204D03*
X1429053Y1073383D03*
X1427203Y1076587D03*
X1414254Y1066974D03*
Y1073383D03*
X1416103Y1070178D03*
Y1076587D03*
X1417954Y1066974D03*
Y1073383D03*
X1419803Y1070178D03*
Y1076587D03*
X1421653Y1066974D03*
Y1073383D03*
X1414254Y1079791D03*
X1417954D03*
X1421653D03*
X1429053Y1066974D03*
X1425353D03*
X1427204Y1070178D03*
X1429053Y1086200D03*
X1416103Y1082995D03*
X1419803D03*
X1414254Y1086200D03*
Y1092608D03*
X1416103Y1089404D03*
Y1095813D03*
X1417954Y1086200D03*
Y1092608D03*
X1419803Y1089404D03*
Y1095813D03*
X1421653Y1086200D03*
Y1092608D03*
X1423503Y1089404D03*
Y1095813D03*
X1425353Y1092608D03*
X1427202Y1082995D03*
X1414254Y1099017D03*
Y1105426D03*
Y1111834D03*
X1416103Y1102221D03*
Y1108630D03*
X1417954Y1099017D03*
Y1105426D03*
Y1111834D03*
X1419803Y1102221D03*
Y1108630D03*
X1421653Y1099017D03*
Y1105426D03*
Y1111834D03*
X1425354Y1099017D03*
Y1105426D03*
Y1111834D03*
X1427203Y1102221D03*
Y1108630D03*
X1429054Y1105426D03*
Y1111834D03*
X1414254Y1118243D03*
Y1124651D03*
X1416103Y1115039D03*
Y1121447D03*
Y1127856D03*
X1417954Y1118243D03*
Y1124651D03*
X1419803Y1115039D03*
Y1121447D03*
Y1127856D03*
X1421653Y1118243D03*
Y1124651D03*
X1425354Y1118243D03*
Y1124651D03*
X1427203Y1115039D03*
Y1121447D03*
Y1127856D03*
X1429054Y1118243D03*
Y1124651D03*
X1414254Y1131060D03*
Y1137769D03*
X1416103Y1134264D03*
X1417954Y1131060D03*
Y1137769D03*
X1419803Y1134264D03*
X1421653Y1131060D03*
Y1137769D03*
X1425354Y1131060D03*
Y1137769D03*
X1427203Y1134264D03*
X1429054Y1131060D03*
Y1137769D03*
X1443420Y848176D03*
X1436020D03*
X1443420Y860993D03*
X1436020D03*
Y873810D03*
X1443420D03*
X1436020Y899445D03*
X1443420D03*
X1436020Y886627D03*
X1443420D03*
X1447120Y899445D03*
X1445271Y902649D03*
X1434171Y909057D03*
X1437871Y915466D03*
X1443420Y912262D03*
X1445271Y915466D03*
X1437871Y909057D03*
X1434171Y915466D03*
X1436020Y918670D03*
X1439720Y912262D03*
X1436020D03*
Y905853D03*
X1439720D03*
X1443420D03*
X1445271Y909057D03*
X1430471Y921875D03*
X1443420Y918670D03*
X1439777Y928348D03*
X1437477D03*
X1435177D03*
X1444377D03*
X1442077D03*
X1445271Y921875D03*
X1439720Y918670D03*
X1441571Y921875D03*
X1434171D03*
X1445392Y942195D03*
X1429726Y944537D03*
Y939937D03*
Y942237D03*
X1429544Y959298D03*
Y956998D03*
X1437565Y956619D03*
X1434545D03*
X1445045D03*
X1429544Y970798D03*
Y973098D03*
X1437565Y971139D03*
X1434545Y971099D03*
X1429544Y986898D03*
Y984598D03*
X1437565Y985579D03*
X1434545D03*
X1445045D03*
X1429544Y998398D03*
Y1012198D03*
Y1000698D03*
X1437565Y1000079D03*
X1434545D03*
X1445045D03*
X1429544Y1014498D03*
X1437436Y1014509D03*
X1434545Y1014539D03*
X1445036Y1014549D03*
X1439321Y1028854D03*
X1436821D03*
X1434321D03*
X1441821D03*
X1434083Y1031908D03*
X1447553Y1041340D03*
X1443853D03*
X1436453Y1047750D03*
X1443853D03*
X1430904Y1044544D03*
Y1038136D03*
X1434083Y1034408D03*
X1434813Y1037069D03*
X1439413D03*
X1437113D03*
X1432753Y1041340D03*
X1440153D03*
X1438304Y1044544D03*
X1434604D03*
X1432753Y1060565D03*
X1438303Y1057361D03*
Y1063770D03*
X1442002Y1050952D03*
X1440153Y1054157D03*
X1436454D03*
X1434604Y1057361D03*
X1443854Y1054157D03*
Y1060565D03*
X1430903Y1063770D03*
X1440154Y1060565D03*
X1434603Y1050952D03*
X1436453Y1060565D03*
Y1073383D03*
X1434602Y1070178D03*
X1436453Y1066974D03*
X1440153D03*
X1442002Y1070178D03*
X1447553Y1066974D03*
X1440154Y1079791D03*
X1436454D03*
X1438304Y1076587D03*
X1432753Y1066974D03*
X1442004Y1076587D03*
X1440153Y1073383D03*
X1434604Y1076587D03*
X1438304Y1082995D03*
X1442004D03*
X1438303Y1095812D03*
X1434603D03*
X1442003Y1089403D03*
X1432754Y1092607D03*
X1430903Y1089403D03*
X1436454Y1086199D03*
X1430902Y1082995D03*
X1442003Y1095812D03*
X1440154Y1092607D03*
X1430903Y1095812D03*
X1434603Y1089403D03*
X1438303D03*
X1438304Y1102221D03*
X1443853Y1099017D03*
X1430903Y1102221D03*
Y1108630D03*
X1432754Y1105426D03*
X1432753Y1111834D03*
X1434603Y1108630D03*
X1436454Y1111834D03*
Y1099016D03*
X1430903Y1115039D03*
Y1121447D03*
Y1127856D03*
X1432753Y1118243D03*
Y1124651D03*
X1436454Y1118243D03*
Y1124651D03*
X1438303Y1115039D03*
Y1121447D03*
Y1127856D03*
X1440153Y1118243D03*
X1440154Y1124651D03*
X1442003Y1127856D03*
X1443854Y1131060D03*
Y1137469D03*
X1430903Y1134264D03*
Y1140973D03*
X1432753Y1131060D03*
X1432754Y1137469D03*
X1434603Y1140973D03*
X1436454Y1131060D03*
Y1137469D03*
X1438303Y1134264D03*
Y1140973D03*
X1440154Y1131060D03*
Y1137469D03*
X1442003Y1134264D03*
Y1140973D03*
X1450820Y848176D03*
X1458220D03*
X1450820Y860993D03*
X1458220D03*
X1450820Y880219D03*
X1452671Y883423D03*
X1458220Y880219D03*
X1460071Y883423D03*
X1448971D03*
X1456371D03*
X1458220Y873810D03*
X1450820D03*
Y893036D03*
X1448971Y896240D03*
X1454520Y886627D03*
Y899445D03*
X1458220Y886627D03*
X1450820D03*
X1452671Y896240D03*
X1456371Y902649D03*
Y915466D03*
X1447122Y912262D03*
X1454521Y918670D03*
X1452671Y915466D03*
X1454522Y912262D03*
X1448971Y902649D03*
X1456370Y909057D03*
X1458220Y905853D03*
X1452671Y902649D03*
X1448970Y915466D03*
X1447120Y905853D03*
X1454520D03*
X1448971Y909057D03*
X1452671D03*
X1456371Y928283D03*
X1454522Y931488D03*
X1454520Y925079D03*
X1458220D03*
X1448971Y921875D03*
X1447120Y918670D03*
X1446677Y928348D03*
X1454520Y937896D03*
X1456371Y941100D03*
Y947509D03*
X1449992Y942195D03*
X1447692D03*
X1454520Y963530D03*
X1456371Y966735D03*
X1458220Y963529D03*
X1456370Y960326D03*
X1456371Y953917D03*
X1454520Y957122D03*
Y950713D03*
X1447545Y956619D03*
X1458220Y982756D03*
X1454521Y969939D03*
X1450045Y971099D03*
X1445445D03*
X1447745D03*
X1452426Y973825D03*
Y971525D03*
X1456371Y979552D03*
X1454520Y982756D03*
X1456371Y973143D03*
X1454520Y976347D03*
X1447545Y985579D03*
X1456804Y999684D03*
X1454953Y1002888D03*
Y1009297D03*
X1456804Y1012501D03*
X1447545Y1000079D03*
X1447345Y1014539D03*
X1456804Y1031727D03*
X1454953Y1028523D03*
Y1022114D03*
X1456803Y1018910D03*
X1454953Y1015705D03*
X1446934Y1028889D03*
X1452466Y1031794D03*
Y1029494D03*
Y1027194D03*
X1456804Y1025318D03*
X1458653Y1015705D03*
X1451253Y1047749D03*
X1445704Y1044544D03*
X1454953Y1034931D03*
X1456804Y1038136D03*
X1454953Y1041340D03*
X1456804Y1044544D03*
X1449404D03*
X1454953Y1047749D03*
X1453104Y1044544D03*
X1456804Y1063770D03*
X1458653Y1054157D03*
X1454954D03*
X1453104Y1057361D03*
Y1063770D03*
X1454954Y1060565D03*
X1456803Y1057361D03*
X1453103Y1050952D03*
X1445703Y1057361D03*
X1445704Y1063770D03*
X1447554Y1060565D03*
X1449403Y1057361D03*
X1449404Y1063770D03*
X1451254Y1054157D03*
X1445703Y1050952D03*
X1449404D03*
X1454953Y1066974D03*
X1445702Y1070178D03*
X1453104Y1076587D03*
X1456804D03*
Y1070178D03*
X1453104D03*
X1447553Y1073383D03*
X1449404Y1076587D03*
X1445704D03*
X1447553Y1079791D03*
X1451253Y1073383D03*
X1458653D03*
X1445704Y1082995D03*
X1456804Y1089404D03*
X1449404Y1095813D03*
X1454954Y1092607D03*
X1451254D03*
X1449403Y1089403D03*
X1447554Y1086199D03*
X1453103Y1082994D03*
X1458654Y1092607D03*
X1453103Y1095812D03*
X1447554Y1092607D03*
X1451254Y1086199D03*
X1454954D03*
X1456804Y1102221D03*
Y1121447D03*
X1449404D03*
X1456804Y1134264D03*
X1445703D03*
X1465620Y848176D03*
X1473020D03*
X1465620Y860993D03*
X1473020D03*
X1465620Y880219D03*
X1467471Y883423D03*
X1473020Y880219D03*
X1474871Y883423D03*
X1463771D03*
X1471171D03*
X1473020Y873810D03*
X1465620D03*
X1461920Y886627D03*
X1469320D03*
X1476720D03*
X1473020D03*
X1465620D03*
X1464204Y1095813D03*
X1477154Y1105426D03*
Y1111833D03*
X1464204Y1115039D03*
Y1121447D03*
X1471604Y1134264D03*
X1464204D03*
X1487820Y848176D03*
X1480420D03*
X1487820Y860993D03*
X1480420D03*
X1487820Y880219D03*
X1489671Y883423D03*
X1480420Y880219D03*
X1482271Y883423D03*
X1485971D03*
X1493371D03*
X1478571D03*
X1487820Y873810D03*
X1480420D03*
X1491520Y886627D03*
X1484120D03*
X1480420D03*
X1487820D03*
X1479004Y1006093D03*
X1486404Y1102221D03*
X1479003Y1108629D03*
X1488254Y1105426D03*
X1484554Y1111833D03*
X1482703Y1102220D03*
X1480854Y1111833D03*
Y1105426D03*
X1486403Y1108630D03*
X1488254Y1111833D03*
X1484554Y1105426D03*
X1479004Y1115039D03*
Y1121447D03*
X1493804D03*
X1486404D03*
X1482703Y1115038D03*
X1479004Y1134264D03*
X1493804D03*
X1486404D03*
X1495220Y848176D03*
Y860993D03*
X1502621D03*
X1495220Y880219D03*
X1497071Y883423D03*
X1502621Y880219D03*
X1504471Y883423D03*
X1500771D03*
X1495220Y873810D03*
X1502621D03*
X1506320Y893036D03*
X1498920Y886627D03*
X1506321D03*
X1495220D03*
X1502621D03*
X1510021D03*
X1506753Y1105426D03*
X1504904Y1102221D03*
X1501204D03*
X1499354Y1099017D03*
X1503053Y1118243D03*
X1510453D03*
X1501204Y1121447D03*
X1508603Y1121446D03*
X1510453Y1124650D03*
X1508603Y1127855D03*
X1501204Y1134264D03*
X1508603Y1140973D03*
X1504903D03*
X1517853Y1118243D03*
X1519703Y1121446D03*
X1516003Y1127855D03*
X1512303D03*
Y1121446D03*
X1516003D03*
X1517853Y1124650D03*
X1519703Y1127855D03*
X1514154Y1131059D03*
X1611475Y1259227D03*
X1714440Y1255381D03*
X1821083Y1252034D03*
G54D40*
X322500Y1391830D03*
X537477Y1395413D03*
X1298642Y1391830D03*
X1513618Y1395413D03*
G54D10*
X27559Y87795D03*
X40708Y631890D03*
Y1368897D03*
X51181Y1714961D03*
X373622Y87795D03*
X395670Y1714961D03*
X661023Y631890D03*
X707677Y1714961D03*
X800787Y87795D03*
X931692Y757874D03*
Y1072834D03*
Y1387795D03*
X1045865Y87795D03*
X1155708Y1714961D03*
X1271260Y631890D03*
X1461805Y1714961D03*
X1499606Y87795D03*
X1816771Y631890D03*
Y1368897D03*
X1806299Y1714961D03*
X1829921Y87795D03*
G54D36*
X238780Y1681456D03*
X230906Y1677519D03*
Y1682244D03*
X238780Y1686180D03*
Y1695629D03*
X230906Y1691692D03*
Y1696417D03*
X238780Y1700354D03*
Y1709803D03*
Y1714527D03*
X230906Y1705866D03*
Y1710590D03*
X238780Y1723976D03*
Y1728700D03*
X230906Y1720039D03*
Y1724763D03*
X254528Y1681456D03*
X246654Y1677519D03*
Y1682244D03*
X254528Y1686180D03*
Y1695629D03*
X246654Y1691692D03*
Y1696417D03*
X254528Y1700354D03*
Y1709803D03*
Y1714527D03*
X246654Y1705866D03*
Y1710590D03*
X254528Y1723976D03*
Y1728700D03*
X246654Y1720039D03*
Y1724763D03*
X270276Y1681456D03*
X262402Y1677519D03*
Y1682244D03*
X270276Y1686180D03*
Y1695629D03*
X262402Y1691692D03*
Y1696417D03*
X270276Y1700354D03*
Y1709803D03*
Y1714527D03*
X262402Y1705866D03*
Y1710590D03*
X270276Y1723976D03*
Y1728700D03*
X262402Y1720039D03*
Y1724763D03*
X286024Y1681456D03*
X278150Y1677519D03*
Y1682244D03*
X286024Y1686180D03*
Y1695629D03*
X278150Y1691692D03*
Y1696417D03*
X286024Y1700354D03*
Y1709803D03*
Y1714527D03*
X278150Y1705866D03*
Y1710590D03*
X286024Y1723976D03*
Y1728700D03*
X278150Y1720039D03*
Y1724763D03*
X297835Y1677519D03*
Y1682244D03*
X305709Y1681456D03*
Y1686180D03*
X297835Y1691692D03*
Y1696417D03*
X305709Y1695629D03*
Y1700354D03*
X297835Y1705866D03*
Y1710590D03*
X305709Y1709803D03*
Y1714527D03*
X297835Y1720039D03*
Y1724763D03*
X305709Y1723976D03*
Y1728700D03*
X313583Y1677519D03*
Y1682244D03*
X321457Y1681456D03*
Y1686180D03*
X313583Y1691692D03*
Y1696417D03*
X321457Y1695629D03*
Y1700354D03*
X313583Y1705866D03*
Y1710590D03*
X321457Y1709803D03*
Y1714527D03*
X313583Y1720039D03*
Y1724763D03*
X321457Y1723976D03*
Y1728700D03*
X329331Y1677519D03*
Y1682244D03*
X337205Y1681456D03*
Y1686180D03*
X329331Y1691692D03*
Y1696417D03*
X337205Y1695629D03*
Y1700354D03*
X329331Y1705866D03*
Y1710590D03*
X337205Y1709803D03*
Y1714527D03*
X329331Y1720039D03*
Y1724763D03*
X337205Y1723976D03*
Y1728700D03*
X345079Y1677519D03*
Y1682244D03*
X352953Y1681456D03*
Y1686180D03*
X345079Y1691692D03*
Y1696417D03*
X352953Y1695629D03*
Y1700354D03*
X345079Y1705866D03*
Y1710590D03*
X352953Y1709803D03*
Y1714527D03*
X345079Y1720039D03*
Y1724763D03*
X352953Y1723976D03*
Y1728700D03*
X495079Y1677519D03*
Y1682244D03*
Y1691692D03*
Y1696417D03*
Y1705866D03*
Y1710590D03*
Y1720039D03*
Y1724763D03*
X510827Y1677519D03*
X502953Y1681456D03*
X510827Y1682244D03*
X502953Y1686180D03*
X510827Y1691692D03*
X502953Y1695629D03*
X510827Y1696417D03*
X502953Y1700354D03*
X510827Y1705866D03*
X502953Y1709803D03*
X510827Y1710590D03*
X502953Y1714527D03*
X510827Y1720039D03*
X502953Y1723976D03*
X510827Y1724763D03*
X502953Y1728700D03*
X526575Y1677519D03*
X518701Y1681456D03*
X526575Y1682244D03*
X534449Y1681456D03*
X518701Y1686180D03*
X534449D03*
X526575Y1691692D03*
X518701Y1695629D03*
X526575Y1696417D03*
X534449Y1695629D03*
X518701Y1700354D03*
X534449D03*
X526575Y1705866D03*
X518701Y1709803D03*
X526575Y1710590D03*
X534449Y1709803D03*
X518701Y1714527D03*
X534449D03*
X526575Y1720039D03*
X518701Y1723976D03*
X526575Y1724763D03*
X534449Y1723976D03*
X518701Y1728700D03*
X534449D03*
X542323Y1677519D03*
Y1682244D03*
X550197Y1681456D03*
Y1686180D03*
X542323Y1691692D03*
Y1696417D03*
X550197Y1695629D03*
Y1700354D03*
X542323Y1705866D03*
Y1710590D03*
X550197Y1709803D03*
Y1714527D03*
X542323Y1720039D03*
Y1724763D03*
X550197Y1723976D03*
Y1728700D03*
X562008Y1677519D03*
Y1682244D03*
Y1691692D03*
Y1696417D03*
Y1705866D03*
Y1710590D03*
Y1720039D03*
Y1724763D03*
X577756Y1677519D03*
X569882Y1681456D03*
X577756Y1682244D03*
X569882Y1686180D03*
X577756Y1691692D03*
X569882Y1695629D03*
X577756Y1696417D03*
X569882Y1700354D03*
X577756Y1705866D03*
X569882Y1709803D03*
X577756Y1710590D03*
X569882Y1714527D03*
X577756Y1720039D03*
X569882Y1723976D03*
X577756Y1724763D03*
X569882Y1728700D03*
X593504Y1677519D03*
X585630Y1681456D03*
X593504Y1682244D03*
X585630Y1686180D03*
X593504Y1691692D03*
X585630Y1695629D03*
X593504Y1696417D03*
X585630Y1700354D03*
X593504Y1705866D03*
X585630Y1709803D03*
X593504Y1710590D03*
X585630Y1714527D03*
X593504Y1720039D03*
X585630Y1723976D03*
X593504Y1724763D03*
X585630Y1728700D03*
X609252Y1677519D03*
X601378Y1681456D03*
X609252Y1682244D03*
X601378Y1686180D03*
X609252Y1691692D03*
X601378Y1695629D03*
X609252Y1696417D03*
X601378Y1700354D03*
X609252Y1705866D03*
X601378Y1709803D03*
X609252Y1710590D03*
X601378Y1714527D03*
X609252Y1720039D03*
X601378Y1723976D03*
X609252Y1724763D03*
X601378Y1728700D03*
X617126Y1681456D03*
Y1686180D03*
Y1695629D03*
Y1700354D03*
Y1709803D03*
Y1714527D03*
Y1723976D03*
Y1728700D03*
X1238780Y1677519D03*
Y1682244D03*
X1246654Y1681456D03*
Y1686180D03*
X1238780Y1691692D03*
Y1696417D03*
X1246654Y1695629D03*
Y1700354D03*
X1238780Y1705866D03*
Y1710590D03*
X1246654Y1709803D03*
Y1714527D03*
X1238780Y1720039D03*
Y1724763D03*
X1246654Y1723976D03*
Y1728700D03*
X1254528Y1677519D03*
Y1682244D03*
X1262402Y1681456D03*
Y1686180D03*
X1254528Y1691692D03*
Y1696417D03*
X1262402Y1695629D03*
Y1700354D03*
X1254528Y1705866D03*
Y1710590D03*
X1262402Y1709803D03*
Y1714527D03*
X1254528Y1720039D03*
Y1724763D03*
X1262402Y1723976D03*
Y1728700D03*
X1270276Y1677519D03*
Y1682244D03*
X1278150Y1681456D03*
Y1686180D03*
X1270276Y1691692D03*
Y1696417D03*
X1278150Y1695629D03*
Y1700354D03*
X1270276Y1705866D03*
Y1710590D03*
X1278150Y1709803D03*
Y1714527D03*
X1270276Y1720039D03*
Y1724763D03*
X1278150Y1723976D03*
Y1728700D03*
X1286024Y1677519D03*
Y1682244D03*
X1293898Y1681456D03*
Y1686180D03*
X1286024Y1691692D03*
Y1696417D03*
X1293898Y1695629D03*
Y1700354D03*
X1286024Y1705866D03*
Y1710590D03*
X1293898Y1709803D03*
Y1714527D03*
X1286024Y1720039D03*
Y1724763D03*
X1293898Y1723976D03*
Y1728700D03*
X1305709Y1677519D03*
Y1682244D03*
X1313583Y1681456D03*
Y1686180D03*
X1305709Y1691692D03*
Y1696417D03*
X1313583Y1695629D03*
Y1700354D03*
X1305709Y1705866D03*
Y1710590D03*
X1313583Y1709803D03*
Y1714527D03*
X1305709Y1720039D03*
Y1724763D03*
X1313583Y1723976D03*
Y1728700D03*
X1321457Y1677519D03*
Y1682244D03*
X1329331Y1681456D03*
Y1686180D03*
X1321457Y1691692D03*
Y1696417D03*
X1329331Y1695629D03*
Y1700354D03*
X1321457Y1705866D03*
Y1710590D03*
X1329331Y1709803D03*
Y1714527D03*
X1321457Y1720039D03*
Y1724763D03*
X1329331Y1723976D03*
Y1728700D03*
X1337205Y1677519D03*
Y1682244D03*
X1345079Y1681456D03*
Y1686180D03*
X1337205Y1691692D03*
Y1696417D03*
X1345079Y1695629D03*
Y1700354D03*
X1337205Y1705866D03*
Y1710590D03*
X1345079Y1709803D03*
Y1714527D03*
X1337205Y1720039D03*
Y1724763D03*
X1345079Y1723976D03*
Y1728700D03*
X1352953Y1677519D03*
Y1682244D03*
X1360827Y1681456D03*
Y1686180D03*
X1352953Y1691692D03*
Y1696417D03*
X1360827Y1695629D03*
Y1700354D03*
X1352953Y1705866D03*
Y1710590D03*
X1360827Y1709803D03*
Y1714527D03*
X1352953Y1720039D03*
Y1724763D03*
X1360827Y1723976D03*
Y1728700D03*
X1502953Y1677519D03*
Y1682244D03*
X1510827Y1681456D03*
Y1686180D03*
X1502953Y1691692D03*
Y1696417D03*
X1510827Y1695629D03*
Y1700354D03*
X1502953Y1705866D03*
Y1710590D03*
X1510827Y1709803D03*
Y1714527D03*
X1502953Y1720039D03*
Y1724763D03*
X1510827Y1723976D03*
Y1728700D03*
X1518701Y1677519D03*
Y1682244D03*
X1526575Y1681456D03*
Y1686180D03*
X1518701Y1691692D03*
Y1696417D03*
X1526575Y1695629D03*
Y1700354D03*
X1518701Y1705866D03*
Y1710590D03*
X1526575Y1709803D03*
Y1714527D03*
X1518701Y1720039D03*
Y1724763D03*
X1526575Y1723976D03*
Y1728700D03*
X1534449Y1677519D03*
Y1682244D03*
X1542323Y1681456D03*
Y1686180D03*
X1534449Y1691692D03*
Y1696417D03*
X1542323Y1695629D03*
Y1700354D03*
X1534449Y1705866D03*
Y1710590D03*
X1542323Y1709803D03*
Y1714527D03*
X1534449Y1720039D03*
Y1724763D03*
X1542323Y1723976D03*
Y1728700D03*
X1550197Y1677519D03*
Y1682244D03*
X1558071Y1681456D03*
Y1686180D03*
X1550197Y1691692D03*
Y1696417D03*
X1558071Y1695629D03*
Y1700354D03*
X1550197Y1705866D03*
Y1710590D03*
X1558071Y1709803D03*
Y1714527D03*
X1550197Y1720039D03*
Y1724763D03*
X1558071Y1723976D03*
Y1728700D03*
X1569882Y1677519D03*
Y1682244D03*
Y1691692D03*
Y1696417D03*
Y1705866D03*
Y1710590D03*
Y1720039D03*
Y1724763D03*
X1585630Y1677519D03*
X1577756Y1681456D03*
X1585630Y1682244D03*
X1577756Y1686180D03*
X1585630Y1691692D03*
X1577756Y1695629D03*
X1585630Y1696417D03*
X1577756Y1700354D03*
X1585630Y1705866D03*
X1577756Y1709803D03*
X1585630Y1710590D03*
X1577756Y1714527D03*
X1585630Y1720039D03*
X1577756Y1723976D03*
X1585630Y1724763D03*
X1577756Y1728700D03*
X1601378Y1677519D03*
X1593504Y1681456D03*
X1601378Y1682244D03*
X1593504Y1686180D03*
X1601378Y1691692D03*
X1593504Y1695629D03*
X1601378Y1696417D03*
X1593504Y1700354D03*
X1601378Y1705866D03*
X1593504Y1709803D03*
X1601378Y1710590D03*
X1593504Y1714527D03*
X1601378Y1720039D03*
X1593504Y1723976D03*
X1601378Y1724763D03*
X1593504Y1728700D03*
X1617126Y1677519D03*
X1609252Y1681456D03*
X1617126Y1682244D03*
X1609252Y1686180D03*
X1617126Y1691692D03*
X1609252Y1695629D03*
X1617126Y1696417D03*
X1609252Y1700354D03*
X1617126Y1705866D03*
X1609252Y1709803D03*
X1617126Y1710590D03*
X1609252Y1714527D03*
X1617126Y1720039D03*
X1609252Y1723976D03*
X1617126Y1724763D03*
X1609252Y1728700D03*
X1625000Y1681456D03*
Y1686180D03*
Y1695629D03*
Y1700354D03*
Y1709803D03*
Y1714527D03*
Y1723976D03*
Y1728700D03*
G54D37*
X277098Y185236D03*
X395208D03*
G54D32*
X205159Y1430034D03*
X393067Y1354446D03*
X422833D03*
X453169D03*
X468443Y1379662D03*
X482543Y1353962D03*
X718638Y1429579D03*
X1178470Y1466363D03*
X1369208Y1353946D03*
X1398974D03*
X1429310D03*
X1444043Y1379362D03*
X1459076Y1353946D03*
X1679944Y1463655D03*
X1836248Y269763D03*
Y299056D03*
G54D30*
X174685Y637367D03*
X174393Y668511D03*
X526478Y1439952D03*
X1502956Y1439530D03*
X1682882Y618174D03*
Y669109D03*
X1769790Y194789D03*
X1799350D03*
G54D48*
X493500Y246362D03*
X559236Y1441207D03*
G54D51*
X688500Y1601900D03*
X1041435Y153357D03*
X1056225Y153131D03*
X1099970Y1702570D03*
G54D66*
X1133779Y1653543D03*
G54D38*
X278126Y676260D03*
Y700414D03*
X395771Y1242785D03*
X420171D03*
X444493D03*
X468893D03*
X493293D03*
X1371912D03*
X1396312D03*
X1420634D03*
X1445034D03*
X1469434D03*
G54D28*
X159474Y1320753D03*
X183847Y1320778D03*
X208247D03*
X275289Y575702D03*
Y599861D03*
Y624015D03*
Y648169D03*
X673093Y1320778D03*
X697466Y1320803D03*
X721866D03*
X1100800Y251488D03*
X1100700Y275788D03*
X1131100Y1357088D03*
X1155500D03*
X1179900D03*
X1577000Y591888D03*
Y616388D03*
Y640888D03*
Y665288D03*
Y689788D03*
Y714288D03*
X1634259Y1354374D03*
X1658632Y1354399D03*
X1683032D03*
G54D78*
X1902608Y988322D03*
X1902682Y1351295D03*
X1951178Y1349597D03*
X1993618Y1349897D03*
G54D75*
X1881720Y988279D03*
X1881211Y1350983D03*
X1930200Y1349548D03*
X1972697Y1349606D03*
G54D23*
X40120Y744554D03*
Y1000853D03*
Y1287664D03*
X69820Y744554D03*
Y1000853D03*
Y1287664D03*
X99520Y744554D03*
Y1000853D03*
Y1287664D03*
X129220Y744554D03*
Y1000853D03*
Y1287664D03*
X158920Y744554D03*
Y1000853D03*
Y1287664D03*
X188620Y744554D03*
Y1000853D03*
Y1287664D03*
X218320Y744554D03*
Y1000853D03*
Y1287664D03*
X248020Y744554D03*
Y1000853D03*
Y1287664D03*
X633320Y744554D03*
Y1000853D03*
Y1287664D03*
X663020Y744554D03*
Y1000853D03*
Y1287664D03*
X692720Y744554D03*
Y1000853D03*
Y1287664D03*
X722420Y744554D03*
Y1000853D03*
Y1287664D03*
X752120Y744554D03*
Y1000853D03*
Y1287664D03*
X781820Y744554D03*
Y1000853D03*
Y1287664D03*
X811520Y744554D03*
Y1000853D03*
Y1287664D03*
X841220Y744554D03*
Y1000853D03*
Y1287664D03*
X1016262Y744554D03*
Y1000853D03*
Y1287664D03*
X1045962Y744554D03*
Y1000853D03*
Y1287664D03*
X1075662Y744554D03*
Y1000853D03*
Y1287664D03*
X1105362Y744554D03*
Y1000853D03*
Y1287664D03*
X1135062Y744554D03*
Y1000853D03*
Y1287664D03*
X1164762Y744554D03*
Y1000853D03*
Y1287664D03*
X1194462Y744554D03*
Y1000853D03*
Y1287664D03*
X1224162Y744554D03*
Y1000853D03*
Y1287664D03*
X1609462Y744554D03*
Y1000853D03*
Y1287664D03*
X1639162Y744554D03*
Y1000853D03*
Y1287664D03*
X1668862Y744554D03*
Y1000853D03*
Y1287664D03*
X1698562Y744554D03*
Y1000853D03*
Y1287664D03*
X1728262Y744554D03*
Y1000853D03*
Y1287664D03*
X1757962Y744554D03*
Y1000853D03*
Y1287664D03*
X1787662Y744554D03*
Y1000853D03*
Y1287664D03*
X1817362Y744554D03*
Y1000853D03*
Y1287664D03*
G54D61*
X928739Y321653D03*
G54D33*
X250326Y185236D03*
X368437D03*
G54D62*
X916545Y309459D03*
X911494Y321653D03*
X916545Y333847D03*
X940933Y309459D03*
X928739Y304408D03*
Y338898D03*
X940933Y333847D03*
X945984Y321653D03*
G54D68*
X1247638Y269488D03*
X1405118Y112008D03*
X1766929Y1714960D03*
G54D13*
X19685Y-29134D03*
Y1803261D03*
X1837795Y-29134D03*
Y1803261D03*
X2081889Y-29134D03*
Y1803261D03*
G54D69*
X1405876Y1453298D03*
X1430204Y1452014D03*
G54D18*
X38346Y1420330D03*
X117932Y605380D03*
X763601Y605413D03*
X1094074Y605380D03*
X1739706Y605455D03*
X1819208Y1420330D03*
G54D21*
X49280Y337402D03*
X41870Y1511291D03*
X441043Y1672205D03*
Y1718465D03*
X1416437Y1672204D03*
Y1718464D03*
X1808192Y1569255D03*
X1812980Y502472D03*
G54D39*
X306772Y991220D03*
X350099Y811121D03*
X356063Y1171318D03*
X531240Y811121D03*
X525276Y1171318D03*
X574567Y991220D03*
X1282914D03*
X1326240Y811121D03*
X1332205Y1171318D03*
X1507382Y811121D03*
X1501418Y1171318D03*
X1550709Y991220D03*
G54D54*
X791280Y1704890D03*
X1066280D03*
G54D34*
X238780Y1648385D03*
X230906Y1644448D03*
X238780Y1662558D03*
X230906Y1658621D03*
X238780Y1676732D03*
X230906Y1672795D03*
X238780Y1690905D03*
X230906Y1686968D03*
X238780Y1705078D03*
X230906Y1701141D03*
Y1715314D03*
X238780Y1719251D03*
X230906Y1729488D03*
X238780Y1733425D03*
X254528Y1648385D03*
X246654Y1644448D03*
X254528Y1662558D03*
X246654Y1658621D03*
X254528Y1676732D03*
X246654Y1672795D03*
X254528Y1690905D03*
X246654Y1686968D03*
X254528Y1705078D03*
X246654Y1701141D03*
Y1715314D03*
X254528Y1719251D03*
X246654Y1729488D03*
X254528Y1733425D03*
X270276Y1648385D03*
X262402Y1644448D03*
X270276Y1662558D03*
X262402Y1658621D03*
X270276Y1676732D03*
X262402Y1672795D03*
X270276Y1690905D03*
X262402Y1686968D03*
X270276Y1705078D03*
X262402Y1701141D03*
Y1715314D03*
X270276Y1719251D03*
X262402Y1729488D03*
X270276Y1733425D03*
X286024Y1648385D03*
X278150Y1644448D03*
X286024Y1662558D03*
X278150Y1658621D03*
X286024Y1676732D03*
X278150Y1672795D03*
X286024Y1690905D03*
X278150Y1686968D03*
X286024Y1705078D03*
X278150Y1701141D03*
Y1715314D03*
X286024Y1719251D03*
X278150Y1729488D03*
X286024Y1733425D03*
X297835Y1672795D03*
X305709Y1676732D03*
X297835Y1686968D03*
X305709Y1690905D03*
X297835Y1701141D03*
X305709Y1705078D03*
X297835Y1715314D03*
X305709Y1719251D03*
X297835Y1729488D03*
X305709Y1733425D03*
X313583Y1672795D03*
X321457Y1676732D03*
X313583Y1686968D03*
X321457Y1690905D03*
X313583Y1701141D03*
X321457Y1705078D03*
X313583Y1715314D03*
X321457Y1719251D03*
X313583Y1729488D03*
X321457Y1733425D03*
X329331Y1672795D03*
X337205Y1676732D03*
X329331Y1686968D03*
X337205Y1690905D03*
X329331Y1701141D03*
X337205Y1705078D03*
X329331Y1715314D03*
X337205Y1719251D03*
X329331Y1729488D03*
X337205Y1733425D03*
X345079Y1672795D03*
X352953Y1676732D03*
X345079Y1686968D03*
X352953Y1690905D03*
X345079Y1701141D03*
X352953Y1705078D03*
X345079Y1715314D03*
X352953Y1719251D03*
X345079Y1729488D03*
X352953Y1733425D03*
X495079Y1672795D03*
Y1686968D03*
Y1701141D03*
Y1715314D03*
Y1729488D03*
X510827Y1672795D03*
X502953Y1676732D03*
X518701D03*
X510827Y1686968D03*
X502953Y1690905D03*
X518701D03*
X510827Y1701141D03*
X502953Y1705078D03*
X518701D03*
X510827Y1715314D03*
X502953Y1719251D03*
X518701D03*
X510827Y1729488D03*
X502953Y1733425D03*
X518701D03*
X526575Y1672795D03*
X534449Y1676732D03*
X526575Y1686968D03*
X534449Y1690905D03*
X526575Y1701141D03*
X534449Y1705078D03*
X526575Y1715314D03*
X534449Y1719251D03*
X526575Y1729488D03*
X534449Y1733425D03*
X542323Y1672795D03*
X550197Y1676732D03*
X542323Y1686968D03*
X550197Y1690905D03*
X542323Y1701141D03*
X550197Y1705078D03*
X542323Y1715314D03*
X550197Y1719251D03*
X542323Y1729488D03*
X550197Y1733425D03*
X562008Y1672795D03*
Y1686968D03*
Y1701141D03*
Y1715314D03*
Y1729488D03*
X577756Y1672795D03*
X569882Y1676732D03*
X577756Y1686968D03*
X569882Y1690905D03*
X577756Y1701141D03*
X569882Y1705078D03*
X577756Y1715314D03*
X569882Y1719251D03*
X577756Y1729488D03*
X569882Y1733425D03*
X593504Y1672795D03*
X585630Y1676732D03*
X593504Y1686968D03*
X585630Y1690905D03*
X593504Y1701141D03*
X585630Y1705078D03*
X593504Y1715314D03*
X585630Y1719251D03*
X593504Y1729488D03*
X585630Y1733425D03*
X609252Y1672795D03*
X601378Y1676732D03*
X609252Y1686968D03*
X601378Y1690905D03*
X609252Y1701141D03*
X601378Y1705078D03*
X609252Y1715314D03*
X601378Y1719251D03*
X609252Y1729488D03*
X601378Y1733425D03*
X617126Y1676732D03*
Y1690905D03*
Y1705078D03*
Y1719251D03*
Y1733425D03*
X1238780Y1672795D03*
X1246654Y1676732D03*
X1238780Y1686968D03*
X1246654Y1690905D03*
X1238780Y1701141D03*
X1246654Y1705078D03*
X1238780Y1715314D03*
X1246654Y1719251D03*
X1238780Y1729488D03*
X1246654Y1733425D03*
X1254528Y1672795D03*
X1262402Y1676732D03*
X1254528Y1686968D03*
X1262402Y1690905D03*
X1254528Y1701141D03*
X1262402Y1705078D03*
X1254528Y1715314D03*
X1262402Y1719251D03*
X1254528Y1729488D03*
X1262402Y1733425D03*
X1270276Y1672795D03*
X1278150Y1676732D03*
X1270276Y1686968D03*
X1278150Y1690905D03*
X1270276Y1701141D03*
X1278150Y1705078D03*
X1270276Y1715314D03*
X1278150Y1719251D03*
X1270276Y1729488D03*
X1278150Y1733425D03*
X1286024Y1672795D03*
X1293898Y1676732D03*
X1286024Y1686968D03*
X1293898Y1690905D03*
X1286024Y1701141D03*
X1293898Y1705078D03*
X1286024Y1715314D03*
X1293898Y1719251D03*
X1286024Y1729488D03*
X1293898Y1733425D03*
X1305709Y1672795D03*
X1313583Y1676732D03*
X1305709Y1686968D03*
X1313583Y1690905D03*
X1305709Y1701141D03*
X1313583Y1705078D03*
X1305709Y1715314D03*
X1313583Y1719251D03*
X1305709Y1729488D03*
X1313583Y1733425D03*
X1321457Y1672795D03*
X1329331Y1676732D03*
X1321457Y1686968D03*
X1329331Y1690905D03*
X1321457Y1701141D03*
X1329331Y1705078D03*
X1321457Y1715314D03*
X1329331Y1719251D03*
X1321457Y1729488D03*
X1329331Y1733425D03*
X1337205Y1672795D03*
X1345079Y1676732D03*
X1337205Y1686968D03*
X1345079Y1690905D03*
X1337205Y1701141D03*
X1345079Y1705078D03*
X1337205Y1715314D03*
X1345079Y1719251D03*
X1337205Y1729488D03*
X1345079Y1733425D03*
X1352953Y1672795D03*
X1360827Y1676732D03*
X1352953Y1686968D03*
X1360827Y1690905D03*
X1352953Y1701141D03*
X1360827Y1705078D03*
X1352953Y1715314D03*
X1360827Y1719251D03*
X1352953Y1729488D03*
X1360827Y1733425D03*
X1502953Y1672795D03*
X1510827Y1676732D03*
X1502953Y1686968D03*
X1510827Y1690905D03*
X1502953Y1701141D03*
X1510827Y1705078D03*
X1502953Y1715314D03*
X1510827Y1719251D03*
X1502953Y1729488D03*
X1510827Y1733425D03*
X1518701Y1672795D03*
X1526575Y1676732D03*
X1518701Y1686968D03*
X1526575Y1690905D03*
X1518701Y1701141D03*
X1526575Y1705078D03*
X1518701Y1715314D03*
X1526575Y1719251D03*
X1518701Y1729488D03*
X1526575Y1733425D03*
X1534449Y1672795D03*
X1542323Y1676732D03*
X1534449Y1686968D03*
X1542323Y1690905D03*
X1534449Y1701141D03*
X1542323Y1705078D03*
X1534449Y1715314D03*
X1542323Y1719251D03*
X1534449Y1729488D03*
X1542323Y1733425D03*
X1550197Y1672795D03*
X1558071Y1676732D03*
X1550197Y1686968D03*
X1558071Y1690905D03*
X1550197Y1701141D03*
X1558071Y1705078D03*
X1550197Y1715314D03*
X1558071Y1719251D03*
X1550197Y1729488D03*
X1558071Y1733425D03*
X1569882Y1672795D03*
Y1686968D03*
Y1701141D03*
Y1715314D03*
Y1729488D03*
X1585630Y1672795D03*
X1577756Y1676732D03*
X1585630Y1686968D03*
X1577756Y1690905D03*
X1585630Y1701141D03*
X1577756Y1705078D03*
X1585630Y1715314D03*
X1577756Y1719251D03*
X1585630Y1729488D03*
X1577756Y1733425D03*
X1601378Y1672795D03*
X1593504Y1676732D03*
X1601378Y1686968D03*
X1593504Y1690905D03*
X1601378Y1701141D03*
X1593504Y1705078D03*
X1601378Y1715314D03*
X1593504Y1719251D03*
X1601378Y1729488D03*
X1593504Y1733425D03*
X1617126Y1672795D03*
X1609252Y1676732D03*
X1625000D03*
X1617126Y1686968D03*
X1609252Y1690905D03*
X1625000D03*
X1617126Y1701141D03*
X1609252Y1705078D03*
X1625000D03*
X1617126Y1715314D03*
X1609252Y1719251D03*
X1625000D03*
X1617126Y1729488D03*
X1609252Y1733425D03*
X1625000D03*
G54D45*
X441043Y1698268D03*
X1416437Y1698267D03*
G54D56*
X805690Y204724D03*
X1057658D03*
G54D20*
X41492Y290637D03*
X44833Y1659909D03*
X61340Y384362D03*
X61250Y396142D03*
X49250Y396332D03*
X49400Y384392D03*
X47618Y413113D03*
X47619Y421155D03*
X56799Y1524094D03*
Y1528094D03*
Y1532094D03*
Y1544094D03*
Y1548094D03*
Y1552094D03*
Y1556094D03*
X54333Y1604359D03*
X50900Y1677775D03*
X65881Y305426D03*
X72774Y1549669D03*
X66906Y1598324D03*
Y1603280D03*
X84274Y1517619D03*
X81038Y1536899D03*
X91538Y1539399D03*
X84700Y1627000D03*
X99274Y1526019D03*
X126225Y504368D03*
X120225D03*
Y510368D03*
X126225Y516368D03*
X120225D03*
X112749Y1524594D03*
Y1540594D03*
Y1544594D03*
Y1548594D03*
Y1536594D03*
Y1564594D03*
Y1560594D03*
X132225Y504368D03*
Y510368D03*
X132401Y516368D03*
X129670Y1563160D03*
X153271Y1540961D03*
X153138Y1549032D03*
X166986Y575918D03*
X161321Y1540858D03*
X161374Y1549073D03*
X189800Y705062D03*
X208312Y576125D03*
X196526Y567825D03*
X208312Y581085D03*
Y578605D03*
X197423Y601496D03*
X194059Y604901D03*
X208312Y615085D03*
Y610125D03*
Y612605D03*
X194059Y638901D03*
X197423Y635496D03*
X208312Y649085D03*
Y644125D03*
Y646605D03*
X213912Y576125D03*
X220668Y574131D03*
X223775D03*
X224064Y568113D03*
X221464D03*
X213912Y578605D03*
Y581085D03*
X217556Y590575D03*
X217561Y582131D03*
Y579531D03*
X223775Y587731D03*
X223759Y590675D03*
X220652D03*
X223775Y584531D03*
X220668Y576731D03*
Y579331D03*
X223775Y581931D03*
Y579331D03*
Y576731D03*
X220668Y581931D03*
Y608131D03*
X223775D03*
X224064Y602113D03*
X221464D03*
X223403Y596820D03*
Y594220D03*
X213912Y612605D03*
Y615085D03*
Y610125D03*
X217561Y616131D03*
Y613531D03*
X217556Y624575D03*
X223759Y624675D03*
X220652D03*
X223775Y618531D03*
X220668Y610731D03*
Y613331D03*
X223775Y615931D03*
Y613331D03*
Y610731D03*
X220668Y615931D03*
X223775Y621731D03*
X223403Y630820D03*
Y628220D03*
X224064Y636113D03*
X221464D03*
X213912Y646605D03*
Y649085D03*
Y644125D03*
X217561Y650131D03*
Y647531D03*
X223775Y655731D03*
Y652531D03*
X220668Y644731D03*
Y647331D03*
Y642131D03*
X223775Y649931D03*
Y647331D03*
Y644731D03*
Y642131D03*
X220668Y649931D03*
X217556Y658575D03*
X223403Y664820D03*
X223759Y658675D03*
X220652D03*
X217510Y668712D03*
X225167Y672006D03*
X222567D03*
X219967D03*
X217367D03*
X211348Y688087D03*
Y685287D03*
X214100Y687376D03*
Y690376D03*
Y684376D03*
Y681376D03*
Y678376D03*
X211348Y690787D03*
Y693587D03*
X214100Y693576D03*
X224506Y698138D03*
Y700738D03*
X221906Y698138D03*
Y700738D03*
X219306D03*
Y698138D03*
X231864Y568113D03*
X229264D03*
X226664D03*
X238393Y570490D03*
X240993D03*
X229264Y602113D03*
X226664D03*
X226003Y594220D03*
Y596820D03*
X228603Y594220D03*
Y596820D03*
X231864Y602113D03*
X233803Y594220D03*
Y596820D03*
X231203Y594220D03*
Y596820D03*
X238393Y604490D03*
X240993D03*
Y596820D03*
X238393D03*
X240993Y594220D03*
X238393D03*
X226003Y628220D03*
Y630820D03*
X228603Y628220D03*
Y630820D03*
X231864Y636113D03*
X233803Y628220D03*
Y630820D03*
X231203Y628220D03*
Y630820D03*
X229264Y636113D03*
X226664D03*
X238393Y638490D03*
X240993D03*
Y630820D03*
X238393D03*
X240993Y628220D03*
X238393D03*
X228603Y664820D03*
X233803D03*
X231203D03*
X226003D03*
X230367Y672006D03*
X227767D03*
X227106Y698138D03*
Y700738D03*
X246400Y563162D03*
X263580Y218627D03*
X318651Y22921D03*
X320825Y159062D03*
X410700Y1658460D03*
X435340Y125346D03*
X435240Y1609200D03*
X433383Y1602629D03*
X450380Y104647D03*
X440019Y1576809D03*
X442128Y1574879D03*
X441308Y1602654D03*
X505055Y1387601D03*
Y1382301D03*
Y1396001D03*
Y1398601D03*
Y1390201D03*
X563634Y1334315D03*
X561034D03*
X612670Y142872D03*
X612520Y154812D03*
X624610Y142842D03*
X624520Y154622D03*
X702975Y414864D03*
X739206Y608020D03*
Y603064D03*
X758830Y1674823D03*
X819114Y115223D03*
X824498Y145198D03*
X831114Y115223D03*
X829114Y150273D03*
X854577Y99651D03*
X876124Y66072D03*
Y86072D03*
Y106072D03*
Y126072D03*
X887869Y386618D03*
X881372Y920655D03*
X898062Y976652D03*
Y969716D03*
X942646Y400793D03*
X946865Y974077D03*
X953235Y972642D03*
X946938Y991162D03*
X943720Y985772D03*
X956022Y1620730D03*
X953022D03*
Y1632730D03*
X956022D03*
Y1629730D03*
X953022D03*
X956022Y1626730D03*
X953022D03*
Y1623730D03*
X956022D03*
X963610Y981292D03*
X959535Y990477D03*
X963780Y997496D03*
X962022Y1620730D03*
X959022D03*
Y1632730D03*
X962022D03*
Y1629730D03*
X959022D03*
X962022Y1626730D03*
X959022D03*
Y1623730D03*
X962022D03*
X978403Y-9022D03*
Y-13978D03*
Y-19022D03*
Y-23978D03*
Y6022D03*
Y10978D03*
Y20978D03*
Y16022D03*
X988835Y185443D03*
X989500Y376362D03*
X985672Y432961D03*
X987662Y1620870D03*
Y1629870D03*
Y1626870D03*
Y1623870D03*
Y1632870D03*
X1002500Y266862D03*
X991770Y418835D03*
X992608Y432961D03*
X1002640Y594692D03*
X990662Y1620870D03*
X993662D03*
Y1629870D03*
X990662D03*
X993662Y1626870D03*
X990662D03*
Y1623870D03*
X993662D03*
X990662Y1632870D03*
X993662D03*
X1001810Y1662700D03*
Y1665200D03*
X1018000Y263862D03*
X1022000Y264362D03*
X1014500Y263862D03*
X1010500D03*
X1018000Y266862D03*
X1010500D03*
X1006500D03*
X1014500D03*
X1011611Y430038D03*
X1019252Y1620870D03*
X1022252D03*
Y1623870D03*
Y1626870D03*
X1019252Y1623870D03*
Y1626870D03*
X1019910Y1662700D03*
Y1665200D03*
X1025000Y264362D03*
X1038220Y589862D03*
X1030980Y598722D03*
X1023740Y596152D03*
X1036480Y596272D03*
X1025252Y1620870D03*
Y1623870D03*
Y1626870D03*
X1023580Y1662700D03*
Y1665200D03*
X1027370Y1662700D03*
Y1665200D03*
X1040924Y286073D03*
X1043720Y589362D03*
X1050200Y598062D03*
X1050390Y604172D03*
X1053200Y612162D03*
X1050721Y1633043D03*
X1053721D03*
Y1624043D03*
Y1627043D03*
Y1630043D03*
X1050721Y1624043D03*
Y1627043D03*
Y1630043D03*
X1053721Y1621043D03*
X1050721D03*
X1044850Y1665050D03*
Y1662550D03*
X1067718Y288500D03*
X1070618D03*
X1056280Y601232D03*
X1056721Y1633043D03*
Y1624043D03*
Y1627043D03*
Y1630043D03*
Y1621043D03*
X1095900Y1646935D03*
X1095649Y1638875D03*
X1099457D03*
X1104457Y1675490D03*
X1120544Y312200D03*
X1129995Y301637D03*
X1150914Y197407D03*
X1148354Y222677D03*
X1150272Y638346D03*
X1160720Y180862D03*
X1165000Y190962D03*
X1162500D03*
X1164300Y197262D03*
X1163732Y204887D03*
X1160732D03*
X1158172Y230157D03*
X1159912Y638216D03*
X1166722Y636206D03*
X1158762Y642266D03*
X1168402Y642136D03*
X1159930Y1645632D03*
X1164830D03*
X1161613Y1669112D03*
X1173065Y194174D03*
X1172865Y210174D03*
X1172795Y222174D03*
X1180398Y289814D03*
X1171540Y310902D03*
X1176362Y636076D03*
X1180262Y642216D03*
X1181930Y1645632D03*
X1186830D03*
X1175830D03*
X1170930D03*
X1183613Y1669112D03*
X1172613D03*
X1189902Y642086D03*
X1192500Y1645942D03*
X1197400D03*
X1194183Y1669422D03*
X1192340Y1691422D03*
X1197240D03*
X1194023Y1714902D03*
X1206093Y120362D03*
X1214593Y168962D03*
X1208518Y174162D03*
X1203858Y185451D03*
X1208365Y271151D03*
X1210457Y1658415D03*
X1218810Y1691732D03*
X1213910D03*
X1203110Y1691467D03*
X1208010D03*
X1215593Y1715212D03*
X1204793Y1714947D03*
X1228704Y112122D03*
X1223100Y127300D03*
X1226093Y152792D03*
X1227500Y380400D03*
X1242520Y165362D03*
X1236593Y209562D03*
X1236584Y217462D03*
X1245614Y227462D03*
X1266093Y129962D03*
X1256093Y143462D03*
X1264685Y175506D03*
X1279485Y105752D03*
X1278949Y123567D03*
X1282293Y248962D03*
X1275557Y269477D03*
Y272436D03*
X1282653Y269446D03*
X1278557Y272436D03*
Y269477D03*
X1272557Y272436D03*
X1287795Y-29033D03*
Y-33989D03*
Y-9033D03*
Y-13989D03*
Y-19033D03*
Y-23989D03*
Y967D03*
Y-3989D03*
X1293430Y84072D03*
X1294354Y105912D03*
X1295053Y140181D03*
X1292293Y143162D03*
X1287943Y233748D03*
X1284437Y230280D03*
X1293893Y237962D03*
X1286611Y260908D03*
X1295887Y315571D03*
X1314741Y68652D03*
X1300454Y95302D03*
X1302964Y124633D03*
X1301993Y140462D03*
X1313950Y261612D03*
X1308790Y290172D03*
X1302450Y290072D03*
X1307798Y287561D03*
X1313246Y287631D03*
X1308220Y304262D03*
X1303120Y304162D03*
X1330102Y59025D03*
X1327920Y84418D03*
X1316478Y92970D03*
X1330273Y128373D03*
X1326493Y249562D03*
X1317893Y257462D03*
X1328393Y264262D03*
X1339280Y126175D03*
X1356223Y131569D03*
X1362793Y145262D03*
X1366124Y101529D03*
X1377597Y197604D03*
X1375300Y208422D03*
X1378452Y236055D03*
X1389609Y145291D03*
X1389443Y147859D03*
X1386780Y197668D03*
X1395321D03*
X1409558Y151948D03*
Y156904D03*
X1401240Y171672D03*
X1404071Y197668D03*
X1412851D03*
X1398700Y1597800D03*
X1436436Y300319D03*
X1456423Y209362D03*
X1453823Y205982D03*
X1445777Y362021D03*
X1449296Y410497D03*
X1451580Y1627990D03*
X1462777Y362021D03*
X1470877Y374496D03*
X1463277Y406446D03*
X1470954D03*
X1476570Y1657974D03*
X1480154Y-29033D03*
Y-33989D03*
Y-9033D03*
Y-13989D03*
Y-19033D03*
Y-23989D03*
Y967D03*
Y-3989D03*
X1481155Y1387742D03*
X1481255Y1382042D03*
X1481155Y1396342D03*
Y1398942D03*
Y1390342D03*
X1478724Y1637189D03*
X1505821Y215802D03*
X1524770Y195792D03*
X1521201Y215551D03*
X1531750Y199762D03*
X1529610Y211614D03*
X1532590Y225432D03*
X1561494Y584292D03*
X1604040Y219692D03*
X1604290Y242472D03*
X1636393Y181778D03*
X1632899Y213012D03*
X1670004Y537065D03*
Y543065D03*
Y531065D03*
X1683394Y469878D03*
X1683476Y473378D03*
X1684356Y476290D03*
X1681602Y485180D03*
X1684356Y485628D03*
X1677464Y491790D03*
X1682004Y537065D03*
X1682180Y543065D03*
X1676004D03*
X1682004Y531065D03*
X1676004D03*
X1697648Y463724D03*
X1693648D03*
X1692883Y703943D03*
X1709027Y655141D03*
X1725473Y474859D03*
X1754307Y262186D03*
X1751068Y262123D03*
X1754245Y269724D03*
X1751068Y266048D03*
X1754307Y266111D03*
X1754414Y275329D03*
X1752165Y273901D03*
X1749565D03*
X1751006Y269661D03*
X1749595Y276711D03*
X1752195D03*
X1748989Y380206D03*
X1764955Y301951D03*
X1768757Y380498D03*
X1793061Y24659D03*
X1828880Y1626595D03*
Y1646595D03*
Y1666595D03*
Y1686595D03*
X1840691Y329470D03*
Y349470D03*
Y369470D03*
Y389470D03*
Y409470D03*
Y429470D03*
Y449470D03*
Y469470D03*
Y489470D03*
Y509470D03*
Y529470D03*
Y549470D03*
Y569470D03*
Y589470D03*
Y669470D03*
Y1329470D03*
Y1409470D03*
Y1429470D03*
Y1449470D03*
Y1469470D03*
Y1489470D03*
Y1509470D03*
Y1529470D03*
Y1549470D03*
Y1569470D03*
Y1589470D03*
X1854470Y112379D03*
Y152379D03*
Y172379D03*
Y192379D03*
Y212379D03*
Y232379D03*
Y252379D03*
Y272379D03*
Y292379D03*
G54D60*
X922441Y154311D03*
Y243799D03*
G54D12*
X14092Y287115D03*
X17371Y49388D03*
X22223Y388057D03*
X29509Y398132D03*
X29962Y401000D03*
X24700Y765600D03*
X37371Y49388D03*
X36255Y304972D03*
X42809Y360862D03*
X39410Y384582D03*
X39226Y395346D03*
X33020Y382822D03*
X36524Y398013D03*
X30680Y438142D03*
X58379Y69340D03*
X60379Y66844D03*
Y71836D03*
X60692Y87118D03*
X54920Y185039D03*
Y177165D03*
X46834Y360862D03*
X55190D03*
X53825Y421746D03*
X54762Y444993D03*
X53800Y435451D03*
X58658Y754145D03*
X55177Y1322328D03*
X55277Y1326068D03*
X46994Y1663165D03*
X69058Y3010D03*
X79047Y23978D03*
X74091D03*
X72091Y25974D03*
X73020Y37106D03*
Y48720D03*
X67335Y69340D03*
X65335Y66844D03*
Y71836D03*
X65648Y87118D03*
X71379Y72844D03*
Y77836D03*
X76335Y72844D03*
Y77836D03*
X78335Y75340D03*
X69379D03*
X71772Y421746D03*
X75490Y432519D03*
X68365Y443677D03*
X64150Y434972D03*
X74340Y663422D03*
X76365Y699244D03*
X76565Y717949D03*
X72315Y717414D03*
X64325Y715674D03*
X75564Y1509952D03*
X78120Y1512936D03*
Y1521336D03*
X75922Y1564874D03*
Y1556474D03*
X73429Y1570008D03*
X78415D03*
X73832Y1689362D03*
X77833Y1689162D03*
X89058Y3010D03*
X81196Y17042D03*
Y22034D03*
X86152Y17042D03*
Y22034D03*
X95369Y17042D03*
Y22034D03*
X79196Y19538D03*
X88152D03*
X93369D03*
X88264Y23978D03*
X93220D03*
X86264Y25974D03*
X95220D03*
X81047D03*
X94279Y37106D03*
X87193D03*
X80106D03*
X94279Y48720D03*
X87193D03*
X80106D03*
X80379Y69340D03*
X89335D03*
X82379Y66844D03*
Y71836D03*
X87335Y66844D03*
Y71836D03*
X91379Y75340D03*
X93379Y72844D03*
Y77836D03*
X86490Y200787D03*
Y208661D03*
X85960Y224409D03*
X85788Y240157D03*
X90700Y282762D03*
Y300262D03*
X87654Y376026D03*
X87520Y386502D03*
X94811Y510173D03*
X80460Y655672D03*
X83100Y649762D03*
X82735Y717949D03*
X87865Y714394D03*
X85165D03*
X81225Y715854D03*
X79635Y717949D03*
X85835Y718049D03*
X93295Y762019D03*
X92071Y1492888D03*
X80649Y1509944D03*
X93544Y1510099D03*
X88459Y1510107D03*
X90998Y1513037D03*
Y1521437D03*
X84048Y1578008D03*
X90713Y1585852D03*
Y1589852D03*
Y1593867D03*
X90788Y1611821D03*
Y1605867D03*
Y1623821D03*
X90698Y1638362D03*
Y1634362D03*
X86245Y1690362D03*
X81833Y1689162D03*
X94220Y1686622D03*
X109058Y3010D03*
X100325Y17042D03*
Y22034D03*
X109542Y17042D03*
Y22034D03*
X102325Y19538D03*
X107542D03*
X102437Y23978D03*
X107393D03*
X100437Y25974D03*
X109393D03*
X108453Y37106D03*
X101366D03*
X108453Y48720D03*
X101366D03*
X102379Y69340D03*
X111335D03*
X104379Y66844D03*
Y71836D03*
X109335Y66844D03*
Y71836D03*
X98335Y72844D03*
Y77836D03*
X100335Y75340D03*
X101317Y431727D03*
X102060Y493578D03*
X111087Y520052D03*
X98134Y722501D03*
X99716Y1567878D03*
X99750Y1559478D03*
X96251Y1577532D03*
X107451Y1574704D03*
X100451D03*
X104318Y1592304D03*
Y1603690D03*
X110200Y1605200D03*
X104318Y1622380D03*
Y1641075D03*
X99980Y1685362D03*
Y1696052D03*
X114498Y17042D03*
Y22034D03*
X123716Y17042D03*
Y22034D03*
X116498Y19538D03*
X121716D03*
X121567Y23978D03*
X116611D03*
X114611Y25974D03*
X123567D03*
X122626Y37106D03*
X115539D03*
X122626Y48720D03*
X115539D03*
X124379Y69340D03*
X126379Y66844D03*
Y71836D03*
X115379Y72844D03*
Y77836D03*
X120335Y72844D03*
Y77836D03*
X122335Y75340D03*
X113379D03*
X114087Y285495D03*
Y302854D03*
X127206Y480216D03*
X123257Y547506D03*
X119087D03*
X115060D03*
X120267Y1327697D03*
X127366Y1535855D03*
Y1541874D03*
Y1547935D03*
X116798Y1586288D03*
Y1598572D03*
Y1635303D03*
X127195Y1670362D03*
X117795Y1698862D03*
X127195Y1688362D03*
Y1692362D03*
Y1708362D03*
X117255Y1730422D03*
X129058Y3010D03*
X128672Y17042D03*
Y22034D03*
X130672Y19538D03*
X129713Y37106D03*
Y48720D03*
X133335Y69340D03*
X131335Y66844D03*
Y71836D03*
X137379Y72844D03*
Y77836D03*
X142335Y72844D03*
Y77836D03*
X135379Y75340D03*
X130057Y636103D03*
X129600Y669400D03*
X132967Y760525D03*
X141470Y1359100D03*
X140104Y1560136D03*
X139080Y1731398D03*
X149058Y3010D03*
X159582Y17042D03*
Y22034D03*
X157582Y19538D03*
X152477Y23978D03*
X157433D03*
X150477Y25974D03*
X159433D03*
X158492Y37106D03*
X151405D03*
X158492Y48720D03*
X151405D03*
X146379Y69340D03*
X155335D03*
X148379Y66844D03*
Y71836D03*
X153335Y66844D03*
Y71836D03*
X158583Y75340D03*
X144335D03*
X149371Y423383D03*
Y419383D03*
Y427383D03*
Y439383D03*
Y431383D03*
Y435383D03*
Y443383D03*
X147141Y698811D03*
X147435Y690807D03*
X149861Y698831D03*
X150155Y690807D03*
X156685Y706836D03*
X153965Y706816D03*
X153879Y721660D03*
X156469D03*
X147031Y706835D03*
X149621D03*
X149669Y721660D03*
X147079D03*
X154477Y1360797D03*
X148663Y1378607D03*
X151163D03*
Y1383807D03*
Y1381207D03*
X158318Y1384286D03*
X155718D03*
X158318Y1387393D03*
X155718D03*
X148663Y1386407D03*
X151163D03*
X148663Y1383807D03*
Y1381207D03*
X160201Y1399732D03*
X157731D03*
Y1394132D03*
X160201D03*
X152806Y1414175D03*
X144748Y1514878D03*
X149728D03*
X154581Y1520981D03*
X158570D03*
X150502Y1572021D03*
X145522D03*
X159107Y1571364D03*
X144854Y1702389D03*
X154803Y1708532D03*
X155100Y1723262D03*
X169058Y3010D03*
X164538Y17042D03*
Y22034D03*
X173755Y17042D03*
Y22034D03*
X166538Y19538D03*
X171755D03*
X166650Y23978D03*
X171606D03*
X164650Y25974D03*
X173606D03*
X172665Y37106D03*
X165579D03*
X172665Y48720D03*
X165579D03*
X169583Y69340D03*
X171583Y66844D03*
Y71836D03*
X176539Y66844D03*
Y71836D03*
X165539Y72844D03*
X160583D03*
Y77836D03*
X165539D03*
X167539Y75340D03*
X174327Y230928D03*
X171180Y401885D03*
X163900Y409362D03*
X163132Y493299D03*
X162750Y512502D03*
X172807Y1360797D03*
X160918Y1384286D03*
X163518D03*
Y1387393D03*
X160918D03*
X169318Y1384286D03*
X166118D03*
X172262Y1384302D03*
Y1387409D03*
X174932Y1378797D03*
Y1381397D03*
X163718Y1390500D03*
X161118D03*
X162631Y1399732D03*
Y1394132D03*
X172231Y1390532D03*
X162693Y1411529D03*
X171262Y1443390D03*
X168900Y1520510D03*
X163920D03*
X166476Y1572464D03*
X171456D03*
X166529Y1707678D03*
X166661Y1721211D03*
X189058Y3010D03*
X178711Y17042D03*
Y22034D03*
X180711Y19538D03*
X179752Y37106D03*
Y48720D03*
X191583Y69340D03*
X178539D03*
X182583Y72844D03*
Y77836D03*
X187539Y72844D03*
Y77836D03*
X189539Y75340D03*
X180583D03*
X186457Y393071D03*
Y385071D03*
Y389071D03*
Y405071D03*
X192220Y408662D03*
Y412162D03*
X177871Y421383D03*
Y425383D03*
Y430883D03*
Y443383D03*
X187490Y568752D03*
X190977Y669718D03*
X191976Y684326D03*
X184215Y1361072D03*
X181403Y1361115D03*
X192620Y1360797D03*
X188233Y1387027D03*
Y1379227D03*
Y1381827D03*
Y1384427D03*
X183283Y1387987D03*
X185633Y1387027D03*
X180672Y1387987D03*
X185633Y1379227D03*
X180672Y1380187D03*
X183283D03*
X177532Y1378797D03*
X185633Y1384427D03*
Y1381827D03*
X180672Y1382787D03*
Y1385387D03*
X183283Y1382787D03*
Y1385387D03*
X177421Y1383997D03*
X177532Y1381397D03*
X182653Y1404535D03*
X192767Y1413725D03*
X185643Y1413945D03*
X185895Y1535462D03*
Y1539723D03*
Y1544029D03*
Y1548487D03*
Y1552875D03*
X176793Y1585173D03*
X188119Y1580678D03*
Y1575686D03*
Y1592590D03*
Y1587598D03*
X192529Y1728947D03*
X183822Y1720517D03*
X209058Y3010D03*
X203716Y17042D03*
Y22034D03*
X208672Y17042D03*
Y22034D03*
X201716Y19538D03*
X201567Y23978D03*
X196611D03*
X194611Y25974D03*
X203567D03*
X208784D03*
X202626Y37106D03*
X195539D03*
X202626Y48720D03*
X195539D03*
X200539Y69340D03*
X193583Y66844D03*
Y71836D03*
X198539Y66844D03*
Y71836D03*
X204717Y72844D03*
Y77836D03*
X202717Y75340D03*
X195888Y581071D03*
X194515Y583433D03*
X195888Y615071D03*
X194515Y617433D03*
Y651433D03*
X195888Y649071D03*
X205320Y667562D03*
X207856Y686443D03*
X203043Y686483D03*
X207824Y681560D03*
X203044Y684036D03*
X207834Y684006D03*
X203237Y681549D03*
X199720Y732862D03*
X206720Y731862D03*
X199220Y739362D03*
X207602Y756855D03*
X199602D03*
X201661Y1384286D03*
X193861D03*
X196461D03*
X199061D03*
X201661Y1387393D03*
X193861D03*
X196461D03*
X199061D03*
X204261Y1384286D03*
X207461D03*
X201861Y1390500D03*
X199261D03*
X195874Y1399732D03*
X198344D03*
X200774D03*
X195874Y1394132D03*
X198344D03*
X200774D03*
X201071Y1412173D03*
X193075Y1580678D03*
Y1575686D03*
X200179D03*
X205135D03*
X200179Y1580678D03*
X205135D03*
X193075Y1592590D03*
Y1587598D03*
X200179Y1592590D03*
X205135D03*
X200179Y1587598D03*
X205135D03*
X198375Y1599884D03*
X193419D03*
X205479D03*
X193419Y1616788D03*
Y1611796D03*
X198375D03*
X193419Y1604876D03*
X198375D03*
Y1616788D03*
X205479Y1611796D03*
Y1604876D03*
Y1616788D03*
X207229Y1631181D03*
X193410Y1711606D03*
X205582Y1700867D03*
X196443Y1722197D03*
X217889Y17042D03*
Y22034D03*
X222845Y17042D03*
Y22034D03*
X210672Y19538D03*
X215889D03*
X224845D03*
X215740Y23978D03*
X210784D03*
X217740Y25974D03*
X223886Y37106D03*
X216799D03*
X209713D03*
X223886Y48720D03*
X216799D03*
X209713D03*
X215717Y66844D03*
Y71836D03*
X220673Y66844D03*
Y71836D03*
X213717Y69340D03*
X222673D03*
X209673Y72844D03*
Y77836D03*
X211673Y75340D03*
X224717D03*
X209579Y457222D03*
Y462235D03*
X211220Y740362D03*
X215824Y1361199D03*
X211350Y1360797D03*
X218960Y1388312D03*
X210405Y1384302D03*
Y1387409D03*
X213075Y1381558D03*
X217133Y1384055D03*
X214425Y1384058D03*
X215675Y1381558D03*
X218175D03*
X213075Y1378958D03*
X215675D03*
X218175D03*
X210374Y1390532D03*
X212239Y1580678D03*
X217195D03*
Y1575686D03*
X212239D03*
X224299D03*
Y1580678D03*
X212239Y1587598D03*
X217195D03*
X212239Y1592590D03*
X217195D03*
X224299Y1587598D03*
Y1592590D03*
X210435Y1599884D03*
X222495D03*
X217539D03*
X210435Y1611796D03*
Y1604876D03*
Y1616788D03*
X222495D03*
X217539D03*
X222495Y1604876D03*
Y1611796D03*
X217539Y1604876D03*
Y1611796D03*
X212684Y1720307D03*
X229058Y3010D03*
X238063Y37162D03*
X230972Y37106D03*
Y48720D03*
X226717Y72844D03*
Y77836D03*
X231673Y72844D03*
Y77836D03*
X233673Y75340D03*
X233800Y162692D03*
X237539Y174266D03*
X228550Y420412D03*
X229255Y1575686D03*
Y1580678D03*
X236359D03*
Y1575686D03*
X241315Y1580678D03*
Y1575686D03*
X229255Y1587598D03*
Y1592590D03*
X236359D03*
Y1587598D03*
X241315Y1592590D03*
Y1587598D03*
X229599Y1599884D03*
X234555D03*
X229599Y1604876D03*
Y1611796D03*
X234555Y1604876D03*
Y1611796D03*
X229599Y1616788D03*
X234555D03*
X249058Y3010D03*
X243490Y23002D03*
X247720Y71862D03*
X244300Y59762D03*
X247720Y75862D03*
X251797Y100843D03*
X249735Y152694D03*
X242255Y162512D03*
X249300Y510362D03*
X253800Y515362D03*
X249860Y518222D03*
X248419Y1575686D03*
X253375D03*
X248419Y1580678D03*
X253375D03*
X248419Y1587598D03*
X253375D03*
X248419Y1592590D03*
X253375D03*
X246615Y1599884D03*
X241659D03*
X253719D03*
X241659Y1616788D03*
X246615D03*
Y1604876D03*
X241659D03*
X246615Y1611796D03*
X241659D03*
X253719Y1604876D03*
Y1611796D03*
Y1616788D03*
X269058Y3010D03*
X263280Y35312D03*
X272600Y27182D03*
X271600Y40162D03*
X272361Y120243D03*
X270364Y118415D03*
X261387Y133783D03*
X258257D03*
X264578Y155203D03*
Y159203D03*
X260700Y218662D03*
X268940Y217982D03*
X270745Y207562D03*
X265343Y244460D03*
X272029Y443735D03*
X274270Y746602D03*
X260479Y1580678D03*
X265435D03*
X260479Y1575592D03*
X265435D03*
X272539Y1575686D03*
Y1580678D03*
X260479Y1592590D03*
X265435D03*
X260479Y1587598D03*
X265435D03*
X272539D03*
Y1592590D03*
X258675Y1599884D03*
X270735Y1599790D03*
X265779D03*
X258675Y1604876D03*
Y1611796D03*
Y1616788D03*
X270735D03*
X265779D03*
X270735Y1611796D03*
Y1604876D03*
X265779D03*
Y1611796D03*
X289058Y3010D03*
X285900Y23962D03*
X287952Y39984D03*
X286071Y48720D03*
X286500Y52462D03*
X278984Y48720D03*
X287800Y60062D03*
X283953Y152503D03*
X288520Y157062D03*
X279740Y205962D03*
X276890Y249022D03*
X289920Y248652D03*
X286920D03*
X282420D03*
X287819Y691097D03*
X287820Y727962D03*
X278520Y738072D03*
X290077Y739735D03*
X289047Y760245D03*
X277495Y1575686D03*
Y1580678D03*
X284599D03*
X289555D03*
Y1575686D03*
X284599D03*
X277495Y1587598D03*
Y1592590D03*
X284599D03*
X289555D03*
X284599Y1587598D03*
X289555D03*
X282795Y1599884D03*
X277839D03*
X289899D03*
X282795Y1604876D03*
Y1611796D03*
X277839D03*
Y1604876D03*
X282795Y1616788D03*
X277839D03*
X289899D03*
Y1604876D03*
Y1611796D03*
X291520Y12762D03*
X291660Y21642D03*
X298720Y40017D03*
X306720Y39982D03*
X292942Y67513D03*
X293447Y78573D03*
X293452Y82483D03*
Y85983D03*
X303047Y79373D03*
X299947Y79273D03*
X299657Y92503D03*
X299628Y149203D03*
Y158703D03*
X294553Y153819D03*
X306087Y569718D03*
X294658Y637809D03*
X290680Y745312D03*
X299427Y768265D03*
X303831Y1318566D03*
X303807Y1342225D03*
X303831Y1344866D03*
X304047Y1368565D03*
X296659Y1575686D03*
X301615D03*
X296659Y1580678D03*
X301615D03*
X296659Y1587598D03*
X301615D03*
X296659Y1592590D03*
X301615D03*
X294855Y1599884D03*
X301959D03*
X294855Y1616788D03*
Y1604876D03*
Y1611796D03*
X301959Y1604876D03*
Y1611796D03*
Y1616788D03*
X309058Y3010D03*
X320057Y85803D03*
Y88803D03*
X314200Y585282D03*
X316080Y578262D03*
X320691Y602448D03*
X311820Y598762D03*
X316397Y776125D03*
X312301Y1345539D03*
Y1342432D03*
X309701Y1345539D03*
Y1342432D03*
X316655Y1352295D03*
X314175D03*
X311695D03*
X320101Y1342432D03*
X317701Y1348646D03*
X315101D03*
X314901Y1345539D03*
X317501D03*
X314901Y1342432D03*
X317501D03*
X316655Y1357895D03*
X311695D03*
X314175D03*
X317979Y1371248D03*
X315221Y1372445D03*
X308719Y1580678D03*
X313675D03*
X308719Y1575686D03*
X313675D03*
X320779D03*
Y1580678D03*
X308719Y1592590D03*
X313675D03*
X308719Y1587598D03*
X313675D03*
X320779D03*
Y1592590D03*
X306915Y1599884D03*
X318975D03*
X314019D03*
X306915Y1604876D03*
Y1611796D03*
Y1616788D03*
X318975D03*
X314019D03*
X318975Y1604876D03*
Y1611796D03*
X314019Y1604876D03*
Y1611796D03*
X329535Y49388D03*
X336240Y150738D03*
X330674Y368261D03*
X331760Y705882D03*
X328915Y1337104D03*
X331515D03*
X328915Y1331904D03*
X331515D03*
X328915Y1329304D03*
X331515D03*
X328915Y1334504D03*
X331515D03*
X328915Y1339704D03*
X326145Y1348651D03*
X326245Y1345555D03*
Y1342448D03*
X323301Y1342432D03*
X338917Y1349488D03*
X336347Y1348353D03*
X325735Y1575686D03*
Y1580678D03*
X332839D03*
X337795D03*
X332839Y1575686D03*
X337795D03*
X325735Y1587598D03*
Y1592590D03*
X332839D03*
X337795D03*
X332839Y1587598D03*
X337795D03*
X326079Y1599884D03*
X331035D03*
X338139D03*
X326079Y1604876D03*
Y1611796D03*
X331035Y1604876D03*
Y1611796D03*
X326079Y1616788D03*
X331035D03*
X338139D03*
Y1604876D03*
Y1611796D03*
X349535Y49388D03*
X343040Y122522D03*
X345869Y192716D03*
X353145Y228362D03*
X345164Y314234D03*
X349187Y715485D03*
X344446Y739434D03*
X348000Y755362D03*
X344429Y1322741D03*
X347029D03*
X341829D03*
X347029Y1319634D03*
X344429D03*
X341829D03*
X349629Y1322741D03*
Y1319634D03*
X352229D03*
X355429D03*
X346303Y1335097D03*
X343823D03*
Y1329497D03*
X346303D03*
X347229Y1325848D03*
X348783Y1329497D03*
X349829Y1325848D03*
X348783Y1335097D03*
X348804Y1346877D03*
X350470Y1349030D03*
X344899Y1575686D03*
X349855D03*
X344899Y1580678D03*
X349855D03*
X344899Y1587598D03*
X349855D03*
X344899Y1592590D03*
X349855D03*
X343095Y1599884D03*
X355155D03*
X350199D03*
X343095Y1616788D03*
Y1604876D03*
Y1611796D03*
X355155Y1604876D03*
Y1611796D03*
X350199Y1604876D03*
Y1611796D03*
X355155Y1616788D03*
X350199D03*
X366775Y127662D03*
X356250Y216342D03*
X358209Y208169D03*
X357764Y314234D03*
X363750Y369362D03*
X371370Y373622D03*
X364014Y382304D03*
X359930Y732985D03*
X360927Y757665D03*
X361043Y1306506D03*
X363643D03*
X367939Y1303319D03*
Y1305919D03*
Y1308519D03*
X358373Y1322757D03*
Y1319650D03*
X361043Y1314306D03*
Y1316906D03*
X362393Y1319406D03*
X361043Y1309106D03*
Y1311706D03*
X363643Y1316906D03*
Y1314306D03*
Y1309106D03*
Y1311706D03*
X358273Y1325853D03*
X370874Y1335876D03*
X367490Y1332568D03*
X356959Y1580678D03*
X361915D03*
X356959Y1575592D03*
X361915D03*
X369019Y1575686D03*
Y1580678D03*
X356959Y1592590D03*
X361915D03*
X356959Y1587598D03*
X361915D03*
X367215Y1599790D03*
X362259D03*
X369019Y1587598D03*
Y1592590D03*
X367215Y1616788D03*
X362259D03*
X367215Y1604876D03*
Y1611796D03*
X362259Y1604876D03*
Y1611796D03*
X376245Y212862D03*
Y217362D03*
Y221362D03*
Y225362D03*
X386120Y220322D03*
X385720Y323761D03*
X376500Y362736D03*
X373957Y1306208D03*
X381757D03*
X379157D03*
X376557D03*
X384357D03*
X387557D03*
X375951Y1321671D03*
X380911Y1316071D03*
X378431D03*
Y1321671D03*
X380911D03*
X373957Y1309315D03*
X381957Y1312422D03*
X381757Y1309315D03*
X379357Y1312422D03*
X379157Y1309315D03*
X376557D03*
X375951Y1316071D03*
X380842Y1334095D03*
X383549Y1333998D03*
X383127Y1395610D03*
X381060Y1433622D03*
X380930Y1531402D03*
X384210Y1534152D03*
X387152Y1582659D03*
X373975Y1575686D03*
Y1580678D03*
Y1587598D03*
Y1592590D03*
X379275Y1599884D03*
X374319D03*
X379275Y1604876D03*
Y1611796D03*
X374319Y1604876D03*
Y1611796D03*
X379275Y1616788D03*
X374319D03*
X374690Y1631700D03*
X375550Y1662052D03*
X386824Y1682866D03*
X387760Y1671092D03*
X393830Y62062D03*
X399800Y59662D03*
X403800D03*
X390830Y155833D03*
X388965Y209949D03*
X398720Y318643D03*
X403675Y363081D03*
X391195Y368199D03*
X391101Y380939D03*
X403581Y375880D03*
X390730Y394852D03*
X403570Y388874D03*
X395771Y1303480D03*
X393171D03*
X395771Y1300880D03*
X393171D03*
X395771Y1295680D03*
X393171D03*
X395771Y1298280D03*
X393171D03*
X394521Y1305980D03*
X390501Y1306224D03*
X400067Y1303319D03*
Y1300719D03*
Y1295519D03*
Y1298119D03*
Y1305919D03*
Y1308519D03*
X390401Y1312427D03*
X390501Y1309331D03*
X399673Y1332653D03*
X403130Y1335963D03*
X400919Y1411231D03*
X391370Y1424782D03*
X392108Y1582659D03*
X401812Y1616456D03*
X394910Y1632364D03*
Y1637320D03*
X402246Y1671745D03*
X409535Y49388D03*
X412930Y62572D03*
X413459Y129061D03*
X411434Y163662D03*
X407490Y216912D03*
X412820Y231922D03*
X405478Y236726D03*
X410090Y241932D03*
X420710Y242482D03*
X419023Y381760D03*
X418982Y407847D03*
X416485Y1306208D03*
X419685D03*
X413885D03*
X406085D03*
X411285D03*
X408685D03*
X414085Y1312422D03*
X413885Y1309315D03*
X411485Y1312422D03*
X408685Y1309315D03*
X406085D03*
X411285D03*
X413039Y1316071D03*
X408079D03*
X410559D03*
X413039Y1321671D03*
X408079D03*
X410559D03*
X416099Y1335568D03*
X414617Y1333473D03*
X412465Y1393878D03*
X419974Y1405289D03*
Y1412789D03*
X420474Y1420289D03*
X407125Y1424978D03*
X404475Y1552452D03*
X419002Y1600306D03*
X406526Y1591212D03*
Y1596168D03*
X406768Y1616456D03*
X408700Y1603500D03*
Y1614300D03*
X411910Y1629170D03*
Y1624214D03*
X410232Y1670244D03*
X429535Y49388D03*
X430655Y58677D03*
X433695Y214862D03*
X429395Y232562D03*
X426295Y227862D03*
X422210Y221452D03*
X429395Y236562D03*
Y240562D03*
X425249Y338061D03*
X431503Y376642D03*
X431462Y402729D03*
X422629Y1306224D03*
X432195Y1303319D03*
Y1305919D03*
X425299Y1303480D03*
X426649Y1305980D03*
X427899Y1303480D03*
X425299Y1295680D03*
X427899D03*
X432195Y1295519D03*
Y1298119D03*
X427899Y1298280D03*
X425299D03*
X432195Y1300719D03*
X427899Y1300880D03*
X425299D03*
X432195Y1308519D03*
X422529Y1312427D03*
X422629Y1309331D03*
X434983Y1335924D03*
X431578Y1332560D03*
X427474Y1405289D03*
X434974D03*
Y1412789D03*
X427474Y1420289D03*
X434974D03*
X423958Y1600306D03*
X428099Y1586282D03*
X428941Y1606441D03*
X449535Y49388D03*
X443678Y145710D03*
X445964Y314234D03*
X450400Y338812D03*
X442853Y542519D03*
Y547519D03*
X448613Y1306208D03*
X446013D03*
X443413D03*
X440813D03*
X438213D03*
X451813D03*
X443613Y1312422D03*
X443413Y1309315D03*
X440813D03*
X438213D03*
X446213Y1312422D03*
X446013Y1309315D03*
X440207Y1316071D03*
X445167D03*
X442687D03*
X440207Y1321671D03*
X445167D03*
X442687D03*
X446944Y1335928D03*
X445153Y1334095D03*
X446258Y1441606D03*
X449778D03*
X451910Y1643282D03*
X437562Y1649770D03*
X442518D03*
X469535Y49388D03*
X454568Y78782D03*
X466992Y145888D03*
X458264Y254862D03*
X460300Y303662D03*
X468490Y340572D03*
X469830Y366158D03*
X460323Y510183D03*
X458327Y1303980D03*
X460927D03*
X464427Y1305380D03*
X454757Y1306224D03*
X460927Y1306580D03*
X458327D03*
Y1301380D03*
X460927D03*
X464427Y1300180D03*
Y1302780D03*
X458327Y1296180D03*
X460927D03*
X464427D03*
X458327Y1298780D03*
X460927D03*
X464423Y1308519D03*
X454657Y1312427D03*
X454757Y1309331D03*
X464738Y1333085D03*
X467644Y1335981D03*
X455576Y1409125D03*
Y1417125D03*
Y1420625D03*
Y1427632D03*
Y1424125D03*
X454450Y1433580D03*
X464160Y1587122D03*
X458414Y1624994D03*
Y1629950D03*
X468040Y1654807D03*
X478240Y55935D03*
Y66575D03*
Y61129D03*
X484396Y161364D03*
X475500Y212685D03*
X472800Y299462D03*
X484800Y307362D03*
X476740Y309272D03*
X479740Y300202D03*
X482920Y398060D03*
X479379Y452445D03*
X480741Y1306208D03*
X478141D03*
X475541D03*
X472941D03*
X470341D03*
X483941D03*
X472941Y1309315D03*
X478141D03*
X470341D03*
X478341Y1312422D03*
X475741D03*
X475541Y1309315D03*
X472335Y1316071D03*
X477295D03*
X474815D03*
X472335Y1321671D03*
X477295D03*
X474815D03*
X477162Y1334095D03*
X478909Y1336038D03*
X485236Y1417844D03*
X482741Y1438698D03*
X482742Y1441312D03*
X484333Y1575686D03*
Y1580678D03*
X477229D03*
X472273D03*
Y1575686D03*
X477229D03*
X482529Y1599884D03*
X477573D03*
X484333Y1587598D03*
Y1592590D03*
X472273D03*
X477229D03*
Y1587598D03*
X472273D03*
X482529Y1616788D03*
X477573D03*
Y1611796D03*
X482529D03*
X477573Y1604876D03*
X482529D03*
X472210Y1618626D03*
X485150Y1624942D03*
X477905Y1667242D03*
X489535Y49347D03*
X497002Y88167D03*
X501540Y105152D03*
X498630Y140492D03*
X489980Y250512D03*
X492074Y300306D03*
X497568Y397632D03*
X494193Y550447D03*
X486885Y1306224D03*
X496451Y1306345D03*
X489555Y1303480D03*
X492155D03*
X490905Y1305980D03*
X492155Y1300880D03*
X489555D03*
X486785Y1312427D03*
X486885Y1309331D03*
X496220Y1322440D03*
X496451Y1316745D03*
Y1308945D03*
Y1314145D03*
Y1311545D03*
X499458Y1349468D03*
X499818Y1385027D03*
X499859Y1393027D03*
X490307Y1421499D03*
X491156Y1438713D03*
X499541Y1438698D03*
X491142Y1441312D03*
X499542D03*
X501349Y1580678D03*
X496393D03*
Y1575686D03*
X501349D03*
X489289D03*
Y1580678D03*
X501693Y1599884D03*
X494589D03*
X489633D03*
X501349Y1592590D03*
X496393D03*
X501349Y1587598D03*
X496393D03*
X489289D03*
Y1592590D03*
X501693Y1611796D03*
Y1604876D03*
Y1616788D03*
X489633Y1611796D03*
X494589Y1604876D03*
X489633D03*
X494589Y1611796D03*
X489633Y1616788D03*
X494589D03*
X487340Y1641352D03*
X517902Y69508D03*
X510815D03*
X503100Y78402D03*
X510030Y78412D03*
X504980Y101752D03*
X503290Y140492D03*
X507360D03*
X514850Y168443D03*
X504075Y231262D03*
X508000Y237862D03*
X505900Y311562D03*
X510740Y332592D03*
X513173Y408740D03*
X514425Y489112D03*
Y495112D03*
X509493Y539819D03*
X513025Y615742D03*
X516069Y1319634D03*
X502469D03*
Y1322741D03*
X512869Y1319634D03*
X510269D03*
X507669D03*
X505069D03*
X507669Y1322741D03*
X505069D03*
X510269D03*
X504463Y1329497D03*
Y1335097D03*
X509423Y1329497D03*
X506943D03*
X509423Y1335097D03*
X506943D03*
X510469Y1325848D03*
X507869D03*
X509382Y1347521D03*
X511149Y1349468D03*
X505018Y1385027D03*
X502418D03*
X505059Y1393027D03*
X502459D03*
X508001Y1438669D03*
X507942Y1441312D03*
X508453Y1575686D03*
X513409D03*
X508453Y1580678D03*
X513409D03*
X513753Y1599884D03*
X506649D03*
X508453Y1587598D03*
X513409D03*
X508453Y1592590D03*
X513409D03*
X513753Y1616788D03*
Y1604876D03*
Y1611796D03*
X506649D03*
Y1604876D03*
Y1616788D03*
X518606Y23797D03*
X532075Y69508D03*
Y57894D03*
X524988Y69508D03*
X529239Y99997D03*
Y92911D03*
X528400Y104225D03*
Y114275D03*
X527823Y131802D03*
Y149802D03*
X527278Y164726D03*
X529480Y183921D03*
X536127Y247652D03*
X523660Y323222D03*
X535220Y383552D03*
X528145Y408705D03*
X518735Y452442D03*
X526852Y511331D03*
X527042Y505830D03*
X526853Y516817D03*
X523033Y1319406D03*
X519013Y1319650D03*
Y1322757D03*
X527645Y1326076D03*
X528579Y1329143D03*
X528377Y1335982D03*
X518913Y1325853D03*
X528579Y1342143D03*
Y1344743D03*
X534597Y1345539D03*
Y1342432D03*
X528975Y1369724D03*
X532573Y1575686D03*
Y1580678D03*
X520513D03*
X525469D03*
X520513Y1575686D03*
X525469D03*
X525813Y1599884D03*
X530769D03*
X518709D03*
X532573Y1587598D03*
Y1592590D03*
X525469D03*
X520513D03*
Y1587598D03*
X525469D03*
X525813Y1611796D03*
X530769D03*
X525813Y1604876D03*
X530769D03*
Y1616788D03*
X525813D03*
X518709D03*
Y1604876D03*
Y1611796D03*
X548609Y32500D03*
X546248Y69508D03*
X539161D03*
Y57894D03*
X546234Y77443D03*
X542620Y103352D03*
X537360Y120522D03*
X550545Y147302D03*
X542798Y202646D03*
X535630Y306602D03*
X543035Y441005D03*
X538120Y463137D03*
X544813Y1322668D03*
X542213D03*
X538293D03*
X535693D03*
X548197Y1342432D03*
X539997Y1348646D03*
X542397Y1345539D03*
X542597Y1348646D03*
X537197Y1342432D03*
X539797D03*
X542397D03*
X544997D03*
X537197Y1345539D03*
X539797D03*
X539071Y1352295D03*
X536591D03*
X541551D03*
Y1357895D03*
X542256Y1369935D03*
X536591Y1357895D03*
X539071D03*
X549589Y1580678D03*
X544633D03*
X549589Y1575592D03*
X544633D03*
X537529Y1575686D03*
Y1580678D03*
X549933Y1599790D03*
X537873Y1599884D03*
X542829D03*
X549589Y1592590D03*
X544633D03*
X549589Y1587598D03*
X544633D03*
X537529D03*
Y1592590D03*
X549933Y1611796D03*
Y1604876D03*
Y1616788D03*
X542829D03*
X537873D03*
Y1604876D03*
X542829D03*
X537873Y1611796D03*
X542829D03*
X560421Y69508D03*
X553335D03*
X553320Y77443D03*
X564988Y118670D03*
X555545Y134340D03*
X565500Y145252D03*
X555220Y167937D03*
X553657Y193862D03*
X564944Y252173D03*
X553536Y307527D03*
X569080Y414002D03*
X559300Y422732D03*
X558933Y1323658D03*
Y1326258D03*
X556563Y1337918D03*
X553963D03*
X558933Y1328938D03*
X556563Y1335318D03*
Y1332718D03*
X558933Y1331538D03*
X553963Y1335318D03*
Y1332718D03*
X555313Y1340418D03*
X551141Y1345555D03*
X551041Y1348651D03*
X551141Y1342448D03*
X555372Y1343037D03*
X561070Y1346174D03*
X556693Y1575686D03*
X561649D03*
X556693Y1580678D03*
X561649D03*
X561993Y1599884D03*
X554889Y1599790D03*
X556693Y1587598D03*
X561649D03*
Y1592590D03*
X556693D03*
X561993Y1616788D03*
Y1604876D03*
Y1611796D03*
X554889D03*
Y1604876D03*
Y1616788D03*
X567673Y130542D03*
X581175Y164717D03*
X569965Y161232D03*
X579481Y202378D03*
Y210378D03*
X568149Y217916D03*
X580712Y215877D03*
X581645Y233362D03*
X569668Y229812D03*
X578711Y230109D03*
X578509Y265132D03*
X569880Y300992D03*
X580400Y302402D03*
X582436Y361032D03*
X570200Y372229D03*
X570760Y451710D03*
X571990Y501046D03*
X571700Y552200D03*
X580813Y1575686D03*
Y1580678D03*
X573709D03*
X568753D03*
Y1575686D03*
X573709D03*
X579009Y1599884D03*
X574053D03*
X566949D03*
X580813Y1587598D03*
Y1592590D03*
X573709D03*
X568753D03*
X573709Y1587598D03*
X568753D03*
X574053Y1616788D03*
X579009D03*
Y1611796D03*
X574053D03*
X579009Y1604876D03*
X574053D03*
X566949Y1616788D03*
Y1604876D03*
Y1611796D03*
X591395Y132142D03*
X595220Y140922D03*
X588000D03*
X592710Y156342D03*
X593248Y159480D03*
X598295Y171862D03*
X596581Y184849D03*
X590337Y177604D03*
X598760Y203712D03*
X593966Y229965D03*
X592039Y252202D03*
X588577Y285862D03*
X586820Y314662D03*
X597820Y317062D03*
X592920Y326362D03*
X591720Y430787D03*
X599220Y444362D03*
X593545Y488212D03*
X594090Y505107D03*
X589260Y519421D03*
X594240Y511953D03*
X593675Y534702D03*
X589989Y745475D03*
X597829Y1580678D03*
X592873D03*
X597829Y1575686D03*
X592873D03*
X585769D03*
Y1580678D03*
X598173Y1599884D03*
X586113D03*
X591069D03*
X597829Y1592590D03*
X592873D03*
X597829Y1587598D03*
X592873D03*
X585769D03*
Y1592590D03*
X598173Y1616788D03*
Y1611796D03*
Y1604876D03*
X586113D03*
X591069D03*
X586113Y1611796D03*
X591069D03*
Y1616788D03*
X586113D03*
X615185Y69508D03*
X603374D03*
X601050Y100008D03*
X610104Y119342D03*
X602306Y143077D03*
X602430Y153862D03*
X606260Y161652D03*
X615572Y173942D03*
X615573Y181984D03*
X614531Y200378D03*
X611030Y188372D03*
X603340Y208142D03*
X614531Y209878D03*
X609456Y204994D03*
X606719Y254966D03*
X609844Y330407D03*
X608830Y374302D03*
X605830Y402782D03*
X604779Y423862D03*
X600351Y461862D03*
X614220Y452862D03*
X610820Y472862D03*
X603779Y486922D03*
X606200Y514862D03*
X609520Y515162D03*
X614086Y537624D03*
X614000Y550800D03*
X603317Y738415D03*
X614660Y739553D03*
X602027Y761445D03*
X612407Y769485D03*
X609889Y1575686D03*
X604933D03*
X609889Y1580678D03*
X604933D03*
X615189Y1599884D03*
X610233D03*
X603129D03*
X609889Y1587598D03*
X604933D03*
X609889Y1592590D03*
X604933D03*
X615189Y1604876D03*
X610233D03*
X615189Y1611796D03*
X610233D03*
X615189Y1616788D03*
X610233D03*
X603129D03*
Y1611796D03*
Y1604876D03*
X631546Y85024D03*
X618460Y119342D03*
X631300Y167872D03*
X628195Y178414D03*
X628194Y170372D03*
X630818Y191248D03*
X625862D03*
X620030Y188782D03*
X627645Y236862D03*
X629564Y256277D03*
X623150Y273172D03*
X625800Y311912D03*
X628294Y317007D03*
X623580Y336429D03*
X629248Y436972D03*
X629220Y472862D03*
Y477862D03*
Y467862D03*
Y482862D03*
X626207Y747585D03*
X618114Y1258470D03*
X629053Y1575686D03*
Y1580678D03*
X621949D03*
X616993D03*
X621949Y1575686D03*
X616993D03*
X622293Y1599884D03*
X627249D03*
X629053Y1587598D03*
Y1592590D03*
X621949D03*
X616993D03*
X621949Y1587598D03*
X616993D03*
X627249Y1616788D03*
X622293D03*
Y1611796D03*
X627249D03*
X622293Y1604876D03*
X627249D03*
X646440Y43632D03*
X632463Y43302D03*
X645150Y69508D03*
X645350Y60612D03*
X632640Y107532D03*
X637500Y110362D03*
X642480Y184862D03*
X645876Y296231D03*
X633138Y296766D03*
X645528Y308623D03*
X645807Y304291D03*
X647200Y354300D03*
X643736Y457214D03*
X644245Y472862D03*
X644220Y467862D03*
X644245Y482862D03*
X636960Y516002D03*
X646069Y1580678D03*
X641113D03*
X646069Y1575592D03*
X641113D03*
X634009Y1575686D03*
Y1580678D03*
X646413Y1599790D03*
X639309Y1599884D03*
X634353D03*
X646069Y1592590D03*
X641113D03*
X646069Y1587598D03*
X641113D03*
X634009D03*
Y1592590D03*
X646413Y1616788D03*
Y1611796D03*
Y1604876D03*
X639309D03*
X634353D03*
X639309Y1611796D03*
X634353D03*
Y1616788D03*
X639309D03*
X641057Y1648659D03*
X645407Y1660425D03*
X639745Y1714362D03*
X648290Y1720052D03*
X639745Y1726362D03*
X661550Y45133D03*
X654464D03*
X652153Y98105D03*
X652680Y89712D03*
X651579Y102703D03*
X659000Y89262D03*
X651980Y133822D03*
X650790Y144982D03*
X660690Y408162D03*
X660720Y404362D03*
X653800Y498740D03*
X662282Y1386432D03*
X654606Y1431203D03*
X653173Y1575686D03*
X658129D03*
X653173Y1580678D03*
X658129D03*
X663429Y1599884D03*
X658473D03*
X651369Y1599790D03*
X653173Y1587598D03*
X658129D03*
X653173Y1592590D03*
X658129D03*
X663429Y1604876D03*
X658473D03*
X663429Y1611796D03*
X658473D03*
Y1616788D03*
X663429D03*
X651369D03*
Y1611796D03*
Y1604876D03*
X663043Y1647557D03*
X655307Y1647436D03*
X663118Y1659557D03*
X663145Y1664862D03*
Y1676862D03*
X656973Y1698727D03*
X652712Y1686275D03*
X672005Y44119D03*
X668800Y45262D03*
X666406Y69508D03*
X675225Y58108D03*
X673750Y77692D03*
X673690Y200672D03*
X673300Y211332D03*
X667020Y225762D03*
X680600Y375462D03*
X668329Y411714D03*
X677295Y404362D03*
X677195Y408262D03*
X674628Y414864D03*
Y443210D03*
X671479Y430612D03*
Y462108D03*
X668329Y481006D03*
X675220Y503837D03*
X680220D03*
X675220Y516852D03*
X671607Y742835D03*
X668096Y1360822D03*
X677137Y1384311D03*
X674537D03*
X671937D03*
X669337D03*
X677137Y1387418D03*
X674537D03*
X671937D03*
X669337D03*
X664782Y1383832D03*
Y1381232D03*
Y1378632D03*
Y1386432D03*
X679737Y1384311D03*
X677337Y1390525D03*
X674737D03*
X676250Y1399757D03*
X673820D03*
X671350D03*
X676250Y1394157D03*
X673820D03*
X671350D03*
X666425Y1414200D03*
X676312Y1411554D03*
X667926Y1547018D03*
X679192Y1564252D03*
X678515Y1573910D03*
X676648Y1657380D03*
X671620Y1670862D03*
X674195Y1708362D03*
X669120Y1718862D03*
X674195Y1732362D03*
X696838Y45112D03*
X686854Y43701D03*
X692380Y43532D03*
X682941Y69982D03*
X687050Y79212D03*
X685230Y76952D03*
X683820Y79192D03*
X682890Y72642D03*
X684953Y104968D03*
X694390Y133682D03*
X684520Y152482D03*
X688520D03*
X692520D03*
X686760Y222912D03*
X685600Y375462D03*
X690600D03*
X695600D03*
X688220Y388362D03*
X697220Y404362D03*
X697120Y408262D03*
X684077Y414864D03*
X680928Y424313D03*
X696676Y436911D03*
X693526Y443210D03*
Y440061D03*
Y436911D03*
X690376Y440061D03*
Y433761D03*
X693526Y452659D03*
Y449510D03*
X696676Y455809D03*
X693526D03*
X690376Y452659D03*
Y458959D03*
X696676Y477856D03*
X684077D03*
X680928Y468407D03*
X690220Y516852D03*
X684357Y742345D03*
X692784Y1298845D03*
X686426Y1360822D03*
X695022Y1361990D03*
X696462Y1386122D03*
X682937Y1384311D03*
X685881Y1384327D03*
Y1387434D03*
X691351Y1380922D03*
X688751D03*
X691240Y1383522D03*
X693851D03*
Y1378322D03*
Y1380922D03*
X691351Y1378322D03*
X688751D03*
X693851Y1386122D03*
X696462Y1378322D03*
Y1383522D03*
Y1380922D03*
X696272Y1404560D03*
X685850Y1390557D03*
X685015Y1438475D03*
X696940Y1437955D03*
X689875Y1577913D03*
X689128Y1652262D03*
X692595Y1670862D03*
X701838Y45112D03*
X700610Y57782D03*
X700741Y83050D03*
X706673Y122762D03*
X703520Y122540D03*
X704880Y133643D03*
X701926Y166535D03*
Y178346D03*
Y184252D03*
Y172441D03*
Y190157D03*
Y196063D03*
Y201968D03*
Y207874D03*
Y213779D03*
Y219685D03*
X700600Y375462D03*
X705600D03*
X706125Y421163D03*
X709274Y436911D03*
X706125Y440061D03*
Y436911D03*
X699825Y440061D03*
Y436911D03*
X712424Y443210D03*
Y440061D03*
Y436911D03*
Y455809D03*
X709274D03*
X706125D03*
Y452659D03*
X699825Y455809D03*
Y452659D03*
X712424D03*
Y449510D03*
X709274Y477856D03*
X699825Y468407D03*
X711220Y516852D03*
X705220D03*
X698600Y530700D03*
X701917Y742865D03*
X703755Y1290545D03*
X708795Y1303701D03*
X698094Y1361947D03*
X706239Y1360822D03*
X699062Y1380922D03*
Y1383522D03*
Y1378322D03*
X707480Y1384311D03*
X710080D03*
X707480Y1387418D03*
X710080D03*
X701662Y1380922D03*
Y1383522D03*
Y1378322D03*
X699062Y1386122D03*
X701662D03*
X712680Y1384311D03*
Y1387418D03*
X709493Y1399757D03*
Y1394157D03*
X712880Y1390525D03*
X711963Y1399757D03*
Y1394157D03*
X699262Y1413970D03*
X704568Y1414119D03*
X706680Y1437535D03*
X701730Y1437855D03*
X711440Y1436905D03*
X702112Y1583683D03*
X709111Y1618842D03*
X697595Y1658862D03*
X704433Y1657964D03*
X697770Y1680810D03*
X714015Y-27612D03*
X720308Y-26403D03*
X714015Y-21457D03*
Y-17583D03*
X714030Y-15068D03*
X714015Y-11428D03*
X714030Y-25097D03*
X720308Y-16374D03*
X714015Y-7554D03*
X714030Y-5039D03*
X720308Y-6345D03*
X728980Y39872D03*
X728028Y101968D03*
X728023Y98058D03*
X728028Y105468D03*
X727720Y356362D03*
X725220Y380787D03*
X715600Y375462D03*
X718220Y388362D03*
X715220Y404362D03*
X715120Y408262D03*
X725022Y414864D03*
X715574Y433761D03*
Y458959D03*
X728172Y449510D03*
X725022Y477856D03*
X722720Y521362D03*
X729200Y588952D03*
X713836Y1283689D03*
X724969Y1360822D03*
X729443Y1361224D03*
X726694Y1381583D03*
Y1378983D03*
X715280Y1384311D03*
X717880D03*
X715280Y1387418D03*
X721080Y1384311D03*
X724024Y1384327D03*
Y1387434D03*
X728044Y1384083D03*
X729294Y1381583D03*
Y1378983D03*
X715480Y1390525D03*
X723993Y1390557D03*
X714393Y1399757D03*
Y1394157D03*
X714455Y1411554D03*
X718230Y1600372D03*
X725378Y1614503D03*
X719770Y1614590D03*
X715780D03*
X722040Y1623970D03*
X713791Y1629816D03*
X721345Y1647300D03*
X716140Y1649895D03*
X726830Y1655380D03*
X724500Y1676500D03*
X744987Y49062D03*
X742840Y39832D03*
X736790D03*
X745130Y69508D03*
X738043D03*
X730957D03*
X731330Y60712D03*
X730820Y84062D03*
X737623Y98858D03*
X734523Y98758D03*
X735733Y111988D03*
X733220Y388362D03*
X737621Y411714D03*
X743720Y404362D03*
X743820Y408262D03*
X731322Y430612D03*
Y462108D03*
X737621Y481006D03*
X730070Y506212D03*
X744630Y506529D03*
X745220Y530362D03*
X737299Y766887D03*
X737784Y1360017D03*
X730752Y1384080D03*
X731794Y1381583D03*
Y1378983D03*
X732238Y1388343D03*
X738810Y1396665D03*
X741540Y1396585D03*
X739170Y1405655D03*
X741670Y1405675D03*
X738170Y1414185D03*
X740760Y1414165D03*
X758606Y23797D03*
X747487Y49062D03*
X752720Y59002D03*
X754219Y75707D03*
X754633Y108288D03*
Y105288D03*
X762172Y123898D03*
X754290Y286632D03*
X755200Y296062D03*
X759940Y438232D03*
X758420Y447662D03*
X751220Y530362D03*
X753137Y766625D03*
X757779Y1390645D03*
X757542Y1420684D03*
X761770Y1695347D03*
X765606Y44894D03*
X769474Y75360D03*
X765858Y87340D03*
X762368Y84088D03*
X769284Y103895D03*
X767061Y99959D03*
X767045Y95960D03*
X767028Y91490D03*
X776730Y117479D03*
X773943Y114633D03*
X771131Y111788D03*
X769775Y107977D03*
X766769Y140138D03*
X771774Y167518D03*
X773220Y296262D03*
X772866Y311558D03*
X776100Y375100D03*
X766195Y418212D03*
X765315Y464862D03*
Y488862D03*
X772220Y530362D03*
X775317Y764025D03*
X763747Y764335D03*
X768520Y1379962D03*
X768620Y1392762D03*
X767820Y1410262D03*
X785095Y49388D03*
X780617Y296345D03*
X779120Y306162D03*
X794600Y360600D03*
X787925Y387900D03*
X781195Y418212D03*
X791590Y417050D03*
X780020Y438287D03*
X781410Y431822D03*
X780340Y468982D03*
Y474862D03*
X793673Y512862D03*
X792720Y589862D03*
X789720Y581862D03*
X783100Y593582D03*
X788225Y1388683D03*
X805095Y49388D03*
X797443Y271469D03*
X806300Y279662D03*
X809700Y273562D03*
X795190Y298572D03*
X798620Y312773D03*
X809800Y360600D03*
X802200D03*
X806588Y351097D03*
X799800Y368700D03*
X802220Y393727D03*
X803150Y408512D03*
X795600Y402500D03*
X799458Y431217D03*
X795370Y474862D03*
X801567Y512942D03*
X798720Y585362D03*
X798220Y597362D03*
X808860Y603802D03*
X797720Y617862D03*
X799637Y763625D03*
X825095Y49388D03*
X821118Y134632D03*
X825698Y139062D03*
X813900Y269698D03*
X827403Y286625D03*
X816420Y287062D03*
X813855Y354008D03*
X820936Y356956D03*
X824980Y405260D03*
Y409260D03*
X821720Y428437D03*
X818500Y451700D03*
X816500Y476800D03*
X821720Y519082D03*
X815040Y590772D03*
X814800Y760922D03*
X822442Y762369D03*
X814234Y1340465D03*
X830975Y2388D03*
X830990Y4903D03*
X837268Y3597D03*
X830975Y22446D03*
Y8543D03*
Y12417D03*
X830990Y14932D03*
X830975Y18572D03*
X837268Y13626D03*
X830990Y24961D03*
X837268Y23655D03*
X836126Y62681D03*
X837791Y85186D03*
X831297Y104206D03*
X842864Y110296D03*
X830339Y228143D03*
X829680Y264580D03*
X836210Y272452D03*
X829720Y277562D03*
X829800Y271562D03*
X829320Y296762D03*
X834400Y283862D03*
X834900Y293462D03*
X828222Y359960D03*
X835471Y363003D03*
X843133Y366158D03*
X833300Y386500D03*
X838784Y392880D03*
X839200Y434300D03*
X841300Y446800D03*
X842600Y477200D03*
X842341Y474241D03*
X841795Y492862D03*
X829745Y498082D03*
X834635Y515447D03*
X830480Y527817D03*
X831700Y596962D03*
X836847Y762495D03*
X828799Y1336870D03*
X828910Y1331756D03*
Y1341725D03*
X845095Y49388D03*
X854107Y91232D03*
X850280Y113852D03*
X853828Y265057D03*
X854333Y276117D03*
X854338Y280027D03*
Y283527D03*
X852800Y288562D03*
X853200Y297462D03*
X856700Y304862D03*
X848000Y374622D03*
X851396Y369614D03*
X859734Y373032D03*
X857560Y417762D03*
X844200Y418800D03*
X847830Y443892D03*
X843810Y453322D03*
X846700Y473000D03*
X848710Y505641D03*
X860345Y522162D03*
X856698Y594011D03*
X853200Y751062D03*
X854687Y761685D03*
X865095Y49388D03*
X868187Y72006D03*
X860937Y71877D03*
X861350Y61672D03*
X871980Y199500D03*
X860833Y276817D03*
X863933Y276917D03*
X862043Y290047D03*
X867922Y376450D03*
X875922Y379793D03*
X870700Y382415D03*
Y390620D03*
Y394620D03*
X871320Y416752D03*
X862620Y503162D03*
Y499062D03*
X860345Y513062D03*
X892214Y141891D03*
X878220Y192055D03*
X880943Y283347D03*
Y286347D03*
X880473Y329370D03*
X883472Y382910D03*
X886362Y534380D03*
X886500Y739162D03*
X878152Y876760D03*
X889439Y1437938D03*
X903930Y202885D03*
X903980Y210355D03*
X903930Y217059D03*
X903980Y224529D03*
X893500Y339062D03*
X900061Y510962D03*
X906127Y496343D03*
X900061Y517898D03*
X893298Y534380D03*
X899462Y533380D03*
X906398D03*
X897000Y891895D03*
X894375Y913692D03*
X912214Y141891D03*
X917680Y174999D03*
Y177999D03*
Y171999D03*
X909386Y195925D03*
Y203011D03*
Y210098D03*
Y217185D03*
Y224271D03*
Y231358D03*
X919279Y461244D03*
X920682Y494586D03*
X920980Y503393D03*
X911720Y511662D03*
X911626Y523430D03*
X918562D03*
X924647Y526808D03*
Y533744D03*
X924600Y824262D03*
X922320Y1660953D03*
X932214Y141891D03*
X927133Y189386D03*
X925320Y203399D03*
X940709Y460438D03*
X938437Y455454D03*
X932724Y455538D03*
X926215Y461244D03*
X929234Y494915D03*
X938588Y485197D03*
X929698Y503595D03*
X928231Y530479D03*
X936273Y530478D03*
X927200Y811462D03*
X931496Y962082D03*
X929221Y1014664D03*
X927122Y1661380D03*
X938220Y1661062D03*
X952214Y141891D03*
X949710Y198289D03*
X941634Y199051D03*
Y193451D03*
X951354Y209437D03*
Y203837D03*
X944880Y210959D03*
Y216559D03*
Y230697D03*
Y225097D03*
X954874Y232071D03*
X954904Y225741D03*
X942827Y422743D03*
Y429679D03*
X945800Y432463D03*
Y439399D03*
X946492Y460410D03*
X956188Y495384D03*
Y502320D03*
X948495Y502784D03*
X948693Y509497D03*
X956188Y509484D03*
Y516420D03*
X952622Y529364D03*
X956700Y786862D03*
X941400Y810062D03*
X946100Y1661100D03*
X972214Y141891D03*
X963520Y214699D03*
X960703Y212668D03*
X971471Y242358D03*
X965792Y350959D03*
X965420Y365719D03*
X963856Y394202D03*
X960059Y387004D03*
X972986Y393171D03*
X970054Y478773D03*
Y485709D03*
X966720Y511362D03*
X960620Y509462D03*
X972379Y509303D03*
X959558Y529364D03*
X962162Y535130D03*
X969098D03*
X958755Y657078D03*
X963520Y665062D03*
X958866Y662378D03*
X959100Y789862D03*
X975688Y152950D03*
Y149950D03*
X985016Y344659D03*
X974791Y339990D03*
X986182Y361062D03*
X979380Y373082D03*
X988159Y409068D03*
X983760Y424292D03*
X980092Y421289D03*
X983720Y512362D03*
X976283Y534226D03*
X994553Y365711D03*
X997598Y382952D03*
X997612Y391804D03*
X1006221Y382945D03*
X997900Y400720D03*
X993387Y429827D03*
X999720Y512862D03*
X991097Y529902D03*
X996675Y1286985D03*
X1012214Y141826D03*
X1022002Y267342D03*
Y270142D03*
X1013500Y344900D03*
X1015638Y382968D03*
X1015637Y391334D03*
X1006589Y392017D03*
X1006750Y401010D03*
X1015657Y401013D03*
X1021259Y420548D03*
X1007249Y422682D03*
X1017511Y430038D03*
X1008720Y498362D03*
X1019145Y503823D03*
X1011720Y589362D03*
X1018720Y592362D03*
X1021720Y601862D03*
X1010630Y748741D03*
X1023407Y-27681D03*
X1029700Y-26472D03*
X1023407Y-32055D03*
X1029700Y-37001D03*
X1023407Y-17652D03*
X1023422Y-15137D03*
X1023407Y-11497D03*
X1029700Y-16443D03*
X1023422Y-25166D03*
X1023407Y-21526D03*
X1029700Y3615D03*
X1023422Y4921D03*
X1023407Y2406D03*
X1023422Y-5108D03*
X1023407Y-7623D03*
Y-1468D03*
X1029700Y-6414D03*
X1023407Y22464D03*
Y18590D03*
Y8561D03*
X1023422Y14950D03*
X1023407Y12435D03*
X1029700Y13644D03*
Y23673D03*
X1023422Y24979D03*
X1038609Y49388D03*
X1027520Y122732D03*
X1037650Y128842D03*
X1023220Y187574D03*
X1031502Y267342D03*
X1028202D03*
X1025102D03*
X1033133Y272564D03*
X1031502Y270142D03*
X1029833Y272564D03*
X1026733D03*
X1023633D03*
X1028202Y270142D03*
X1025102D03*
X1029094Y383070D03*
Y387872D03*
X1033860Y400802D03*
X1038294Y506504D03*
X1027190Y510672D03*
X1029220Y520032D03*
X1043629Y375078D03*
Y372578D03*
X1049100Y390162D03*
X1046156Y442699D03*
X1058609Y49388D03*
X1066820Y151632D03*
X1072310Y364422D03*
X1078609Y49388D03*
X1075100Y55682D03*
X1084146Y67102D03*
X1078270Y93462D03*
X1077270Y369061D03*
Y374131D03*
Y379251D03*
X1073724Y476867D03*
X1081906Y472577D03*
X1076739Y506461D03*
X1077751Y522235D03*
X1098609Y49388D03*
X1097794Y67881D03*
X1102480Y133722D03*
X1105553Y356475D03*
X1096477Y744385D03*
X1102930Y1668690D03*
X1092072Y1734244D03*
X1118609Y49388D03*
X1118110Y1398010D03*
X1109118Y1526046D03*
X1116338Y1711380D03*
X1113055Y1718338D03*
X1132856Y52926D03*
X1129948Y66786D03*
X1127788Y1397126D03*
X1131629Y1420615D03*
X1129029D03*
X1134229D03*
X1123674Y1414936D03*
X1121174D03*
X1123674Y1417536D03*
Y1420136D03*
X1121174Y1417536D03*
Y1420136D03*
X1131629Y1423722D03*
X1129029D03*
X1134229D03*
X1123674Y1422736D03*
X1121174D03*
X1131042Y1436061D03*
X1135942D03*
X1133512D03*
X1131042Y1430461D03*
X1135942D03*
X1133512D03*
X1134429Y1426829D03*
X1136004Y1447858D03*
X1126117Y1450504D03*
X1127008Y1550285D03*
X1133780Y1550301D03*
X1138609Y49388D03*
X1145603Y73679D03*
X1140465Y379592D03*
X1142302Y366532D03*
X1142790Y611122D03*
X1146118Y1397126D03*
X1150843Y1415126D03*
X1148243D03*
X1150843Y1417726D03*
X1148243D03*
X1150732Y1420326D03*
X1142629Y1420615D03*
X1145573Y1420631D03*
X1139429Y1420615D03*
X1136829D03*
X1145573Y1423738D03*
X1136829Y1423722D03*
X1145542Y1426861D03*
X1137029Y1426829D03*
X1145108Y1476732D03*
X1158609Y49388D03*
X1156790Y373231D03*
X1153467Y586462D03*
X1153490Y610322D03*
X1165931Y1397126D03*
X1154714Y1398295D03*
X1157786Y1398252D03*
X1167172Y1420615D03*
X1153913Y1420606D03*
Y1415406D03*
Y1418006D03*
X1159124D03*
Y1420606D03*
Y1415406D03*
X1161724D03*
Y1420606D03*
Y1418006D03*
X1156524Y1415406D03*
Y1420606D03*
Y1418006D03*
X1167172Y1423722D03*
X1153913Y1423206D03*
X1159124D03*
X1161724D03*
X1156524D03*
X1155964Y1440864D03*
X1164260Y1450423D03*
X1158954Y1450274D03*
X1168192Y1604130D03*
X1152950Y1616470D03*
X1165950Y1617729D03*
X1152930Y1633880D03*
X1174980Y585632D03*
X1174880Y592652D03*
X1173990Y602192D03*
X1183230Y739102D03*
X1184661Y1397126D03*
X1183716Y1420631D03*
X1180772Y1420615D03*
X1174972D03*
X1177572D03*
X1172372D03*
X1169772D03*
X1183716Y1423738D03*
X1174972Y1423722D03*
X1172372D03*
X1169772D03*
X1174085Y1436061D03*
Y1430461D03*
X1171655Y1436061D03*
X1169185D03*
X1171655Y1430461D03*
X1169185D03*
X1183685Y1426861D03*
X1175172Y1426829D03*
X1172572D03*
X1174147Y1447858D03*
X1179922Y1550285D03*
X1184501Y1606521D03*
X1185030Y1633010D03*
X1182470Y1618914D03*
X1172530Y1623020D03*
X1176900Y1627510D03*
X1198609Y49388D03*
X1188720Y56755D03*
X1191700Y56822D03*
X1185500Y101400D03*
X1190700Y99000D03*
X1197627Y132859D03*
X1196100Y188962D03*
X1193500D03*
X1192600Y217662D03*
X1193000Y204486D03*
X1195500D03*
X1195100Y217662D03*
X1194840Y240672D03*
X1199027Y588714D03*
X1189135Y1397529D03*
X1187736Y1420387D03*
X1188986Y1415287D03*
Y1417887D03*
X1186386Y1415287D03*
Y1417887D03*
X1191486Y1415287D03*
Y1417887D03*
X1190444Y1420384D03*
X1194750Y1424672D03*
X1197700Y1432672D03*
X1191930Y1424647D03*
X1198010Y1441902D03*
X1198880Y1457162D03*
X1197181Y1563587D03*
X1195994Y1580678D03*
Y1575686D03*
X1200950Y1580678D03*
Y1575686D03*
X1201294Y1599884D03*
X1195994Y1592590D03*
Y1587598D03*
X1200950Y1592590D03*
Y1587598D03*
X1201294Y1604876D03*
Y1611796D03*
Y1616788D03*
X1213026Y56742D03*
X1201800Y94600D03*
X1204800Y108900D03*
X1206900Y115900D03*
X1214573Y148909D03*
X1204420Y195362D03*
X1210084Y224362D03*
X1207220Y247148D03*
X1217720Y249862D03*
X1204880Y754032D03*
X1213010Y1575686D03*
X1208054D03*
X1213010Y1580678D03*
X1208054D03*
X1206250Y1599884D03*
X1213354D03*
X1213010Y1587598D03*
X1208054D03*
X1213010Y1592590D03*
X1208054D03*
X1206250Y1604876D03*
Y1611796D03*
Y1616788D03*
X1213354D03*
Y1604876D03*
Y1611796D03*
X1213980Y1676500D03*
X1218609Y49388D03*
X1228420Y58862D03*
X1230250Y89450D03*
X1223720Y217862D03*
Y205862D03*
X1232000Y244332D03*
Y248332D03*
X1225070Y1580678D03*
Y1575686D03*
X1220114D03*
Y1580678D03*
X1232174D03*
Y1575686D03*
X1218310Y1599884D03*
X1225414D03*
X1230370D03*
X1225070Y1592590D03*
X1220114D03*
X1225070Y1587598D03*
X1220114D03*
X1232174D03*
Y1592590D03*
X1218310Y1616788D03*
Y1604876D03*
Y1611796D03*
X1225414D03*
Y1604876D03*
X1230370Y1611796D03*
Y1604876D03*
X1225414Y1616788D03*
X1230370D03*
X1238609Y49388D03*
X1239907Y95008D03*
X1243808Y116832D03*
X1247333Y121999D03*
X1236520Y213462D03*
X1246444Y256098D03*
X1252040Y306480D03*
X1237130Y1575686D03*
Y1580678D03*
X1244234D03*
X1249190D03*
X1244234Y1575686D03*
X1249190D03*
X1242430Y1599884D03*
X1237474D03*
X1249534D03*
X1237130Y1587598D03*
Y1592590D03*
X1249190D03*
X1244234D03*
Y1587598D03*
X1249190D03*
X1242430Y1616788D03*
X1237474D03*
X1242430Y1611796D03*
Y1604876D03*
X1237474Y1611796D03*
Y1604876D03*
X1249534Y1611796D03*
Y1604876D03*
Y1616788D03*
X1258609Y49388D03*
X1262800Y101100D03*
X1264620Y92724D03*
X1252961Y111903D03*
X1267150Y305998D03*
X1256787Y749605D03*
X1261250Y1575686D03*
X1256294D03*
X1261250Y1580678D03*
X1256294D03*
X1254490Y1599884D03*
X1261594D03*
X1261250Y1587598D03*
X1256294D03*
X1261250Y1592590D03*
X1256294D03*
X1254490Y1611796D03*
Y1604876D03*
Y1616788D03*
X1261594D03*
Y1611796D03*
Y1604876D03*
X1278300Y81232D03*
X1280135Y1340002D03*
Y1337402D03*
Y1345202D03*
Y1342602D03*
X1280312Y1365689D03*
X1273310Y1580678D03*
Y1575592D03*
X1268354D03*
Y1580678D03*
X1280414Y1575686D03*
Y1580678D03*
X1266550Y1599884D03*
X1273654Y1599790D03*
X1278610D03*
X1273310Y1592590D03*
X1268354D03*
X1273310Y1587598D03*
X1268354D03*
X1280414D03*
Y1592590D03*
X1266550Y1616788D03*
Y1611796D03*
Y1604876D03*
X1273654Y1611796D03*
Y1604876D03*
X1278610Y1611796D03*
Y1604876D03*
X1273654Y1616788D03*
X1278610D03*
X1295278Y297056D03*
X1290322D03*
X1294937Y746965D03*
X1292904Y782048D03*
X1292614Y789910D03*
X1291205Y1345875D03*
X1286005Y1342768D03*
Y1345875D03*
X1296405Y1342768D03*
X1293805D03*
X1288605D03*
X1291205D03*
X1288605Y1345875D03*
X1293805D03*
X1291405Y1348982D03*
X1294005D03*
X1292916Y1352531D03*
X1290436D03*
X1287956D03*
X1292916Y1358131D03*
X1290436D03*
X1287956D03*
X1283280Y1372301D03*
X1293887Y1370043D03*
X1294477Y1372651D03*
X1285370Y1575686D03*
Y1580678D03*
X1297430D03*
X1292474D03*
Y1575686D03*
X1297430D03*
X1285714Y1599884D03*
X1290670D03*
X1297774D03*
X1285370Y1587598D03*
Y1592590D03*
X1297430D03*
X1292474D03*
X1297430Y1587598D03*
X1292474D03*
X1290670Y1616788D03*
X1285714D03*
Y1611796D03*
X1290670D03*
X1285714Y1604876D03*
X1290670D03*
X1297774Y1611796D03*
Y1604876D03*
Y1616788D03*
X1311960Y49672D03*
X1314450Y319841D03*
X1312845Y324764D03*
X1305909D03*
X1303017Y785837D03*
X1311952Y1321945D03*
X1307656Y1337104D03*
X1305056D03*
X1307656Y1334504D03*
Y1329304D03*
Y1331904D03*
X1305056Y1334504D03*
Y1329304D03*
Y1331904D03*
Y1339704D03*
X1312488Y1348353D03*
X1299605Y1342768D03*
X1302549Y1345891D03*
X1302520Y1348762D03*
X1315058Y1349488D03*
X1302549Y1342784D03*
X1309490Y1575686D03*
X1304534D03*
X1309490Y1580678D03*
X1304534D03*
X1302730Y1599884D03*
X1309834D03*
X1314790D03*
X1309490Y1587598D03*
X1304534D03*
X1309490Y1592590D03*
X1304534D03*
X1302730Y1611796D03*
Y1604876D03*
Y1616788D03*
X1309834D03*
Y1611796D03*
Y1604876D03*
X1314790Y1616788D03*
Y1611796D03*
Y1604876D03*
X1318609Y49388D03*
X1319125Y296540D03*
X1324081D03*
X1324636Y290920D03*
X1329592D03*
X1330248Y325670D03*
X1323312D03*
X1321386Y319841D03*
X1329977Y334384D03*
X1327601Y540049D03*
X1317970Y1322741D03*
Y1319634D03*
X1325770Y1322741D03*
X1323170D03*
X1331570Y1319634D03*
X1323170D03*
X1325770D03*
X1328370D03*
X1320570Y1322741D03*
Y1319634D03*
X1322444Y1329497D03*
X1324924D03*
X1319964D03*
X1322444Y1335097D03*
X1324924D03*
X1319964D03*
X1323370Y1325848D03*
X1325970D03*
X1324945Y1346877D03*
X1327196Y1349068D03*
X1321550Y1580678D03*
X1316594D03*
X1321550Y1575686D03*
X1316594D03*
X1328654D03*
Y1580678D03*
X1321894Y1599884D03*
X1326850D03*
X1321550Y1592590D03*
X1316594D03*
X1321550Y1587598D03*
X1316594D03*
X1328654D03*
Y1592590D03*
X1321894Y1611796D03*
Y1604876D03*
X1326850Y1611796D03*
Y1604876D03*
X1321894Y1616788D03*
X1326850D03*
X1332726Y-27681D03*
X1339019Y-26472D03*
X1332726Y-32055D03*
X1339019Y-37001D03*
X1332726Y-11497D03*
X1339019Y-16443D03*
X1332741Y-15137D03*
X1332726Y-17652D03*
Y-21526D03*
X1332741Y-25166D03*
X1332726Y2406D03*
X1332741Y4921D03*
X1339019Y3615D03*
X1332726Y-1468D03*
X1339019Y-6414D03*
X1332726Y-7623D03*
X1332741Y-5108D03*
X1332726Y18590D03*
Y22464D03*
X1339019Y13644D03*
X1332726Y12435D03*
X1332741Y14950D03*
X1332726Y8561D03*
X1332741Y24979D03*
X1339019Y23673D03*
X1338609Y49388D03*
X1346720Y82912D03*
X1343362Y283155D03*
X1335947Y290755D03*
X1340903D03*
X1343656Y330749D03*
X1343199Y324461D03*
X1336263D03*
X1336913Y334384D03*
X1335643Y540048D03*
X1336187Y755635D03*
X1339784Y1306506D03*
X1337184D03*
X1344080Y1305919D03*
X1343968Y1300579D03*
X1344080Y1308519D03*
X1334514Y1322757D03*
Y1319650D03*
X1337184Y1309106D03*
X1339784D03*
X1338534Y1319406D03*
X1339784Y1316906D03*
Y1314306D03*
Y1311706D03*
X1337184Y1314306D03*
Y1316906D03*
Y1311706D03*
X1334414Y1325853D03*
X1347015Y1335876D03*
X1343631Y1332568D03*
X1333610Y1575686D03*
Y1580678D03*
X1345670D03*
X1340714D03*
X1345670Y1575686D03*
X1340714D03*
X1338910Y1599884D03*
X1333954D03*
X1346014D03*
X1333610Y1587598D03*
Y1592590D03*
X1345670D03*
X1340714D03*
X1345670Y1587598D03*
X1340714D03*
X1338910Y1616788D03*
Y1611796D03*
Y1604876D03*
X1333954Y1616788D03*
Y1611796D03*
Y1604876D03*
X1346014Y1611796D03*
Y1604876D03*
Y1616788D03*
X1350550Y101632D03*
X1363846Y279848D03*
X1349362Y283155D03*
X1353902Y287540D03*
X1359902D03*
X1350592Y330749D03*
X1356968Y339611D03*
X1350032D03*
X1363539Y334043D03*
X1356603D03*
X1350098Y1306208D03*
X1352698D03*
X1355298D03*
X1360498D03*
X1363698D03*
X1357898D03*
X1352698Y1309315D03*
X1350098D03*
X1355498Y1312422D03*
X1358098D03*
X1355298Y1309315D03*
X1357898D03*
X1352092Y1316071D03*
Y1321671D03*
X1357052Y1316071D03*
X1354572D03*
X1357052Y1321671D03*
X1354572D03*
X1356983Y1334095D03*
X1359516Y1334058D03*
X1355357Y1396020D03*
X1357730Y1575686D03*
X1352774D03*
X1357730Y1580678D03*
X1352774D03*
X1350970Y1599884D03*
X1363030D03*
X1358074D03*
X1357730Y1587598D03*
X1352774D03*
X1357730Y1592590D03*
X1352774D03*
X1350970Y1611796D03*
Y1604876D03*
Y1616788D03*
X1363030D03*
Y1611796D03*
Y1604876D03*
X1358074Y1616788D03*
Y1611796D03*
Y1604876D03*
X1378550Y110692D03*
X1377742Y244372D03*
Y250372D03*
X1377626Y258914D03*
Y264914D03*
X1369846Y279848D03*
X1372381Y661428D03*
X1371931Y672978D03*
Y685278D03*
X1372243Y697108D03*
Y709108D03*
Y721108D03*
X1370662Y1305980D03*
X1371912Y1303480D03*
X1376208Y1305919D03*
Y1303319D03*
X1371912Y1300880D03*
X1376208Y1300719D03*
Y1295586D03*
X1371912Y1295747D03*
Y1298280D03*
X1376208Y1298119D03*
X1369312Y1303480D03*
X1366642Y1306224D03*
X1369312Y1300880D03*
Y1295747D03*
Y1298280D03*
X1376208Y1308519D03*
X1366542Y1312427D03*
X1366642Y1309331D03*
X1379271Y1335963D03*
X1375814Y1332653D03*
X1377060Y1411231D03*
X1371960Y1436172D03*
X1365040Y1431142D03*
X1369790Y1580678D03*
X1364834D03*
X1369790Y1575592D03*
X1364834D03*
X1376894Y1575686D03*
Y1580678D03*
X1375090Y1599790D03*
X1370134D03*
X1369790Y1592590D03*
X1364834D03*
X1369790Y1587598D03*
X1364834D03*
X1376894D03*
Y1592590D03*
X1375090Y1611796D03*
Y1604876D03*
Y1616788D03*
X1370134Y1611796D03*
Y1604876D03*
Y1616788D03*
X1383480Y88932D03*
X1383734Y243329D03*
Y237329D03*
X1388778Y250661D03*
X1388908Y260301D03*
X1386237Y265620D03*
Y275200D03*
X1385190Y501242D03*
X1390220Y497742D03*
X1381131Y656378D03*
Y668378D03*
X1395831Y666278D03*
X1386931Y660978D03*
X1381131Y680278D03*
X1396031Y680678D03*
X1386931Y675478D03*
X1387143Y690208D03*
X1380731Y692208D03*
X1395631Y695108D03*
X1380731Y704208D03*
X1387143Y704708D03*
X1380731Y716208D03*
X1395631Y709608D03*
X1387143Y719235D03*
X1395631Y724135D03*
X1382920Y733725D03*
X1391408Y738625D03*
X1382226Y1306208D03*
X1384826D03*
X1387426D03*
X1390026D03*
X1392626D03*
X1395826D03*
X1386700Y1321671D03*
X1389180D03*
X1382226Y1309315D03*
X1384826D03*
X1390226Y1312422D03*
X1387626D03*
X1390026Y1309315D03*
X1387426D03*
X1384220Y1316071D03*
Y1321671D03*
X1389180Y1316071D03*
X1386700D03*
X1390758Y1333473D03*
X1392076Y1335658D03*
X1388813Y1393160D03*
X1396115Y1405289D03*
Y1412789D03*
X1396615Y1420289D03*
X1384695Y1425047D03*
X1392475Y1576097D03*
X1381850Y1575686D03*
Y1580678D03*
X1396600Y1582500D03*
X1387150Y1599884D03*
X1382194D03*
X1381850Y1587598D03*
Y1592590D03*
X1396600Y1594000D03*
X1387150Y1616788D03*
X1382194D03*
X1387150Y1611796D03*
Y1604876D03*
X1382194Y1611796D03*
Y1604876D03*
X1404630Y220018D03*
X1412270Y230952D03*
X1405436Y238378D03*
X1400207Y238257D03*
X1398770Y1306224D03*
X1404040Y1303480D03*
X1408336Y1305919D03*
Y1303319D03*
X1404040Y1300880D03*
X1408336Y1300719D03*
Y1295586D03*
X1404040Y1295747D03*
Y1298280D03*
X1408336Y1298119D03*
X1401440Y1303480D03*
X1402790Y1305980D03*
X1401440Y1300880D03*
Y1295747D03*
Y1298280D03*
X1408336Y1308519D03*
X1398670Y1312427D03*
X1398770Y1309331D03*
X1411124Y1335924D03*
X1407719Y1332560D03*
X1403615Y1405289D03*
X1411115D03*
Y1412789D03*
X1403615Y1420289D03*
X1411115D03*
X1403350Y1516435D03*
X1403590Y1532255D03*
X1403350Y1521335D03*
X1403740Y1548375D03*
X1403590Y1537155D03*
X1403740Y1543475D03*
X1407200Y1591400D03*
X1411070Y1603282D03*
X1400000Y1630362D03*
Y1642362D03*
X1413350Y220018D03*
X1416020D03*
X1424690D03*
X1424520Y225002D03*
X1416810Y225422D03*
X1428640Y230022D03*
X1431430Y251265D03*
X1428940Y269292D03*
X1414354Y1306208D03*
X1416954D03*
X1419554D03*
X1422154D03*
X1424754D03*
X1427954D03*
X1418828Y1316071D03*
X1416348D03*
X1418828Y1321671D03*
X1416348D03*
X1421308Y1316071D03*
Y1321671D03*
X1414354Y1309315D03*
X1416954D03*
X1419554D03*
X1422354Y1312422D03*
X1419754D03*
X1422154Y1309315D03*
X1421294Y1334095D03*
X1423656Y1335468D03*
X1429345Y1433695D03*
X1427349Y1442776D03*
X1414264Y1439494D03*
X1419256Y1440258D03*
X1423829Y1442776D03*
X1416800Y1564862D03*
X1428403Y1581378D03*
X1418241Y1583441D03*
X1422145Y1575362D03*
X1426680Y1603262D03*
X1425770Y1633772D03*
X1413230Y1641042D03*
X1438609Y49388D03*
X1441125Y57362D03*
X1438680Y64412D03*
X1441490Y224062D03*
X1438720Y220018D03*
X1430130Y259342D03*
X1437177Y720965D03*
X1437182Y1298991D03*
X1430898Y1306224D03*
X1434582Y1304191D03*
Y1306791D03*
Y1301591D03*
Y1296458D03*
Y1298991D03*
X1440507Y1305430D03*
Y1302830D03*
Y1300230D03*
X1440536Y1296455D03*
X1440464Y1308519D03*
X1437182Y1304191D03*
Y1306791D03*
Y1301591D03*
Y1296458D03*
X1430798Y1312427D03*
X1430898Y1309331D03*
X1443785Y1335981D03*
X1440879Y1333085D03*
X1439155Y1399064D03*
X1431717Y1420625D03*
Y1417125D03*
Y1409125D03*
Y1427632D03*
X1436330Y1521152D03*
X1436570Y1536972D03*
X1436720Y1548192D03*
X1437140Y1576012D03*
X1438300Y1598400D03*
X1430250Y1608442D03*
X1438300Y1611000D03*
X1438273Y1671103D03*
X1458609Y49388D03*
X1458720Y153362D03*
Y149362D03*
Y169862D03*
Y165862D03*
Y161862D03*
Y157862D03*
Y181862D03*
Y177862D03*
Y173862D03*
X1446830Y236232D03*
X1453670Y278170D03*
X1459312Y341130D03*
X1460600Y352742D03*
X1456700Y369642D03*
X1454889Y658712D03*
X1454439Y670262D03*
Y682562D03*
X1454751Y694392D03*
Y706392D03*
X1454439Y718362D03*
X1459057Y733545D03*
X1457597Y739035D03*
X1446482Y1306208D03*
X1449082D03*
X1451682D03*
X1456882D03*
X1460082D03*
X1454282D03*
X1450956Y1321671D03*
X1448476D03*
X1453436Y1316071D03*
Y1321671D03*
X1446482Y1309315D03*
X1451882Y1312422D03*
X1449082Y1309315D03*
X1451682D03*
X1454482Y1312422D03*
X1454282Y1309315D03*
X1450956Y1316071D03*
X1448476D03*
X1453303Y1334095D03*
X1455436Y1335598D03*
X1461377Y1417844D03*
X1459135Y1439627D03*
X1459136Y1442241D03*
X1461517Y1575686D03*
Y1580678D03*
X1446600Y1595400D03*
X1461517Y1587598D03*
Y1592590D03*
X1460441Y1602441D03*
X1446786Y1610639D03*
X1452757Y1671399D03*
X1446380Y1676291D03*
X1464200Y67802D03*
X1470220Y145362D03*
X1470101Y207751D03*
X1476858Y225448D03*
X1466940Y230272D03*
X1466958Y244948D03*
X1468620Y258857D03*
X1467230Y252472D03*
X1466660Y273878D03*
X1475790Y404842D03*
X1473310Y418502D03*
X1463639Y653662D03*
X1469651Y655992D03*
X1462010Y645842D03*
X1463639Y665662D03*
X1478139Y660892D03*
X1469439Y670262D03*
X1463639Y677562D03*
X1463239Y689492D03*
X1478139Y689892D03*
X1469651Y684992D03*
X1463239Y701492D03*
X1478139Y704392D03*
X1469477Y699475D03*
X1463239Y713492D03*
X1478139Y718892D03*
X1469651Y713992D03*
X1474100Y735662D03*
X1466451Y726992D03*
X1474939Y731892D03*
X1472592Y1306345D03*
X1463026Y1306224D03*
X1465696Y1303480D03*
X1467046Y1305980D03*
X1468296Y1303480D03*
X1465696Y1300880D03*
X1468296D03*
X1472361Y1322440D03*
X1472592Y1308945D03*
Y1316745D03*
Y1314145D03*
Y1311545D03*
X1462926Y1312427D03*
X1463026Y1309331D03*
X1475599Y1349468D03*
X1475959Y1385027D03*
X1476000Y1393027D03*
X1465747Y1401405D03*
X1466448Y1421499D03*
X1475935Y1439627D03*
X1475936Y1442241D03*
X1467550Y1439642D03*
X1467536Y1442241D03*
X1473577Y1580678D03*
Y1575686D03*
X1466473D03*
Y1580678D03*
X1471773Y1599884D03*
X1466817D03*
X1473577Y1592590D03*
Y1587598D03*
X1466473D03*
Y1592590D03*
X1466817Y1611796D03*
X1471773D03*
X1466817Y1604876D03*
X1471773D03*
Y1616788D03*
X1466817D03*
X1478609Y49388D03*
X1481360Y358792D03*
X1488500Y410152D03*
X1478539Y675462D03*
X1486410Y1322741D03*
X1483810D03*
X1486410Y1319634D03*
X1483810D03*
X1481210Y1322741D03*
Y1319634D03*
X1492210D03*
X1489010D03*
X1478610Y1322741D03*
Y1319634D03*
X1484010Y1325848D03*
X1486610D03*
X1485564Y1335097D03*
X1483084D03*
X1485564Y1329497D03*
X1483084D03*
X1480604Y1335097D03*
Y1329497D03*
X1485523Y1347521D03*
X1487386Y1349258D03*
X1478559Y1385027D03*
X1481159Y1384727D03*
X1478600Y1393027D03*
X1481107Y1393095D03*
X1484395Y1439598D03*
X1484336Y1442241D03*
X1490593Y1580678D03*
Y1575686D03*
X1485637D03*
Y1580678D03*
X1478533D03*
Y1575686D03*
X1490937Y1599884D03*
X1478877D03*
X1483833D03*
X1490593Y1587598D03*
X1485637D03*
Y1592590D03*
X1490593D03*
X1478533D03*
Y1587598D03*
X1490937Y1604876D03*
Y1611796D03*
Y1616788D03*
X1483833D03*
X1478877D03*
Y1611796D03*
X1483833D03*
X1478877Y1604876D03*
X1483833D03*
X1498609Y49388D03*
X1496200Y359522D03*
X1497880Y373062D03*
X1503450Y382693D03*
X1497770Y732502D03*
X1495154Y1322757D03*
Y1319650D03*
X1499048Y1319946D03*
X1504720Y1329143D03*
X1495054Y1325853D03*
X1503786Y1326076D03*
X1504518Y1335982D03*
X1504720Y1342143D03*
Y1344743D03*
X1505116Y1369724D03*
X1509757Y1575686D03*
Y1580678D03*
X1502653D03*
X1497697D03*
X1502653Y1575686D03*
X1497697D03*
X1502997Y1599884D03*
X1507953D03*
X1495893D03*
X1509757Y1587598D03*
Y1592590D03*
X1502653D03*
X1497697D03*
X1502653Y1587598D03*
X1497697D03*
X1502997Y1616788D03*
X1507953D03*
X1502997Y1604876D03*
Y1611796D03*
X1507953Y1604876D03*
Y1611796D03*
X1495893Y1604876D03*
Y1611796D03*
Y1616788D03*
X1518608Y49377D03*
X1522920Y113030D03*
X1526675Y140117D03*
X1526083Y146225D03*
X1513759Y263676D03*
X1516683Y278437D03*
X1511624Y291175D03*
X1519336Y303426D03*
X1520094Y306543D03*
X1514369Y308467D03*
X1524505Y748912D03*
X1522066Y1312808D03*
X1526066D03*
X1518066D03*
X1515066D03*
X1511066D03*
X1510738Y1345539D03*
Y1342432D03*
X1518538Y1345539D03*
Y1342432D03*
X1515938Y1345539D03*
Y1342432D03*
X1513338Y1345539D03*
Y1342432D03*
X1521138D03*
X1524338D03*
X1518738Y1348646D03*
X1516138D03*
X1515212Y1352295D03*
X1512732D03*
X1517692D03*
X1515212Y1357895D03*
X1512732D03*
X1517692D03*
X1518451Y1369919D03*
X1521817Y1580678D03*
Y1575686D03*
X1514713D03*
Y1580678D03*
X1520013Y1599884D03*
X1515057D03*
X1521817Y1592590D03*
Y1587598D03*
X1514713D03*
Y1592590D03*
X1520013Y1604876D03*
X1515057D03*
X1520013Y1611796D03*
X1515057D03*
Y1616788D03*
X1520013D03*
X1534818Y66801D03*
Y71793D03*
X1539774Y66801D03*
Y71793D03*
X1541774Y69297D03*
X1532818D03*
X1534774Y103093D03*
X1529818D03*
X1535320Y113062D03*
X1529500Y129602D03*
X1545447Y156035D03*
X1537262Y197834D03*
X1540989Y616587D03*
X1535052Y1325904D03*
X1532552Y1334504D03*
X1535052D03*
X1529952D03*
X1532552Y1339704D03*
X1529952D03*
X1537652Y1325904D03*
Y1334504D03*
X1532552Y1337104D03*
X1529952D03*
X1538510Y1346392D03*
X1531302Y1342204D03*
X1535892Y1346354D03*
Y1343754D03*
X1527282Y1345555D03*
Y1342448D03*
X1538757Y1356355D03*
X1527182Y1348651D03*
X1538757Y1360855D03*
Y1365355D03*
X1533877Y1575592D03*
X1538833D03*
X1533877Y1580678D03*
X1538833D03*
X1526773D03*
Y1575686D03*
X1539177Y1599790D03*
X1527117Y1599884D03*
X1532073D03*
X1533877Y1587598D03*
X1538833D03*
X1533877Y1592590D03*
X1538833D03*
X1526773D03*
Y1587598D03*
X1539177Y1611796D03*
Y1604876D03*
Y1616788D03*
X1527117D03*
Y1604876D03*
Y1611796D03*
X1532073Y1616788D03*
Y1604876D03*
Y1611796D03*
X1547768Y3010D03*
X1555635Y16999D03*
Y21991D03*
X1553635Y19495D03*
X1553486Y23935D03*
X1548530D03*
X1546530Y25931D03*
X1555486D03*
X1547429Y37106D03*
X1554515D03*
Y48720D03*
X1547429D03*
X1554818Y69297D03*
X1556818Y66801D03*
Y71793D03*
X1543818Y75297D03*
X1552774D03*
X1550774Y77793D03*
Y72801D03*
X1545818Y77793D03*
Y72801D03*
X1554239Y138263D03*
X1554723Y200375D03*
X1557560Y196912D03*
X1554723Y224529D03*
Y248945D03*
X1554727Y631527D03*
X1550417Y677045D03*
X1550057Y693485D03*
X1548479Y706088D03*
X1557997Y1575686D03*
Y1580678D03*
X1550893D03*
X1545937D03*
X1550893Y1575686D03*
X1545937D03*
X1556193Y1599884D03*
X1551237D03*
X1544133Y1599790D03*
X1557997Y1587598D03*
Y1592590D03*
X1545937D03*
X1550893D03*
Y1587598D03*
X1545937D03*
X1551237Y1616788D03*
X1556193D03*
Y1604876D03*
X1551237D03*
X1556193Y1611796D03*
X1551237D03*
X1544133Y1604876D03*
Y1611796D03*
Y1616788D03*
X1567768Y3010D03*
X1560591Y16999D03*
Y21991D03*
X1569808Y16999D03*
Y21991D03*
X1574764Y16999D03*
Y21991D03*
X1562591Y19495D03*
X1567808D03*
X1567659Y23935D03*
X1562703D03*
X1560703Y25931D03*
X1569659D03*
X1574876D03*
X1561602Y37106D03*
X1568688D03*
Y48720D03*
X1561602D03*
X1563774Y69297D03*
X1561774Y66801D03*
Y71793D03*
X1565818Y75297D03*
X1574774D03*
X1572774Y77793D03*
Y72801D03*
X1567818Y77793D03*
Y72801D03*
X1559860Y240002D03*
X1575169Y303929D03*
X1560717Y648522D03*
X1570720Y729362D03*
X1570057Y1580678D03*
X1575013D03*
X1570057Y1575686D03*
X1575013D03*
X1562953D03*
Y1580678D03*
X1575357Y1599884D03*
X1563297D03*
X1568253D03*
X1570057Y1592590D03*
X1575013D03*
X1570057Y1587598D03*
X1575013D03*
X1562953D03*
Y1592590D03*
X1575357Y1616788D03*
Y1604876D03*
Y1611796D03*
X1563297Y1604876D03*
Y1611796D03*
X1568253Y1604876D03*
Y1611796D03*
X1563297Y1616788D03*
X1568253D03*
X1587768Y3010D03*
X1583981Y16999D03*
Y21991D03*
X1588937Y16999D03*
Y21991D03*
X1576764Y19495D03*
X1581981D03*
X1590937D03*
X1576876Y23935D03*
X1581832D03*
X1591050D03*
X1583832Y25931D03*
X1589050D03*
X1575775Y37106D03*
X1582862D03*
X1589948D03*
Y48720D03*
X1582862D03*
X1575775D03*
X1576818Y69297D03*
X1585774D03*
X1578818Y66801D03*
Y71793D03*
X1583774Y66801D03*
Y71793D03*
X1587818Y75297D03*
X1589818Y77793D03*
Y72801D03*
X1582117Y1575686D03*
X1587073D03*
X1582117Y1580678D03*
X1587073D03*
X1587417Y1599884D03*
X1580313D03*
X1582117Y1587598D03*
X1587073D03*
X1582117Y1592590D03*
X1587073D03*
X1587417Y1604876D03*
Y1611796D03*
Y1616788D03*
X1580313D03*
Y1604876D03*
Y1611796D03*
X1607768Y3010D03*
X1598155Y16999D03*
Y21991D03*
X1603111Y16999D03*
Y21991D03*
X1596155Y19495D03*
X1605111D03*
X1596006Y23935D03*
X1598006Y25931D03*
X1597035Y37106D03*
X1604122D03*
Y48720D03*
X1597035D03*
X1598818Y69297D03*
X1607774D03*
X1600818Y66801D03*
Y71793D03*
X1605774Y66801D03*
Y71793D03*
X1596774Y75297D03*
X1594774Y77793D03*
Y72801D03*
X1603778Y189943D03*
X1603726Y198061D03*
X1596444Y215526D03*
X1598030Y251002D03*
X1606980Y1449922D03*
X1606237Y1575686D03*
Y1580678D03*
X1594177D03*
X1599133D03*
X1594177Y1575686D03*
X1599133D03*
X1599477Y1599884D03*
X1604433D03*
X1592373D03*
X1606237Y1587598D03*
Y1592590D03*
X1594177D03*
X1599133D03*
X1594177Y1587598D03*
X1599133D03*
X1599477Y1616788D03*
X1604433D03*
X1599477Y1604876D03*
Y1611796D03*
X1604433Y1604876D03*
Y1611796D03*
X1592373Y1604876D03*
Y1611796D03*
Y1616788D03*
X1620818Y69297D03*
X1622818Y66801D03*
Y71793D03*
X1609818Y75297D03*
X1618774D03*
X1616774Y77793D03*
Y72801D03*
X1611818Y77793D03*
Y72801D03*
X1623448Y1420028D03*
Y1417428D03*
Y1414828D03*
Y1412228D03*
X1612630Y1418842D03*
X1615597Y1433669D03*
X1618297Y1580678D03*
X1623253D03*
X1618297Y1575686D03*
X1623253D03*
X1611193D03*
Y1580678D03*
X1623597Y1599884D03*
X1611537D03*
X1616493D03*
X1618297Y1592590D03*
X1623253D03*
X1618297Y1587598D03*
X1623253D03*
X1611193D03*
Y1592590D03*
X1623597Y1616788D03*
Y1604876D03*
Y1611796D03*
X1611537Y1604876D03*
Y1611796D03*
X1616493Y1604876D03*
Y1611796D03*
X1611537Y1616788D03*
X1616493D03*
X1634021Y16999D03*
Y21991D03*
X1638977Y16999D03*
Y21991D03*
X1632021Y19495D03*
X1631872Y23935D03*
X1626916D03*
X1624916Y25931D03*
X1633872D03*
X1639089D03*
X1625814Y37106D03*
X1632901D03*
X1639988D03*
X1625814Y48720D03*
X1632901D03*
X1639988D03*
X1629774Y69297D03*
X1627774Y66801D03*
Y71793D03*
X1633022Y75297D03*
X1635022Y77793D03*
X1639978D03*
Y72801D03*
X1635022D03*
X1635032Y196188D03*
X1642135Y414202D03*
X1629262Y1394418D03*
X1625948Y1417428D03*
Y1412228D03*
X1633103Y1417907D03*
X1630503D03*
X1635703D03*
X1633103Y1421014D03*
X1630503D03*
X1635703D03*
X1638303Y1417907D03*
Y1421014D03*
X1625948Y1414828D03*
Y1420028D03*
X1635903Y1424121D03*
X1638503D03*
X1632516Y1427753D03*
Y1433353D03*
X1634986Y1427753D03*
Y1433353D03*
X1637416Y1427753D03*
Y1433353D03*
X1627591Y1447796D03*
X1637478Y1445150D03*
X1630357Y1575592D03*
X1635313D03*
X1630357Y1580678D03*
X1635313D03*
X1640613Y1599790D03*
X1635657D03*
X1628553Y1599884D03*
X1630357Y1587598D03*
X1635313D03*
X1630357Y1592590D03*
X1635313D03*
X1640613Y1604876D03*
Y1611796D03*
X1635657Y1604876D03*
Y1611796D03*
X1640613Y1616788D03*
X1635657D03*
X1628553D03*
Y1604876D03*
Y1611796D03*
X1648194Y16999D03*
Y21991D03*
X1653150Y16999D03*
Y21991D03*
X1640977Y19495D03*
X1646194D03*
X1655150D03*
X1641089Y23935D03*
X1646045D03*
X1648045Y25931D03*
X1654161Y37106D03*
X1647074D03*
Y48720D03*
X1654161D03*
X1644022Y69297D03*
X1652978D03*
X1646022Y66801D03*
Y71793D03*
X1650978Y66801D03*
Y71793D03*
X1655022Y75297D03*
X1641978D03*
X1657022Y77793D03*
Y72801D03*
X1652610Y394727D03*
X1652810Y407402D03*
X1647110Y434177D03*
X1651890Y520540D03*
X1649220Y620662D03*
X1656188Y1394736D03*
X1647592Y1394418D03*
X1655779Y1417618D03*
Y1412418D03*
Y1415018D03*
X1644103Y1417907D03*
X1647047Y1417923D03*
Y1421030D03*
X1653279Y1412418D03*
X1650679D03*
X1653279Y1415018D03*
X1650679D03*
X1653168Y1417618D03*
X1650557D03*
X1640903Y1417907D03*
X1647016Y1424153D03*
X1648947Y1476695D03*
X1647373Y1580678D03*
X1642417D03*
X1647373Y1575686D03*
X1642417D03*
X1647717Y1599884D03*
X1652673D03*
X1647373Y1592590D03*
X1642417D03*
X1647373Y1587598D03*
X1642417D03*
X1647717Y1616788D03*
X1652673D03*
X1647717Y1604876D03*
Y1611796D03*
X1652673Y1604876D03*
Y1611796D03*
X1671050Y23935D03*
X1669050Y25931D03*
X1669948Y37106D03*
Y48720D03*
X1666022Y69297D03*
X1668022Y66801D03*
Y71793D03*
X1672978Y66801D03*
Y71793D03*
X1663978Y75297D03*
X1661978Y77793D03*
Y72801D03*
X1668030Y200580D03*
X1666074Y229710D03*
X1660176Y231100D03*
X1670400Y229462D03*
X1659610Y394727D03*
X1663610D03*
X1661110Y434177D03*
X1660866Y546749D03*
X1664040Y569642D03*
X1668040D03*
X1672040D03*
X1662120Y604782D03*
X1657220Y620662D03*
X1667405Y1394418D03*
X1659260Y1394693D03*
X1658390Y1420218D03*
Y1415018D03*
Y1412418D03*
Y1417618D03*
X1663590Y1420218D03*
X1660990D03*
Y1415018D03*
Y1417618D03*
Y1412418D03*
X1663590Y1415018D03*
Y1417618D03*
Y1412418D03*
X1668646Y1417907D03*
Y1421014D03*
X1671246Y1417907D03*
Y1421014D03*
X1670659Y1427753D03*
X1673129D03*
X1670659Y1433353D03*
X1673129D03*
X1657438Y1438156D03*
X1660428Y1447566D03*
X1667577Y1447545D03*
X1666123Y1497362D03*
X1665940Y1512862D03*
X1666110Y1504662D03*
X1666123Y1524862D03*
Y1537862D03*
Y1541862D03*
Y1553557D03*
X1666198Y1565557D03*
Y1585321D03*
X1678155Y16999D03*
Y21991D03*
X1683111Y16999D03*
Y21991D03*
X1676155Y19495D03*
X1685111D03*
X1676006Y23935D03*
X1685223D03*
X1678006Y25931D03*
X1683223D03*
X1677035Y37106D03*
X1684122D03*
X1677035Y48720D03*
X1684122D03*
X1688156Y69297D03*
X1674978D03*
X1677156Y75297D03*
X1686112D03*
X1684112Y77793D03*
Y72801D03*
X1679156Y77793D03*
Y72801D03*
X1676300Y219762D03*
X1681900Y227962D03*
X1682810Y465940D03*
X1676040Y569627D03*
X1688301Y722158D03*
X1683121D03*
X1680401D03*
X1686135Y1394418D03*
X1687860Y1415179D03*
X1689210Y1417679D03*
X1687860Y1412579D03*
X1685190Y1417923D03*
X1676446Y1417907D03*
X1679046D03*
X1682246D03*
X1676446Y1421014D03*
X1685190Y1421030D03*
X1673846Y1417907D03*
Y1421014D03*
X1676646Y1424121D03*
X1685159Y1424153D03*
X1675559Y1427753D03*
Y1433353D03*
X1674046Y1424121D03*
X1675621Y1445150D03*
X1679508Y1503421D03*
Y1522921D03*
Y1543921D03*
Y1563380D03*
Y1583880D03*
X1692328Y16999D03*
Y21991D03*
X1697284Y16999D03*
Y21991D03*
X1690328Y19495D03*
X1699284D03*
X1690179Y23935D03*
X1692179Y25931D03*
X1691208Y37106D03*
X1698295D03*
X1705381D03*
X1698295Y48720D03*
X1691208D03*
X1705381D03*
X1697112Y69297D03*
X1690156Y66801D03*
Y71793D03*
X1695112Y66801D03*
Y71793D03*
X1699156Y75297D03*
X1701156Y77793D03*
Y72801D03*
X1695950Y96437D03*
X1697725Y205120D03*
X1700846Y455894D03*
X1702760Y478207D03*
X1696760D03*
X1702760Y490207D03*
X1696760D03*
Y484207D03*
X1696120Y506937D03*
X1703720Y509362D03*
X1696851Y515607D03*
X1693701D03*
X1702270Y552742D03*
X1698920Y698562D03*
X1695227Y722325D03*
X1699307Y722465D03*
X1698137Y718345D03*
X1701087Y719055D03*
X1695367Y719345D03*
X1691021Y722158D03*
X1698537Y766015D03*
X1690809Y1393970D03*
X1699150Y1393613D03*
X1690460Y1415179D03*
Y1412579D03*
X1691918Y1417676D03*
X1692960Y1415179D03*
Y1412579D03*
X1693404Y1421939D03*
X1699593Y1428384D03*
X1697820Y1423616D03*
X1699545Y1425868D03*
X1699437Y1431295D03*
X1699457Y1439185D03*
Y1447805D03*
X1691988Y1498303D03*
Y1517803D03*
Y1538803D03*
Y1558262D03*
X1714520Y37162D03*
X1710920Y82162D03*
X1708112Y75297D03*
X1706112Y77793D03*
Y72801D03*
X1708000Y99122D03*
X1714180Y154790D03*
X1721400Y374462D03*
X1711477Y465229D03*
Y468379D03*
X1708760Y478031D03*
Y490207D03*
Y484207D03*
X1710500Y538162D03*
X1706720Y703762D03*
X1709107Y728449D03*
X1718149Y1496270D03*
X1717149Y1505895D03*
X1720174D03*
X1717988Y1520951D03*
X1711988D03*
X1717149Y1513945D03*
X1720174D03*
X1714988Y1520951D03*
X1708988D03*
X1717988Y1530445D03*
X1714988D03*
X1708988D03*
X1711988D03*
X1727768Y3010D03*
X1732320Y28162D03*
X1728820D03*
X1725320D03*
X1729520Y61762D03*
X1729620Y57262D03*
X1730820Y76362D03*
X1726918Y101967D03*
X1733378Y134907D03*
X1736508D03*
X1723240Y185200D03*
X1737704Y183139D03*
X1737260Y368132D03*
X1732660Y372692D03*
X1725400Y372062D03*
X1725500Y383662D03*
X1737434Y398990D03*
X1727760Y420415D03*
X1747768Y3010D03*
X1754090Y16302D03*
X1748400Y37262D03*
X1753398Y48720D03*
X1745485Y119539D03*
X1747482Y121367D03*
X1741222Y151527D03*
X1747591Y171733D03*
X1751084Y190928D03*
X1745000Y299862D03*
X1746970Y1451872D03*
X1750970Y1459172D03*
Y1456172D03*
X1767768Y3010D03*
X1769900Y37732D03*
X1760485Y48720D03*
X1759700Y57662D03*
X1764400Y57462D03*
X1758063Y68637D03*
X1758573Y87107D03*
Y83607D03*
X1768168Y80497D03*
X1758568Y79697D03*
X1765068Y80397D03*
X1766278Y93627D03*
X1768483Y166260D03*
X1763731Y283817D03*
X1766725Y282981D03*
X1763731Y279517D03*
X1760398Y279548D03*
X1766765Y279433D03*
X1757439Y279611D03*
X1760398Y283848D03*
X1759509Y292434D03*
X1762549Y286704D03*
X1757439Y283911D03*
X1768045Y295238D03*
X1765053Y295188D03*
X1762285Y295137D03*
X1759629Y295164D03*
X1767309Y290994D03*
X1763045Y289691D03*
X1759529Y289864D03*
X1766655Y286531D03*
X1767455Y302651D03*
X1758563Y310478D03*
X1754963D03*
X1770520Y364148D03*
Y368148D03*
X1767300Y461393D03*
X1765670Y458012D03*
X1767300Y465893D03*
X1764112Y703948D03*
X1761612D03*
X1764112Y695648D03*
X1763570Y693192D03*
X1761612Y695648D03*
X1764072Y720508D03*
X1761572D03*
X1764112Y712248D03*
X1761612D03*
X1760160Y1476032D03*
X1763730Y1483712D03*
Y1480712D03*
X1763830Y1490782D03*
Y1487782D03*
X1785178Y86927D03*
Y89927D03*
X1784238Y150744D03*
X1786690Y234782D03*
Y231782D03*
X1771029Y295164D03*
X1771229Y291064D03*
X1772863Y310478D03*
X1782420Y443987D03*
X1773870Y438222D03*
X1776160Y592792D03*
X1787768Y3010D03*
X1794910Y44573D03*
X1797324Y161465D03*
X1803129Y362293D03*
X1802929Y385293D03*
X1795479Y408056D03*
X1795468Y421334D03*
X1800107Y1256426D03*
X1795484Y1496401D03*
X1792645Y1511423D03*
X1798450Y1524830D03*
X1801450D03*
Y1527830D03*
X1814322Y49388D03*
X1807549Y56415D03*
X1807580Y59397D03*
X1810835Y163986D03*
X1806365Y154032D03*
X1819939Y177243D03*
X1820307Y373829D03*
X1820144Y398052D03*
X1819374Y410432D03*
X1818874Y423932D03*
X1818816Y468872D03*
X1803517Y1495567D03*
X1818410Y1525815D03*
X1812250Y1521830D03*
X1811250Y1524830D03*
Y1527830D03*
X1807850D03*
X1804650D03*
Y1524830D03*
X1807850D03*
X1814370Y1528900D03*
X1814210Y1525815D03*
X1818524Y1528991D03*
X1834322Y49388D03*
X1823508Y158868D03*
X1829026Y367701D03*
X1823426Y1507916D03*
X1831994Y1525977D03*
X1835334Y1520921D03*
X1828510Y1525915D03*
X1821710D03*
X1830466Y1606658D03*
X1838910Y185772D03*
X1843134Y244362D03*
X1836750Y373632D03*
X1838020Y459121D03*
X1854096Y52383D03*
G54D43*
X335349Y985939D03*
X549278Y949619D03*
X1300207Y177799D03*
X1311491Y985939D03*
X1355761Y177798D03*
X1525420Y949619D03*
X1879155Y592848D03*
Y840748D03*
X1889155Y592848D03*
Y840748D03*
X1900275Y964708D03*
X1910275D03*
X1931395Y592868D03*
X1921395D03*
X1952395Y1205248D03*
X1942395D03*
X1963362Y593010D03*
X1973362D03*
X1984482Y1205220D03*
X1994482D03*
X2015452Y593020D03*
X2005452D03*
X2026452Y1205400D03*
X2047419Y593162D03*
X2036452Y1205400D03*
X2057419Y593162D03*
X2078539Y1205372D03*
X2068539D03*
G54D57*
X828780Y1694890D03*
Y1684890D03*
X818780Y1694890D03*
Y1684890D03*
X828780Y1704890D03*
X818780D03*
X828780Y1714890D03*
X818780D03*
X853780Y1694890D03*
Y1684890D03*
Y1704890D03*
Y1714890D03*
X863780Y1694890D03*
Y1684890D03*
Y1704890D03*
Y1714890D03*
X888780Y1684890D03*
Y1694890D03*
Y1704890D03*
Y1714890D03*
X898780Y1684890D03*
Y1694890D03*
Y1704890D03*
Y1714890D03*
X918780Y1704890D03*
X958780Y1694890D03*
Y1684890D03*
Y1704890D03*
Y1714890D03*
X968780Y1694890D03*
Y1684890D03*
Y1704890D03*
Y1714890D03*
X993780Y1684890D03*
Y1694890D03*
X1003780Y1684890D03*
Y1694890D03*
X993780Y1704890D03*
Y1714890D03*
X1003780Y1704890D03*
Y1714890D03*
X1028780Y1684890D03*
Y1694890D03*
X1038780Y1684890D03*
Y1694890D03*
X1028780Y1704890D03*
Y1714890D03*
X1038780Y1704890D03*
Y1714890D03*
G54D16*
X27699Y770144D03*
Y783530D03*
Y776837D03*
Y800263D03*
Y793570D03*
Y820341D03*
Y813648D03*
Y806955D03*
Y830381D03*
Y850459D03*
Y843766D03*
Y837074D03*
Y867192D03*
Y857152D03*
Y880577D03*
Y873885D03*
Y893963D03*
Y887270D03*
Y917389D03*
Y910696D03*
Y904003D03*
Y930774D03*
Y924081D03*
Y947507D03*
Y940814D03*
Y964239D03*
Y954200D03*
Y977625D03*
Y970932D03*
Y991011D03*
Y984318D03*
Y1031168D03*
Y1024475D03*
Y1017782D03*
Y1044554D03*
Y1037861D03*
Y1057940D03*
Y1051247D03*
Y1078018D03*
Y1071326D03*
Y1064633D03*
Y1094751D03*
Y1088058D03*
Y1108137D03*
Y1101444D03*
Y1124869D03*
Y1114829D03*
Y1144948D03*
Y1138255D03*
Y1131562D03*
Y1161680D03*
Y1151641D03*
Y1175066D03*
Y1168373D03*
Y1188452D03*
Y1181759D03*
Y1205184D03*
Y1198491D03*
Y1225263D03*
Y1218570D03*
Y1211877D03*
Y1241995D03*
Y1235302D03*
Y1248688D03*
X43841Y766798D03*
X36399Y770144D03*
X43841Y780184D03*
Y773491D03*
X36399Y783530D03*
Y776837D03*
X43841Y803609D03*
Y796916D03*
Y790223D03*
X36399Y800263D03*
Y793570D03*
X43841Y816995D03*
Y810302D03*
X36399Y820341D03*
Y813648D03*
Y806955D03*
X43841Y833727D03*
Y827034D03*
X36399Y830381D03*
X43841Y847113D03*
Y840420D03*
X36399Y850459D03*
Y843766D03*
Y837074D03*
X43841Y863845D03*
Y853806D03*
X36399Y867192D03*
Y857152D03*
X43841Y883924D03*
Y877231D03*
Y870538D03*
X36399Y880577D03*
Y873885D03*
X43841Y900656D03*
Y890617D03*
X36399Y893963D03*
Y887270D03*
X43841Y914042D03*
Y907349D03*
X36399Y917389D03*
Y910696D03*
Y904003D03*
X43841Y927428D03*
Y920735D03*
X36399Y930774D03*
Y924081D03*
X43841Y944160D03*
Y937467D03*
X36399Y947507D03*
Y940814D03*
X43841Y960892D03*
Y950853D03*
X36399Y964239D03*
Y954200D03*
X43841Y980971D03*
Y974278D03*
Y967585D03*
X36399Y977625D03*
Y970932D03*
X43841Y987664D03*
X36399Y991011D03*
Y984318D03*
X43841Y1027822D03*
Y1017782D03*
X36399Y1031168D03*
Y1024475D03*
Y1017782D03*
X43841Y1047900D03*
Y1041207D03*
Y1034515D03*
X36399Y1044554D03*
Y1037861D03*
X43841Y1061286D03*
Y1054593D03*
X36399Y1057940D03*
Y1051247D03*
X43841Y1074672D03*
Y1067979D03*
X36399Y1078018D03*
Y1071326D03*
Y1064633D03*
X43841Y1091404D03*
Y1084711D03*
X36399Y1094751D03*
Y1088058D03*
X43841Y1111483D03*
Y1104790D03*
Y1098097D03*
X36399Y1108137D03*
Y1101444D03*
X43841Y1128215D03*
Y1121522D03*
X36399Y1124869D03*
Y1114829D03*
X43841Y1141601D03*
Y1134908D03*
X36399Y1144948D03*
Y1138255D03*
Y1131562D03*
X43841Y1158333D03*
Y1148294D03*
X36399Y1161680D03*
Y1151641D03*
X43841Y1171719D03*
Y1165026D03*
X36399Y1175066D03*
Y1168373D03*
X43841Y1185105D03*
Y1178412D03*
X36399Y1188452D03*
Y1181759D03*
X43841Y1208530D03*
Y1201837D03*
Y1195144D03*
X36399Y1205184D03*
Y1198491D03*
X43841Y1221916D03*
Y1215223D03*
X36399Y1225263D03*
Y1218570D03*
Y1211877D03*
X43841Y1238648D03*
Y1231955D03*
X36399Y1241995D03*
Y1235302D03*
X43841Y1245341D03*
X36399Y1248688D03*
X36449Y1257262D03*
X33546Y1273364D03*
X30746D03*
X57399Y770144D03*
X52541Y766798D03*
X57399Y783530D03*
Y776837D03*
X52541Y780184D03*
Y773491D03*
X57399Y800263D03*
Y793570D03*
X52541Y803609D03*
Y796916D03*
Y790223D03*
X57399Y820341D03*
Y813648D03*
Y806955D03*
X52541Y816995D03*
Y810302D03*
X57399Y830381D03*
X52541Y833727D03*
Y827034D03*
X57399Y850459D03*
Y843766D03*
Y837074D03*
X52541Y847113D03*
Y840420D03*
X57399Y867192D03*
Y857152D03*
X52541Y863845D03*
Y853806D03*
X57399Y880577D03*
Y873885D03*
X52541Y883924D03*
Y877231D03*
Y870538D03*
X57399Y893963D03*
Y887270D03*
X52541Y900656D03*
Y890617D03*
X57399Y917389D03*
Y910696D03*
Y904003D03*
X52541Y914042D03*
Y907349D03*
X57399Y930774D03*
Y924081D03*
X52541Y927428D03*
Y920735D03*
X57399Y947507D03*
Y940814D03*
X52541Y944160D03*
Y937467D03*
X57399Y964239D03*
Y954200D03*
X52541Y960892D03*
Y950853D03*
X57399Y977625D03*
Y970932D03*
X52541Y980971D03*
Y974278D03*
Y967585D03*
X57399Y991011D03*
Y984318D03*
X52541Y987664D03*
X57399Y1031168D03*
Y1024475D03*
Y1017782D03*
X52541Y1027822D03*
Y1017782D03*
X57399Y1044554D03*
Y1037861D03*
X52541Y1047900D03*
Y1041207D03*
Y1034515D03*
X57399Y1057940D03*
Y1051247D03*
X52541Y1061286D03*
Y1054593D03*
X57399Y1078018D03*
Y1071326D03*
Y1064633D03*
X52541Y1074672D03*
Y1067979D03*
X57399Y1094751D03*
Y1088058D03*
X52541Y1091404D03*
Y1084711D03*
X57399Y1108137D03*
Y1101444D03*
X52541Y1111483D03*
Y1104790D03*
Y1098097D03*
X57399Y1124869D03*
Y1114829D03*
X52541Y1128215D03*
Y1121522D03*
X57399Y1144948D03*
Y1138255D03*
Y1131562D03*
X52541Y1141601D03*
Y1134908D03*
X57399Y1161680D03*
Y1151641D03*
X52541Y1158333D03*
Y1148294D03*
X57399Y1175066D03*
Y1168373D03*
X52541Y1171719D03*
Y1165026D03*
X57399Y1188452D03*
Y1181759D03*
X52541Y1185105D03*
Y1178412D03*
X57399Y1205184D03*
Y1198491D03*
X52541Y1208530D03*
Y1201837D03*
Y1195144D03*
X57399Y1225263D03*
Y1218570D03*
Y1211877D03*
X52541Y1221916D03*
Y1215223D03*
X57399Y1241995D03*
Y1235302D03*
X52541Y1238648D03*
Y1231955D03*
Y1248688D03*
X57399D03*
X52541Y1245341D03*
X60446Y1273364D03*
X49546D03*
X46746D03*
X73541Y766798D03*
X66099Y770144D03*
X73541Y780184D03*
Y773491D03*
X66099Y783530D03*
Y776837D03*
X73541Y803609D03*
Y796916D03*
Y790223D03*
X66099Y800263D03*
Y793570D03*
X73541Y816995D03*
Y810302D03*
X66099Y820341D03*
Y813648D03*
Y806955D03*
X73541Y833727D03*
Y827034D03*
X66099Y830381D03*
X73541Y847113D03*
Y840420D03*
X66099Y850459D03*
Y843766D03*
Y837074D03*
X73541Y863845D03*
Y853806D03*
X66099Y867192D03*
Y857152D03*
X73541Y883924D03*
Y877231D03*
Y870538D03*
X66099Y880577D03*
Y873885D03*
X73541Y900656D03*
Y890617D03*
X66099Y893963D03*
Y887270D03*
X73541Y914042D03*
Y907349D03*
X66099Y917389D03*
Y910696D03*
Y904003D03*
X73541Y927428D03*
Y920735D03*
X66099Y930774D03*
Y924081D03*
X73541Y944160D03*
Y937467D03*
X66099Y947507D03*
Y940814D03*
X73541Y960892D03*
Y950853D03*
X66099Y964239D03*
Y954200D03*
X73541Y980971D03*
Y974278D03*
Y967585D03*
X66099Y977625D03*
Y970932D03*
X73541Y987664D03*
X66099Y991011D03*
Y984318D03*
X73541Y1027822D03*
Y1017782D03*
X66099Y1031168D03*
Y1024475D03*
Y1017782D03*
X73541Y1047900D03*
Y1041207D03*
Y1034515D03*
X66099Y1044554D03*
Y1037861D03*
X73541Y1061286D03*
Y1054593D03*
X66099Y1057940D03*
Y1051247D03*
X73541Y1074672D03*
Y1067979D03*
X66099Y1078018D03*
Y1071326D03*
Y1064633D03*
X73541Y1091404D03*
Y1084711D03*
X66099Y1094751D03*
Y1088058D03*
X73541Y1111483D03*
Y1104790D03*
Y1098097D03*
X66099Y1108137D03*
Y1101444D03*
X73541Y1128215D03*
Y1121522D03*
X66099Y1124869D03*
Y1114829D03*
X73541Y1141601D03*
Y1134908D03*
X66099Y1144948D03*
Y1138255D03*
Y1131562D03*
X73541Y1158333D03*
Y1148294D03*
X66099Y1161680D03*
Y1151641D03*
X73541Y1171719D03*
Y1165026D03*
X66099Y1175066D03*
Y1168373D03*
X73541Y1185105D03*
Y1178412D03*
X66099Y1188452D03*
Y1181759D03*
X73541Y1208530D03*
Y1201837D03*
Y1195144D03*
X66099Y1205184D03*
Y1198491D03*
X73541Y1221916D03*
Y1215223D03*
X66099Y1225263D03*
Y1218570D03*
Y1211877D03*
X73541Y1238648D03*
Y1231955D03*
X66099Y1241995D03*
Y1235302D03*
X66189Y1257488D03*
X73541Y1245341D03*
X66099Y1248688D03*
X76446Y1273364D03*
X63246D03*
X87099Y770144D03*
X82241Y766798D03*
X87099Y783530D03*
Y776837D03*
X82241Y780184D03*
Y773491D03*
X87099Y800263D03*
Y793570D03*
X82241Y803609D03*
Y796916D03*
Y790223D03*
X87099Y820341D03*
Y813648D03*
Y806955D03*
X82241Y816995D03*
Y810302D03*
X87099Y830381D03*
X82241Y833727D03*
Y827034D03*
X87099Y850459D03*
Y843766D03*
Y837074D03*
X82241Y847113D03*
Y840420D03*
X87099Y867192D03*
Y857152D03*
X82241Y863845D03*
Y853806D03*
X87099Y880577D03*
Y873885D03*
X82241Y883924D03*
Y877231D03*
Y870538D03*
X87099Y893963D03*
Y887270D03*
X82241Y900656D03*
Y890617D03*
X87099Y917389D03*
Y910696D03*
Y904003D03*
X82241Y914042D03*
Y907349D03*
X87099Y930774D03*
Y924081D03*
X82241Y927428D03*
Y920735D03*
X87099Y947507D03*
Y940814D03*
X82241Y944160D03*
Y937467D03*
X87099Y964239D03*
Y954200D03*
X82241Y960892D03*
Y950853D03*
X87099Y977625D03*
Y970932D03*
X82241Y980971D03*
Y974278D03*
Y967585D03*
X87099Y991011D03*
Y984318D03*
X82241Y987664D03*
X87099Y1031168D03*
Y1024475D03*
Y1017782D03*
X82241Y1027822D03*
Y1017782D03*
X87099Y1044554D03*
Y1037861D03*
X82241Y1047900D03*
Y1041207D03*
Y1034515D03*
X87099Y1057940D03*
Y1051247D03*
X82241Y1061286D03*
Y1054593D03*
X87099Y1078018D03*
Y1071326D03*
Y1064633D03*
X82241Y1074672D03*
Y1067979D03*
X87099Y1094751D03*
Y1088058D03*
X82241Y1091404D03*
Y1084711D03*
X87099Y1108137D03*
Y1101444D03*
X82241Y1111483D03*
Y1104790D03*
Y1098097D03*
X87099Y1124869D03*
Y1114829D03*
X82241Y1128215D03*
Y1121522D03*
X87099Y1144948D03*
Y1138255D03*
Y1131562D03*
X82241Y1141601D03*
Y1134908D03*
X87099Y1161680D03*
Y1151641D03*
X82241Y1158333D03*
Y1148294D03*
X87099Y1175066D03*
Y1168373D03*
X82241Y1171719D03*
Y1165026D03*
X87099Y1188452D03*
Y1181759D03*
X82241Y1185105D03*
Y1178412D03*
X87099Y1205184D03*
Y1198491D03*
X82241Y1208530D03*
Y1201837D03*
Y1195144D03*
X87099Y1225263D03*
Y1218570D03*
Y1211877D03*
X82241Y1221916D03*
Y1215223D03*
X87099Y1241995D03*
Y1235302D03*
X82241Y1238648D03*
Y1231955D03*
X87099Y1248688D03*
X82241Y1245341D03*
X92946Y1273364D03*
X90146D03*
X79246D03*
X103241Y766798D03*
X95799Y770144D03*
X103241Y780184D03*
Y773491D03*
X95799Y783530D03*
Y776837D03*
X103241Y803609D03*
Y796916D03*
Y790223D03*
X95799Y800263D03*
Y793570D03*
X103241Y816995D03*
Y810302D03*
X95799Y820341D03*
Y813648D03*
Y806955D03*
X103241Y833727D03*
Y827034D03*
X95799Y830381D03*
X103241Y847113D03*
Y840420D03*
X95799Y850459D03*
Y843766D03*
Y837074D03*
X103241Y863845D03*
Y853806D03*
X95799Y867192D03*
Y857152D03*
X103241Y883924D03*
Y877231D03*
Y870538D03*
X95799Y880577D03*
Y873885D03*
X103241Y900656D03*
Y890617D03*
X95799Y893963D03*
Y887270D03*
X103241Y914042D03*
Y907349D03*
X95799Y917389D03*
Y910696D03*
Y904003D03*
X103241Y927428D03*
Y920735D03*
X95799Y930774D03*
Y924081D03*
X103241Y944160D03*
Y937467D03*
X95799Y947507D03*
Y940814D03*
X103241Y960892D03*
Y950853D03*
X95799Y964239D03*
Y954200D03*
X103241Y980971D03*
Y974278D03*
Y967585D03*
X95799Y977625D03*
Y970932D03*
X103241Y987664D03*
X95799Y991011D03*
Y984318D03*
X103241Y1027822D03*
Y1017782D03*
X95799Y1031168D03*
Y1024475D03*
Y1017782D03*
X103241Y1047900D03*
Y1041207D03*
Y1034515D03*
X95799Y1044554D03*
Y1037861D03*
X103241Y1061286D03*
Y1054593D03*
X95799Y1057940D03*
Y1051247D03*
X103241Y1074672D03*
Y1067979D03*
X95799Y1078018D03*
Y1071326D03*
Y1064633D03*
X103241Y1091404D03*
Y1084711D03*
X95799Y1094751D03*
Y1088058D03*
X103241Y1111483D03*
Y1104790D03*
Y1098097D03*
X95799Y1108137D03*
Y1101444D03*
X103241Y1128215D03*
Y1121522D03*
X95799Y1124869D03*
Y1114829D03*
X103241Y1141601D03*
Y1134908D03*
X95799Y1144948D03*
Y1138255D03*
Y1131562D03*
X103241Y1158333D03*
Y1148294D03*
X95799Y1161680D03*
Y1151641D03*
X103241Y1171719D03*
Y1165026D03*
X95799Y1175066D03*
Y1168373D03*
X103241Y1185105D03*
Y1178412D03*
X95799Y1188452D03*
Y1181759D03*
X103241Y1208530D03*
Y1201837D03*
Y1195144D03*
X95799Y1205184D03*
Y1198491D03*
X103241Y1221916D03*
Y1215223D03*
X95799Y1225263D03*
Y1218570D03*
Y1211877D03*
X103241Y1238648D03*
Y1231955D03*
X95799Y1241995D03*
Y1235302D03*
X95849Y1257262D03*
X103241Y1245341D03*
X95799Y1248688D03*
X108946Y1273364D03*
X106146D03*
X125499Y770144D03*
X116799D03*
X111941Y766798D03*
X125499Y783530D03*
X116799D03*
X125499Y776837D03*
X116799D03*
X111941Y780184D03*
Y773491D03*
X125499Y800263D03*
X116799D03*
X125499Y793570D03*
X116799D03*
X111941Y803609D03*
Y796916D03*
Y790223D03*
X125499Y820341D03*
X116799D03*
X125499Y813648D03*
X116799D03*
X125499Y806955D03*
X116799D03*
X111941Y816995D03*
Y810302D03*
X125499Y830381D03*
X116799D03*
X111941Y833727D03*
Y827034D03*
X125499Y850459D03*
X116799D03*
X125499Y843766D03*
X116799D03*
X125499Y837074D03*
X116799D03*
X111941Y847113D03*
Y840420D03*
X125499Y867192D03*
X116799D03*
X125499Y857152D03*
X116799D03*
X111941Y863845D03*
Y853806D03*
X125499Y880577D03*
X116799D03*
X125499Y873885D03*
X116799D03*
X111941Y883924D03*
Y877231D03*
Y870538D03*
X125499Y893963D03*
X116799D03*
X125499Y887270D03*
X116799D03*
X111941Y900656D03*
Y890617D03*
X125499Y917389D03*
X116799D03*
X125499Y910696D03*
X116799D03*
X125499Y904003D03*
X116799D03*
X111941Y914042D03*
Y907349D03*
X125499Y930774D03*
X116799D03*
X125499Y924081D03*
X116799D03*
X111941Y927428D03*
Y920735D03*
X125499Y947507D03*
X116799D03*
X125499Y940814D03*
X116799D03*
X111941Y944160D03*
Y937467D03*
X125499Y964239D03*
X116799D03*
X125499Y954200D03*
X116799D03*
X111941Y960892D03*
Y950853D03*
X125499Y977625D03*
X116799D03*
X125499Y970932D03*
X116799D03*
X111941Y980971D03*
Y974278D03*
Y967585D03*
X125499Y991011D03*
X116799D03*
X125499Y984318D03*
X116799D03*
X111941Y987664D03*
X125499Y1031168D03*
X116799D03*
X125499Y1024475D03*
X116799D03*
X125499Y1017782D03*
X116799D03*
X111941Y1027822D03*
Y1017782D03*
X125499Y1044554D03*
X116799D03*
X125499Y1037861D03*
X116799D03*
X111941Y1047900D03*
Y1041207D03*
Y1034515D03*
X125499Y1057940D03*
X116799D03*
X125499Y1051247D03*
X116799D03*
X111941Y1061286D03*
Y1054593D03*
X125499Y1078018D03*
X116799D03*
X125499Y1071326D03*
X116799D03*
X125499Y1064633D03*
X116799D03*
X111941Y1074672D03*
Y1067979D03*
X125499Y1094751D03*
X116799D03*
X125499Y1088058D03*
X116799D03*
X111941Y1091404D03*
Y1084711D03*
X125499Y1108137D03*
X116799D03*
X125499Y1101444D03*
X116799D03*
X111941Y1111483D03*
Y1104790D03*
Y1098097D03*
X125499Y1124869D03*
X116799D03*
X125499Y1114829D03*
X116799D03*
X111941Y1128215D03*
Y1121522D03*
X125499Y1144948D03*
X116799D03*
X125499Y1138255D03*
X116799D03*
X125499Y1131562D03*
X116799D03*
X111941Y1141601D03*
Y1134908D03*
X125499Y1161680D03*
X116799D03*
X125499Y1151641D03*
X116799D03*
X111941Y1158333D03*
Y1148294D03*
X125499Y1175066D03*
X116799D03*
X125499Y1168373D03*
X116799D03*
X111941Y1171719D03*
Y1165026D03*
X125499Y1188452D03*
X116799D03*
X125499Y1181759D03*
X116799D03*
X111941Y1185105D03*
Y1178412D03*
X125499Y1205184D03*
X116799D03*
X125499Y1198491D03*
X116799D03*
X111941Y1208530D03*
Y1201837D03*
Y1195144D03*
X125499Y1225263D03*
X116799D03*
X125499Y1218570D03*
X116799D03*
X125499Y1211877D03*
X116799D03*
X111941Y1221916D03*
Y1215223D03*
X125499Y1241995D03*
X116799D03*
X125499Y1235302D03*
X116799D03*
X111941Y1238648D03*
Y1231955D03*
X125412Y1257102D03*
X125499Y1248688D03*
X116799D03*
X111941Y1245341D03*
X119846Y1273364D03*
X122646D03*
X141641Y766798D03*
X132941D03*
X141641Y773491D03*
X132941D03*
X141641Y780184D03*
X132941D03*
X141641Y803609D03*
X132941D03*
X141641Y790223D03*
X132941D03*
X141641Y796916D03*
X132941D03*
X141641Y816995D03*
X132941D03*
X141641Y810302D03*
X132941D03*
X141641Y833727D03*
X132941D03*
X141641Y827034D03*
X132941D03*
X141641Y840420D03*
X132941D03*
X141641Y847113D03*
X132941D03*
Y863845D03*
X141641D03*
Y853806D03*
X132941D03*
Y883924D03*
X141641D03*
X132941Y870538D03*
X141641D03*
X132941Y877231D03*
X141641D03*
X132941Y900656D03*
X141641D03*
X132941Y890617D03*
X141641D03*
X132941Y907349D03*
X141641D03*
X132941Y914042D03*
X141641D03*
X132941Y920735D03*
X141641D03*
X132941Y927428D03*
X141641D03*
X132941Y937467D03*
X141641D03*
X132941Y944160D03*
X141641D03*
X132941Y960892D03*
X141641D03*
X132941Y950853D03*
X141641D03*
X132941Y980971D03*
X141641D03*
X132941Y974278D03*
X141641D03*
X132941Y967585D03*
X141641D03*
X132941Y987664D03*
X141641D03*
X132941Y1027822D03*
X141641D03*
X132941Y1017782D03*
X141641D03*
X132941Y1047900D03*
X141641D03*
X132941Y1041207D03*
X141641D03*
X132941Y1034515D03*
X141641D03*
Y1061286D03*
X132941D03*
X141641Y1054593D03*
X132941D03*
X141641Y1074672D03*
X132941D03*
X141641Y1067979D03*
X132941D03*
X141641Y1091404D03*
X132941D03*
X141641Y1084711D03*
X132941D03*
X141641Y1111483D03*
X132941D03*
X141641Y1104790D03*
X132941D03*
X141641Y1098097D03*
X132941D03*
X141641Y1128215D03*
X132941D03*
X141641Y1121522D03*
X132941D03*
X141641Y1141601D03*
X132941D03*
X141641Y1134908D03*
X132941D03*
X141641Y1158333D03*
X132941D03*
X141641Y1148294D03*
X132941D03*
X141641Y1171719D03*
X132941D03*
X141641Y1165026D03*
X132941D03*
X141641Y1185105D03*
X132941D03*
X141641Y1178412D03*
X132941D03*
X141641Y1208530D03*
X132941D03*
X141641Y1201837D03*
X132941D03*
X141641Y1195144D03*
X132941D03*
Y1221916D03*
X141641D03*
X132941Y1215223D03*
X141641D03*
X132941Y1238648D03*
X141641D03*
X132941Y1231955D03*
X141641D03*
X132941Y1245341D03*
X141641D03*
X135846Y1273364D03*
X138646D03*
X146499Y770144D03*
X155199D03*
X146499Y783530D03*
X155199D03*
X146499Y776837D03*
X155199D03*
X146499Y800263D03*
X155199D03*
X146499Y793570D03*
X155199D03*
X146499Y820341D03*
X155199D03*
X146499Y813648D03*
X155199D03*
X146499Y806955D03*
X155199D03*
X146499Y830381D03*
X155199D03*
X146499Y850459D03*
X155199D03*
X146499Y843766D03*
X155199D03*
X146499Y837074D03*
X155199D03*
Y867192D03*
X146499D03*
Y857152D03*
X155199D03*
Y880577D03*
X146499D03*
X155199Y873885D03*
X146499D03*
X155199Y893963D03*
X146499D03*
X155199Y887270D03*
X146499D03*
X155199Y917389D03*
X146499D03*
X155199Y910696D03*
X146499D03*
X155199Y904003D03*
X146499D03*
X155199Y930774D03*
X146499D03*
X155199Y924081D03*
X146499D03*
X155199Y947507D03*
X146499D03*
X155199Y940814D03*
X146499D03*
X155199Y964239D03*
X146499D03*
X155199Y954200D03*
X146499D03*
X155199Y977625D03*
X146499D03*
X155199Y970932D03*
X146499D03*
X155199Y991011D03*
X146499D03*
X155199Y984318D03*
X146499D03*
X155199Y1031168D03*
X146499D03*
X155199Y1024475D03*
X146499D03*
X155199Y1017782D03*
X146499D03*
X155199Y1044554D03*
X146499D03*
X155199Y1037861D03*
X146499D03*
X155199Y1057940D03*
X146499D03*
X155199Y1051247D03*
X146499D03*
X155199Y1078018D03*
X146499D03*
X155199Y1071326D03*
X146499D03*
X155199Y1064633D03*
X146499D03*
X155199Y1094751D03*
X146499D03*
X155199Y1088058D03*
X146499D03*
X155199Y1108137D03*
X146499D03*
X155199Y1101444D03*
X146499D03*
X155199Y1124869D03*
X146499D03*
X155199Y1114829D03*
X146499D03*
X155199Y1144948D03*
X146499D03*
X155199Y1138255D03*
X146499D03*
X155199Y1131562D03*
X146499D03*
X155199Y1161680D03*
X146499D03*
X155199Y1151641D03*
X146499D03*
X155199Y1175066D03*
X146499D03*
X155199Y1168373D03*
X146499D03*
X155199Y1188452D03*
X146499D03*
X155199Y1181759D03*
X146499D03*
X155199Y1205184D03*
X146499D03*
X155199Y1198491D03*
X146499D03*
X155199Y1225263D03*
X146499D03*
X155199Y1218570D03*
X146499D03*
X155199Y1211877D03*
X146499D03*
X155199Y1241995D03*
X146499D03*
X155199Y1235302D03*
X146499D03*
X155135Y1257134D03*
X155199Y1248688D03*
X146499D03*
X149546Y1273364D03*
X152346D03*
X176199Y770144D03*
X162641Y766798D03*
X171341D03*
X176199Y783530D03*
Y776837D03*
X162641Y780184D03*
X171341D03*
Y773491D03*
X162641D03*
X176199Y800263D03*
X162641Y803609D03*
X171341D03*
X176199Y793570D03*
X162641Y796916D03*
X171341D03*
X162641Y790223D03*
X171341D03*
X176199Y820341D03*
X162641Y816995D03*
X171341D03*
X176199Y813648D03*
Y806955D03*
X162641Y810302D03*
X171341D03*
X162641Y833727D03*
X171341D03*
X176199Y830381D03*
X162641Y827034D03*
X171341D03*
X176199Y850459D03*
Y843766D03*
Y837074D03*
X162641Y847113D03*
X171341D03*
X162641Y840420D03*
X171341D03*
X176199Y867192D03*
X171341Y863845D03*
X162641D03*
X176199Y857152D03*
X162641Y853806D03*
X171341D03*
Y883924D03*
X162641D03*
X176199Y880577D03*
Y873885D03*
X171341Y877231D03*
X162641D03*
X171341Y870538D03*
X162641D03*
X171341Y900656D03*
X162641D03*
X176199Y893963D03*
Y887270D03*
X171341Y890617D03*
X162641D03*
X176199Y917389D03*
Y910696D03*
Y904003D03*
X171341Y914042D03*
X162641D03*
X171341Y907349D03*
X162641D03*
X176199Y930774D03*
Y924081D03*
X171341Y927428D03*
X162641D03*
X171341Y920735D03*
X162641D03*
X176199Y947507D03*
Y940814D03*
X171341Y944160D03*
X162641D03*
X171341Y937467D03*
X162641D03*
X176199Y964239D03*
Y954200D03*
X171341Y960892D03*
X162641D03*
X171341Y950853D03*
X162641D03*
X171341Y980971D03*
X162641D03*
X176199Y977625D03*
Y970932D03*
X171341Y974278D03*
X162641D03*
X171341Y967585D03*
X162641D03*
X176199Y991011D03*
Y984318D03*
X171341Y987664D03*
X162641D03*
X176199Y1031168D03*
Y1024475D03*
Y1017782D03*
X171341Y1027822D03*
X162641D03*
X171341Y1017782D03*
X162641D03*
X171341Y1047900D03*
X162641D03*
X176199Y1044554D03*
Y1037861D03*
X171341Y1041207D03*
X162641D03*
X171341Y1034515D03*
X162641D03*
X176199Y1057940D03*
Y1051247D03*
X171341Y1061286D03*
X162641D03*
X171341Y1054593D03*
X162641D03*
X176199Y1078018D03*
Y1071326D03*
Y1064633D03*
X171341Y1074672D03*
X162641D03*
X171341Y1067979D03*
X162641D03*
X176199Y1094751D03*
Y1088058D03*
X171341Y1091404D03*
X162641D03*
X171341Y1084711D03*
X162641D03*
X171341Y1111483D03*
X162641D03*
X176199Y1108137D03*
Y1101444D03*
X171341Y1104790D03*
X162641D03*
X171341Y1098097D03*
X162641D03*
X171341Y1128215D03*
X162641D03*
X176199Y1124869D03*
Y1114829D03*
X171341Y1121522D03*
X162641D03*
X176199Y1144948D03*
Y1138255D03*
Y1131562D03*
X171341Y1141601D03*
X162641D03*
X171341Y1134908D03*
X162641D03*
X176199Y1161680D03*
Y1151641D03*
X171341Y1158333D03*
X162641D03*
X171341Y1148294D03*
X162641D03*
X176199Y1175066D03*
Y1168373D03*
X171341Y1171719D03*
X162641D03*
X171341Y1165026D03*
X162641D03*
X176199Y1188452D03*
Y1181759D03*
X171341Y1185105D03*
X162641D03*
X171341Y1178412D03*
X162641D03*
X176199Y1205184D03*
Y1198491D03*
X171341Y1208530D03*
X162641D03*
X171341Y1201837D03*
X162641D03*
X171341Y1195144D03*
X162641D03*
X176199Y1225263D03*
Y1218570D03*
Y1211877D03*
X162641Y1221916D03*
X171341D03*
Y1215223D03*
X162641D03*
X176199Y1241995D03*
Y1235302D03*
X171341Y1238648D03*
X162641D03*
X171341Y1231955D03*
X162641D03*
X176199Y1248688D03*
X171341Y1245341D03*
X162641D03*
X165546Y1273364D03*
X168346D03*
X192341Y766798D03*
X184899Y770144D03*
X192341Y780184D03*
Y773491D03*
X184899Y783530D03*
Y776837D03*
X192341Y803609D03*
Y796916D03*
Y790223D03*
X184899Y800263D03*
Y793570D03*
X192341Y816995D03*
Y810302D03*
X184899Y820341D03*
Y813648D03*
Y806955D03*
X192341Y833727D03*
X191491Y827034D03*
X184899Y830381D03*
X192341Y847113D03*
Y840420D03*
X184899Y850459D03*
Y843766D03*
Y837074D03*
X191491Y863845D03*
X184899Y867192D03*
X192341Y853806D03*
X184899Y857152D03*
X192341Y883924D03*
Y877231D03*
Y870538D03*
X184899Y880577D03*
Y873885D03*
X192341Y900656D03*
Y890617D03*
X184899Y893963D03*
Y887270D03*
X192341Y914042D03*
Y907349D03*
X184899Y917389D03*
Y910696D03*
Y904003D03*
X191491Y927428D03*
X192341Y920735D03*
X184899Y930774D03*
Y924081D03*
X192341Y937467D03*
Y944160D03*
X184899Y947507D03*
Y940814D03*
X192341Y960892D03*
Y950853D03*
X184899Y964239D03*
Y954200D03*
X192341Y974278D03*
Y980971D03*
Y967585D03*
X184899Y977625D03*
Y970932D03*
X192341Y987664D03*
X184899Y991011D03*
Y984318D03*
X192341Y1027822D03*
Y1017782D03*
X184899Y1031168D03*
Y1024475D03*
Y1017782D03*
X192341Y1047900D03*
Y1041207D03*
Y1034515D03*
X184899Y1044554D03*
Y1037861D03*
X192341Y1054593D03*
Y1061286D03*
X184899Y1057940D03*
Y1051247D03*
X192341Y1074672D03*
Y1067979D03*
X184899Y1078018D03*
Y1071326D03*
Y1064633D03*
X192341Y1091404D03*
X191491Y1084711D03*
X184899Y1094751D03*
Y1088058D03*
X192341Y1111483D03*
Y1104790D03*
Y1098097D03*
X184899Y1108137D03*
Y1101444D03*
X192341Y1128215D03*
Y1121522D03*
X184899Y1124869D03*
Y1114829D03*
X192341Y1141601D03*
Y1134908D03*
X184899Y1144948D03*
Y1138255D03*
Y1131562D03*
X191491Y1158333D03*
X192341Y1148294D03*
X184899Y1161680D03*
Y1151641D03*
X192341Y1171719D03*
Y1165026D03*
X184899Y1175066D03*
Y1168373D03*
X192341Y1185105D03*
Y1178412D03*
X184899Y1188452D03*
Y1181759D03*
X192341Y1208530D03*
Y1201837D03*
Y1195144D03*
X184899Y1205184D03*
Y1198491D03*
X192341Y1221916D03*
Y1215223D03*
X184899Y1225263D03*
Y1218570D03*
Y1211877D03*
X192341Y1238648D03*
X191491Y1231955D03*
X184899Y1241995D03*
Y1235302D03*
X184923Y1258871D03*
X192341Y1245341D03*
X184899Y1248688D03*
X192594Y1271262D03*
X192605Y1268774D03*
X182046Y1273364D03*
X179246D03*
X186697Y1578182D03*
Y1590094D03*
X191997Y1602380D03*
Y1614292D03*
X205899Y770144D03*
X201041Y766798D03*
X205899Y783530D03*
Y776837D03*
X201041Y780184D03*
Y773491D03*
X205899Y800263D03*
Y793570D03*
X201041Y803609D03*
Y796916D03*
Y790223D03*
X205899Y813648D03*
Y806955D03*
X205049Y820341D03*
X201041Y816995D03*
Y810302D03*
X205049Y830381D03*
X201041Y833727D03*
Y827034D03*
X205899Y850459D03*
Y837074D03*
Y843766D03*
X201041Y847113D03*
Y840420D03*
X205049Y867192D03*
X201041Y863845D03*
X205049Y857152D03*
X201041Y853806D03*
X205899Y873885D03*
Y880577D03*
X201041Y883924D03*
Y877231D03*
Y870538D03*
X205899Y893963D03*
Y887270D03*
X201041Y900656D03*
Y890617D03*
X205899Y917389D03*
Y910696D03*
Y904003D03*
X201041Y914042D03*
Y907349D03*
X205049Y930774D03*
Y924081D03*
X201041Y927428D03*
Y920735D03*
X205899Y940814D03*
Y947507D03*
X201041Y937467D03*
Y944160D03*
X205899Y964239D03*
Y954200D03*
X201041Y960892D03*
Y950853D03*
X205899Y970932D03*
Y977625D03*
X201041Y974278D03*
Y980971D03*
Y967585D03*
X205899Y991011D03*
Y984318D03*
X201041Y987664D03*
X205899Y1031168D03*
Y1017782D03*
Y1024475D03*
X201041Y1027822D03*
Y1017782D03*
X205899Y1044554D03*
Y1037861D03*
X201041Y1047900D03*
Y1041207D03*
Y1034515D03*
X205899Y1057940D03*
Y1051247D03*
X201041Y1054593D03*
Y1061286D03*
X205049Y1078018D03*
X205899Y1071326D03*
Y1064633D03*
X201041Y1074672D03*
Y1067979D03*
X205899Y1094751D03*
X205049Y1088058D03*
X201041Y1091404D03*
Y1084711D03*
X205899Y1101444D03*
Y1108137D03*
X201041Y1111483D03*
Y1104790D03*
Y1098097D03*
X205899Y1114829D03*
Y1124869D03*
X201041Y1128215D03*
Y1121522D03*
X205899Y1144948D03*
Y1138255D03*
Y1131562D03*
X201041Y1141601D03*
Y1134908D03*
X205049Y1161680D03*
Y1151641D03*
X201041Y1158333D03*
Y1148294D03*
X205899Y1168373D03*
Y1175066D03*
X201041Y1171719D03*
Y1165026D03*
X205899Y1188452D03*
Y1181759D03*
X201041Y1185105D03*
Y1178412D03*
X205899Y1205184D03*
Y1198491D03*
X201041Y1208530D03*
Y1201837D03*
Y1195144D03*
X205049Y1225263D03*
X205899Y1211877D03*
Y1218570D03*
X201041Y1221916D03*
Y1215223D03*
X205899Y1241995D03*
X205049Y1235302D03*
X201041Y1238648D03*
Y1231955D03*
X205899Y1248688D03*
X201041Y1245341D03*
X206268Y1271348D03*
X206337Y1268720D03*
X194497Y1578182D03*
X206557D03*
X198757D03*
X194497Y1590094D03*
X206557D03*
X198757D03*
X199797Y1614292D03*
Y1602380D03*
X204057Y1614292D03*
Y1602380D03*
X222041Y766798D03*
X214599Y770144D03*
X222041Y780184D03*
Y773491D03*
X214599Y783530D03*
Y776837D03*
X222041Y803609D03*
Y796916D03*
Y790223D03*
X214599Y800263D03*
Y793570D03*
X222041Y810302D03*
X221191Y816995D03*
X214599Y813648D03*
Y806955D03*
X215449Y820341D03*
X222041Y833727D03*
X221191Y827034D03*
X215449Y830381D03*
X222041Y847113D03*
Y840420D03*
X214599Y850459D03*
Y837074D03*
Y843766D03*
X221191Y863845D03*
X215449Y867192D03*
X222041Y853806D03*
X215449Y857152D03*
X222041Y877231D03*
X221191Y870538D03*
X222041Y883924D03*
X214599Y873885D03*
Y880577D03*
X222041Y900656D03*
Y890617D03*
X214599Y893963D03*
Y887270D03*
X222041Y914042D03*
Y907349D03*
X214599Y917389D03*
Y910696D03*
Y904003D03*
X221241Y927428D03*
X222041Y920735D03*
X215449Y930774D03*
Y924081D03*
X222041Y944160D03*
X221191Y937467D03*
X214599Y940814D03*
Y947507D03*
X222041Y960892D03*
Y950853D03*
X214599Y964239D03*
Y954200D03*
X222041Y980971D03*
Y974278D03*
Y967585D03*
X214599Y970932D03*
Y977625D03*
Y991011D03*
Y984318D03*
X222041Y987664D03*
Y1027822D03*
Y1017782D03*
X214599Y1031168D03*
Y1017782D03*
Y1024475D03*
X222041Y1047900D03*
Y1041207D03*
Y1034515D03*
X214599Y1044554D03*
Y1037861D03*
X222041Y1054593D03*
Y1061286D03*
X214599Y1057940D03*
Y1051247D03*
X222041Y1067979D03*
X221191Y1074672D03*
X215449Y1078018D03*
X214599Y1071326D03*
Y1064633D03*
X222041Y1091404D03*
X221191Y1084711D03*
X214599Y1094751D03*
X215449Y1088058D03*
X222041Y1111483D03*
Y1098097D03*
Y1104790D03*
X214599Y1101444D03*
Y1108137D03*
X222041Y1128215D03*
Y1121522D03*
X214599Y1114829D03*
Y1124869D03*
X222041Y1141601D03*
X221191Y1134908D03*
X214599Y1144948D03*
Y1138255D03*
Y1131562D03*
X222041Y1158333D03*
X221191Y1148294D03*
X215449Y1161680D03*
Y1151641D03*
X222041Y1165026D03*
Y1171719D03*
X214599Y1168373D03*
Y1175066D03*
X222041Y1185105D03*
Y1178412D03*
X214599Y1188452D03*
Y1181759D03*
X222041Y1208530D03*
Y1201837D03*
Y1195144D03*
X214599Y1205184D03*
Y1198491D03*
X222041Y1221916D03*
Y1215223D03*
X215449Y1225263D03*
X214599Y1211877D03*
Y1218570D03*
X221191Y1231955D03*
Y1238648D03*
X214599Y1241995D03*
X215449Y1235302D03*
X222041Y1245341D03*
X214824Y1258711D03*
X214599Y1248688D03*
X224987Y1273535D03*
X218617Y1578182D03*
X210817D03*
X222877D03*
X218617Y1590094D03*
X210817D03*
X222877D03*
X211857Y1614292D03*
Y1602380D03*
X223917Y1614292D03*
X216117D03*
X223917Y1602380D03*
X216117D03*
X235599Y770144D03*
X230741Y766798D03*
X235599Y783530D03*
Y776837D03*
X230741Y780184D03*
Y773491D03*
X235599Y800263D03*
Y793570D03*
X230741Y803609D03*
Y796916D03*
Y790223D03*
X234749Y820341D03*
Y813648D03*
X235599Y806955D03*
X230741Y810302D03*
X231006Y817554D03*
X235599Y830381D03*
X230741Y833727D03*
X231591Y827034D03*
X235599Y850459D03*
Y837074D03*
Y843766D03*
X230741Y847113D03*
Y840420D03*
X234749Y867492D03*
X231591Y863845D03*
X234749Y857152D03*
X230741Y853806D03*
X235599Y874185D03*
Y880577D03*
X230741Y877231D03*
X231059Y871084D03*
X230741Y883924D03*
X235599Y893963D03*
Y887270D03*
X230741Y900656D03*
Y890617D03*
X235599Y917389D03*
Y910696D03*
Y904003D03*
X230741Y914042D03*
Y907349D03*
X235599Y930774D03*
Y924081D03*
X231541Y927428D03*
X230741Y920735D03*
X235599Y947507D03*
X234859Y940814D03*
X230741Y944660D03*
X231591Y937467D03*
X235599Y964239D03*
Y954200D03*
X230741Y960892D03*
Y950853D03*
X235599Y977625D03*
Y970932D03*
X230741Y980971D03*
Y974278D03*
Y967585D03*
X235599Y991011D03*
X230741Y987664D03*
X235599Y984318D03*
Y1031168D03*
X230741Y1027822D03*
Y1017782D03*
X235599D03*
Y1024475D03*
Y1044554D03*
Y1037861D03*
X230741Y1047900D03*
Y1041207D03*
Y1034515D03*
X235599Y1051247D03*
Y1057940D03*
X230741Y1054593D03*
Y1061286D03*
X234749Y1078018D03*
X235599Y1071326D03*
Y1064633D03*
X230741Y1067979D03*
X231591Y1074672D03*
X235599Y1094751D03*
X234749Y1088058D03*
X230741Y1091404D03*
Y1084711D03*
X235599Y1108137D03*
Y1101444D03*
X230741Y1111483D03*
Y1098097D03*
Y1104790D03*
X234749Y1124869D03*
X235599Y1114829D03*
X230741Y1128215D03*
Y1121522D03*
X235599Y1144948D03*
Y1138255D03*
X234749Y1131562D03*
X230741Y1141601D03*
X231591Y1134908D03*
X235599Y1151641D03*
Y1161680D03*
X230741Y1158333D03*
X231591Y1148294D03*
X235599Y1175066D03*
Y1168373D03*
X230741Y1165026D03*
Y1171719D03*
X235599Y1188452D03*
Y1181759D03*
X230741Y1185105D03*
Y1178412D03*
X235599Y1205184D03*
Y1198491D03*
X230741Y1208530D03*
Y1201837D03*
Y1195144D03*
X234749Y1225263D03*
X235599Y1218570D03*
Y1211877D03*
X230741Y1221916D03*
Y1215223D03*
X235599Y1241995D03*
X235186Y1234977D03*
X231591Y1231955D03*
Y1238648D03*
X235599Y1248688D03*
X230741Y1245341D03*
X227746Y1273364D03*
X240966Y1273143D03*
X238971Y1274353D03*
X230677Y1578182D03*
X234937D03*
X230677Y1590094D03*
X234937D03*
X228177Y1614292D03*
X235977D03*
X228177Y1602380D03*
X235977D03*
X240237D03*
Y1614292D03*
X233268Y1679920D03*
Y1675383D03*
X241142Y1679320D03*
X233268Y1698627D03*
Y1694093D03*
Y1689556D03*
Y1684454D03*
X241142Y1683857D03*
Y1688391D03*
Y1693493D03*
Y1698030D03*
X233268Y1712800D03*
Y1708266D03*
Y1703729D03*
X241142Y1702564D03*
Y1707666D03*
Y1712203D03*
X233268Y1717903D03*
Y1722440D03*
Y1726974D03*
X241142Y1716737D03*
Y1730911D03*
Y1726377D03*
Y1721840D03*
X251741Y766798D03*
X244299Y770144D03*
X251741Y780184D03*
Y773491D03*
X244299Y783530D03*
Y776837D03*
X251741Y803609D03*
Y796916D03*
Y790223D03*
X244299Y800263D03*
Y793570D03*
X250891Y816995D03*
X251741Y810302D03*
X245149Y820341D03*
Y813648D03*
X244299Y806955D03*
X251741Y833727D03*
X250891Y827034D03*
X244299Y830381D03*
X251741Y847113D03*
Y840420D03*
X244299Y850459D03*
Y837074D03*
Y843766D03*
X250891Y863845D03*
Y853806D03*
X245149Y867192D03*
Y857152D03*
X251741Y870538D03*
Y883924D03*
Y877231D03*
X244299Y873885D03*
Y880577D03*
X250891Y900656D03*
X251741Y890617D03*
X244299Y893963D03*
Y887270D03*
X251741Y914042D03*
Y907349D03*
X244299Y917389D03*
Y910696D03*
Y904003D03*
X250891Y927428D03*
X251741Y920735D03*
X245149Y930774D03*
X244299Y924081D03*
X251741Y944160D03*
X250891Y937467D03*
X244299Y947507D03*
X245149Y940814D03*
X251741Y960892D03*
Y950853D03*
X244299Y964239D03*
Y954200D03*
X251741Y980971D03*
Y974278D03*
Y967585D03*
X244299Y977625D03*
Y970932D03*
X251741Y987664D03*
X244299Y991011D03*
Y984318D03*
Y1031168D03*
X251741Y1027822D03*
Y1017782D03*
X244299D03*
Y1024475D03*
X251741Y1047900D03*
Y1041207D03*
Y1034515D03*
X244299Y1044554D03*
Y1037861D03*
X251741Y1061286D03*
Y1054593D03*
X244299Y1051247D03*
Y1057940D03*
X250891Y1074672D03*
Y1067979D03*
X245149Y1078018D03*
X244299Y1071326D03*
Y1064633D03*
X251741Y1091404D03*
Y1084711D03*
X244299Y1094751D03*
X245149Y1088058D03*
X251741Y1104790D03*
X250891Y1111483D03*
X251741Y1098097D03*
X244299Y1108137D03*
Y1101444D03*
X251741Y1128215D03*
X250891Y1121522D03*
X245149Y1124869D03*
X244299Y1114829D03*
X251741Y1134908D03*
Y1141601D03*
X244299Y1144948D03*
Y1138255D03*
X245149Y1131562D03*
X251741Y1158333D03*
Y1148294D03*
X244299Y1151641D03*
Y1161680D03*
X251741Y1171719D03*
Y1165026D03*
X244299Y1175066D03*
Y1168373D03*
X251741Y1185105D03*
Y1178412D03*
X244299Y1188452D03*
Y1181759D03*
X251741Y1208530D03*
Y1201837D03*
X250891Y1195144D03*
X244299Y1205184D03*
Y1198491D03*
X250891Y1221916D03*
X251741Y1215223D03*
X245149Y1225263D03*
X244299Y1218570D03*
Y1211877D03*
X250891Y1231955D03*
X244299Y1241995D03*
X245149Y1235302D03*
X251741Y1238648D03*
X244299Y1248688D03*
X251741Y1245341D03*
X244789Y1260093D03*
X254897Y1274040D03*
X257197Y1273640D03*
X242737Y1578182D03*
X246997D03*
X254797D03*
X242737Y1590094D03*
X246997D03*
X254797D03*
X248037Y1602380D03*
Y1614292D03*
X252297Y1602380D03*
Y1614292D03*
X249016Y1675383D03*
Y1679920D03*
X256890Y1679320D03*
X249016Y1684454D03*
Y1689556D03*
Y1694093D03*
Y1698627D03*
X256890Y1683857D03*
Y1688391D03*
Y1693493D03*
Y1698030D03*
X249016Y1703729D03*
Y1708266D03*
Y1712800D03*
X256890Y1702564D03*
Y1707666D03*
Y1712203D03*
X249016Y1726974D03*
Y1722440D03*
Y1717903D03*
X256890Y1716737D03*
Y1730911D03*
Y1726377D03*
Y1721840D03*
X260441Y766798D03*
Y780184D03*
Y773491D03*
Y803609D03*
Y796916D03*
Y790223D03*
X261291Y816995D03*
X260441Y810302D03*
Y833727D03*
X261291Y827034D03*
X260441Y847113D03*
Y840420D03*
X261291Y863845D03*
Y853806D03*
X260441Y870538D03*
Y883924D03*
Y877231D03*
Y900656D03*
Y890617D03*
Y914042D03*
Y907349D03*
X261291Y927428D03*
X260441Y920735D03*
Y944160D03*
X261291Y937467D03*
X260441Y960892D03*
Y950853D03*
Y980971D03*
Y974278D03*
Y967585D03*
Y987664D03*
Y1027822D03*
Y1017782D03*
Y1047900D03*
Y1041207D03*
Y1034515D03*
Y1061286D03*
Y1054593D03*
X261291Y1074672D03*
Y1067979D03*
X260441Y1091404D03*
Y1084711D03*
Y1104790D03*
X261291Y1111483D03*
X260441Y1098097D03*
Y1128215D03*
X261291Y1121522D03*
X260441Y1134908D03*
Y1141601D03*
Y1158333D03*
Y1148294D03*
Y1171719D03*
Y1165026D03*
Y1185105D03*
Y1178412D03*
Y1208530D03*
Y1201837D03*
Y1195144D03*
X261291Y1221916D03*
X260441Y1215223D03*
X261291Y1231955D03*
X260441Y1238648D03*
Y1245341D03*
X266857Y1578182D03*
X259057D03*
X271117D03*
X266857Y1590094D03*
X259057D03*
X271117D03*
X260097Y1602380D03*
Y1614292D03*
X272157Y1602380D03*
Y1614292D03*
X264357D03*
Y1602380D03*
X264764Y1675383D03*
Y1679920D03*
X272638Y1679320D03*
X264764Y1684454D03*
Y1689556D03*
Y1694093D03*
Y1698627D03*
X272638Y1683857D03*
Y1688391D03*
Y1693493D03*
Y1698030D03*
X264764Y1703729D03*
Y1708266D03*
Y1712800D03*
X272638Y1702564D03*
Y1707666D03*
Y1712203D03*
X264764Y1726974D03*
Y1722440D03*
Y1717903D03*
X272638Y1716737D03*
Y1730911D03*
Y1726377D03*
Y1721840D03*
X278917Y1578182D03*
X283177D03*
X278917Y1590094D03*
X283177D03*
X284217Y1602380D03*
Y1614292D03*
X276417D03*
Y1602380D03*
X288477Y1614292D03*
Y1602380D03*
X280512Y1675383D03*
Y1679920D03*
Y1684454D03*
Y1689556D03*
Y1694093D03*
Y1698627D03*
Y1703729D03*
Y1708266D03*
Y1712800D03*
Y1726974D03*
Y1722440D03*
Y1717903D03*
X290977Y1578182D03*
X295237D03*
X303037D03*
X290977Y1590094D03*
X295237D03*
X303037D03*
X296277Y1614292D03*
Y1602380D03*
X300537D03*
Y1614292D03*
X300197Y1679920D03*
Y1675383D03*
Y1698627D03*
Y1694093D03*
Y1689556D03*
Y1684454D03*
Y1712800D03*
Y1708266D03*
Y1703729D03*
Y1717903D03*
Y1722440D03*
Y1726974D03*
X315097Y1578182D03*
X307297D03*
X319357D03*
X315097Y1590094D03*
X307297D03*
X319357D03*
X308337Y1602380D03*
Y1614292D03*
X320397D03*
X312597D03*
X320397Y1602380D03*
X312597D03*
X308071Y1679320D03*
X315945Y1679920D03*
Y1675383D03*
X308071Y1683857D03*
Y1698030D03*
Y1693493D03*
Y1688391D03*
X315945Y1698627D03*
Y1694093D03*
Y1689556D03*
Y1684454D03*
X308071Y1702564D03*
Y1712203D03*
Y1707666D03*
X315945Y1712800D03*
Y1708266D03*
Y1703729D03*
X308071Y1716737D03*
Y1721840D03*
Y1726377D03*
Y1730911D03*
X315945Y1717903D03*
Y1722440D03*
Y1726974D03*
X327157Y1578182D03*
X331417D03*
X327157Y1590094D03*
X331417D03*
X324657Y1602380D03*
X332457D03*
X324657Y1614292D03*
X332457D03*
X336717Y1602380D03*
Y1614292D03*
X323819Y1679320D03*
X331693Y1679920D03*
Y1675383D03*
X323819Y1683857D03*
Y1698030D03*
Y1693493D03*
Y1688391D03*
X331693Y1698627D03*
Y1694093D03*
Y1689556D03*
Y1684454D03*
X323819Y1702564D03*
Y1712203D03*
Y1707666D03*
X331693Y1712800D03*
Y1708266D03*
Y1703729D03*
X323819Y1716737D03*
Y1721840D03*
Y1726377D03*
Y1730911D03*
X331693Y1717903D03*
Y1722440D03*
Y1726974D03*
X352579Y854584D03*
X347029Y870606D03*
Y889832D03*
X343707Y1091513D03*
X339217Y1578182D03*
X343477D03*
X351277D03*
X339217Y1590094D03*
X343477D03*
X351277D03*
X344517Y1602380D03*
Y1614292D03*
X348777Y1602380D03*
Y1614292D03*
X339567Y1679320D03*
X347441Y1679920D03*
Y1675383D03*
X355315Y1679320D03*
X339567Y1683857D03*
Y1698030D03*
Y1693493D03*
Y1688391D03*
X347441Y1698627D03*
Y1694093D03*
Y1689556D03*
Y1684454D03*
X355315Y1683857D03*
Y1698030D03*
Y1693493D03*
Y1688391D03*
X339567Y1702564D03*
Y1712203D03*
Y1707666D03*
X347441Y1712800D03*
Y1708266D03*
Y1703729D03*
X355315Y1702564D03*
Y1712203D03*
Y1707666D03*
X339567Y1716737D03*
Y1721840D03*
Y1726377D03*
Y1730911D03*
X347441Y1717903D03*
Y1722440D03*
Y1726974D03*
X355315Y1716737D03*
Y1721840D03*
Y1726377D03*
Y1730911D03*
X359979Y841467D03*
X367379D03*
X365529Y851380D03*
X369229D03*
X359979Y880219D03*
Y899445D03*
X371078D03*
X359979Y918670D03*
X365529Y941100D03*
X359979Y937896D03*
X371078D03*
X369662Y1006093D03*
X365962Y1076587D03*
X363337Y1578088D03*
X355537Y1578182D03*
X367597D03*
X363337Y1590094D03*
X355537D03*
X367597D03*
X356577Y1602380D03*
Y1614292D03*
X368637D03*
X360837D03*
X368637Y1602286D03*
X360837Y1602380D03*
X382179Y841467D03*
X374779D03*
X380329Y851380D03*
X376629D03*
X372929D03*
X384029D03*
X387729D03*
X378478Y931488D03*
X378911Y1060565D03*
X375397Y1578182D03*
Y1590094D03*
X372897Y1602380D03*
X380697D03*
X372897Y1614292D03*
X380697D03*
X389579Y841467D03*
X396978Y899445D03*
Y937896D03*
X415185Y985580D03*
X417575D03*
X415185Y1014540D03*
X417575D03*
X435829Y851380D03*
Y864197D03*
Y877014D03*
Y889832D03*
Y902649D03*
X428429Y921875D03*
X430279Y937897D03*
X433979D03*
X433980Y944305D03*
Y957123D03*
Y950714D03*
Y963531D03*
Y976348D03*
Y969940D03*
Y982757D03*
X434411Y1009298D03*
X434412Y1002889D03*
X434411Y1028524D03*
Y1022115D03*
X434412Y1015706D03*
Y1034932D03*
X434411Y1092608D03*
X450629Y851380D03*
Y877014D03*
X437678Y912262D03*
X441379Y937897D03*
X445079D03*
X437679D03*
X446929Y941101D03*
X446930Y947510D03*
Y960327D03*
Y953918D03*
Y966736D03*
Y979553D03*
Y973144D03*
X447362Y1006094D03*
Y999685D03*
Y1012502D03*
Y1025319D03*
Y1018911D03*
Y1031728D03*
X456178Y912262D03*
X461729Y921875D03*
X462261Y942152D03*
X464561D03*
X466861D03*
X454423Y949139D03*
X454393Y963829D03*
Y966129D03*
X463874Y956540D03*
X466272D03*
X454423Y951439D03*
X466272Y971100D03*
X463874Y971140D03*
X454263Y981209D03*
Y978909D03*
X454463Y995299D03*
Y992999D03*
X466272Y985580D03*
X463874D03*
X466272Y1014540D03*
X463874D03*
X454443Y1009409D03*
Y1007109D03*
X466272Y1000060D03*
X463874D03*
X468895Y1014550D03*
X465862Y1057361D03*
X458462Y1063770D03*
X465862D03*
X456611Y1073383D03*
X454762Y1070178D03*
X467711Y1073383D03*
Y1066974D03*
X474678Y899445D03*
Y912262D03*
X480229Y921875D03*
X471204Y1014540D03*
X475111Y1060565D03*
X484361Y1057361D03*
X475111Y1066974D03*
X473262Y1070178D03*
X478811Y1073383D03*
X484361Y1076587D03*
X482512Y1066974D03*
X478812Y1079791D03*
X475111D03*
X482911Y1578182D03*
X478651D03*
X470851D03*
X482911Y1590094D03*
X478651D03*
X470851D03*
X483951Y1614292D03*
Y1602380D03*
X476151D03*
Y1614292D03*
X489478Y912262D03*
X495462Y1057361D03*
X499162Y1063770D03*
X495462Y1076587D03*
X493612Y1073383D03*
X486211D03*
X497311Y1066974D03*
X495462Y1108630D03*
X493611Y1111834D03*
X494971Y1578182D03*
X490711D03*
X494971Y1590094D03*
X490711D03*
X500271Y1614292D03*
Y1602380D03*
X488211Y1614292D03*
Y1602380D03*
X496011D03*
Y1614292D03*
X497441Y1675383D03*
Y1679920D03*
Y1684454D03*
Y1689556D03*
Y1694093D03*
Y1698627D03*
Y1703729D03*
Y1708266D03*
Y1712800D03*
Y1726974D03*
Y1722440D03*
Y1717903D03*
X507978Y937896D03*
X509829Y947509D03*
X510262Y1057361D03*
X506562Y1063770D03*
X510262Y1076587D03*
X512111Y1073383D03*
X508411Y1066974D03*
X515811D03*
X508411Y1079791D03*
X515811Y1086200D03*
X507031Y1578182D03*
X514831D03*
X502771D03*
X507031Y1590094D03*
X514831D03*
X502771D03*
X512331Y1614292D03*
Y1602380D03*
X508071Y1614292D03*
Y1602380D03*
X513189Y1675383D03*
Y1679920D03*
X505315Y1679320D03*
X513189Y1684454D03*
Y1689556D03*
Y1694093D03*
Y1698627D03*
X505315Y1688391D03*
Y1693493D03*
Y1698030D03*
Y1683857D03*
X513189Y1703729D03*
Y1708266D03*
Y1712800D03*
X505315Y1707666D03*
Y1712203D03*
Y1702564D03*
X513189Y1726974D03*
Y1722440D03*
Y1717903D03*
X505315Y1730911D03*
Y1726377D03*
Y1721840D03*
Y1716737D03*
X521362Y1057361D03*
X525061Y1063770D03*
X532462D03*
X521362Y1076587D03*
X519512Y1073383D03*
X523211Y1066974D03*
X534311D03*
X531151Y1578182D03*
X519091D03*
X526891D03*
X531151Y1590094D03*
X519091D03*
X526891D03*
X532191Y1614292D03*
Y1602380D03*
X524391Y1614292D03*
Y1602380D03*
X520131D03*
Y1614292D03*
X528937Y1675383D03*
Y1679920D03*
X521063Y1679320D03*
X528937Y1684454D03*
Y1689556D03*
Y1694093D03*
Y1698627D03*
X521063Y1688391D03*
Y1693493D03*
Y1698030D03*
Y1683857D03*
X528937Y1703729D03*
Y1708266D03*
Y1712800D03*
X521063Y1707666D03*
Y1712203D03*
Y1702564D03*
X528937Y1726974D03*
Y1722440D03*
Y1717903D03*
X521063Y1730911D03*
Y1726377D03*
Y1721840D03*
Y1716737D03*
X543129Y928283D03*
X539429D03*
X537578Y925079D03*
X535729Y928283D03*
X548678Y925079D03*
X537578Y944304D03*
X548678D03*
X536161Y1057361D03*
X549422Y1064850D03*
X541711Y1073383D03*
X545411Y1066974D03*
X536161Y1076587D03*
X536162Y1070178D03*
X538011Y1073383D03*
X547262Y1070178D03*
X543211Y1578182D03*
X538951D03*
X543211Y1590094D03*
X538951D03*
X548511Y1614292D03*
Y1602380D03*
X536451D03*
Y1614292D03*
X544251Y1602380D03*
Y1614292D03*
X544685Y1675383D03*
Y1679920D03*
X536811Y1679320D03*
X544685Y1684454D03*
Y1689556D03*
Y1694093D03*
Y1698627D03*
X536811Y1688391D03*
Y1693493D03*
Y1698030D03*
Y1683857D03*
X544685Y1703729D03*
Y1708266D03*
Y1712800D03*
X536811Y1707666D03*
Y1712203D03*
Y1702564D03*
X544685Y1726974D03*
Y1722440D03*
Y1717903D03*
X536811Y1730911D03*
Y1726377D03*
Y1721840D03*
Y1716737D03*
X555271Y1578182D03*
X563071D03*
X551011D03*
X555271Y1590094D03*
X563071D03*
X551011D03*
X560571Y1602380D03*
X556311Y1614292D03*
Y1602380D03*
X552559Y1679320D03*
X564370Y1675383D03*
Y1679920D03*
X552559Y1688391D03*
Y1693493D03*
Y1698030D03*
Y1683857D03*
X564370Y1684454D03*
Y1689556D03*
Y1694093D03*
Y1698627D03*
X552559Y1707666D03*
Y1712203D03*
Y1702564D03*
X564370Y1703729D03*
Y1708266D03*
Y1712800D03*
X552559Y1730911D03*
Y1726377D03*
Y1721840D03*
Y1716737D03*
X564370Y1726974D03*
Y1722440D03*
Y1717903D03*
X579391Y1578182D03*
X567331D03*
X575131D03*
X579391Y1590094D03*
X567331D03*
X575131D03*
X580431Y1614292D03*
X572631D03*
Y1602380D03*
X568371D03*
Y1614292D03*
X580118Y1675383D03*
Y1679920D03*
X572244Y1679320D03*
X580118Y1684454D03*
Y1689556D03*
Y1694093D03*
Y1698627D03*
X572244Y1688391D03*
Y1693493D03*
Y1698030D03*
Y1683857D03*
X580118Y1703729D03*
Y1708266D03*
Y1712800D03*
X572244Y1707666D03*
Y1712203D03*
Y1702564D03*
X580118Y1726974D03*
Y1722440D03*
Y1717903D03*
X572244Y1730911D03*
Y1726377D03*
Y1721840D03*
Y1716737D03*
X599251Y1578182D03*
X591451D03*
X587191D03*
X599251Y1590094D03*
X591451D03*
X587191D03*
X596751Y1614292D03*
Y1602380D03*
X584691D03*
Y1614292D03*
X592491Y1602380D03*
Y1614292D03*
X595866Y1675383D03*
Y1679920D03*
X587992Y1679320D03*
X595866Y1684454D03*
Y1689556D03*
Y1694093D03*
Y1698627D03*
X587992Y1688391D03*
Y1693493D03*
Y1698030D03*
Y1683857D03*
X595866Y1703729D03*
Y1708266D03*
Y1712800D03*
X587992Y1707666D03*
Y1712203D03*
Y1702564D03*
X595866Y1726974D03*
Y1722440D03*
Y1717903D03*
X587992Y1730911D03*
Y1726377D03*
Y1721840D03*
Y1716737D03*
X615571Y1578182D03*
X603511D03*
X611311D03*
X615571Y1590094D03*
X603511D03*
X611311D03*
X608811Y1602380D03*
Y1614292D03*
X604551Y1602380D03*
Y1614292D03*
X611614Y1675383D03*
Y1679920D03*
X603740Y1679320D03*
X611614Y1684454D03*
Y1689556D03*
Y1694093D03*
Y1698627D03*
X603740Y1688391D03*
Y1693493D03*
Y1698030D03*
Y1683857D03*
X611614Y1703729D03*
Y1708266D03*
Y1712800D03*
X603740Y1707666D03*
Y1712203D03*
Y1702564D03*
X611614Y1726974D03*
Y1722440D03*
Y1717903D03*
X603740Y1730911D03*
Y1726377D03*
Y1721840D03*
Y1716737D03*
X629599Y770144D03*
X620899D03*
X629599Y783530D03*
X620899D03*
X629599Y776837D03*
X620899D03*
X620846Y800263D03*
X629599D03*
Y793570D03*
X620899D03*
Y820341D03*
X629599D03*
X620076Y813648D03*
X630593D03*
X619632Y806955D03*
X630792D03*
X620899Y830381D03*
X629599D03*
X620005Y850459D03*
X630754D03*
X620899Y843766D03*
X629599D03*
Y837074D03*
X620899D03*
Y867192D03*
X629599D03*
X620058Y857152D03*
X630481D03*
X620899Y880577D03*
X629599D03*
X620899Y873885D03*
X629599D03*
X630756Y893963D03*
X620899D03*
X629599Y887270D03*
X620899D03*
Y910696D03*
X629599D03*
Y917389D03*
X620899D03*
X629599Y904003D03*
X620899D03*
X630399Y930697D03*
X619905Y930774D03*
X620899Y924081D03*
X629599D03*
Y947507D03*
X620899D03*
X619964Y940814D03*
X630777D03*
X629599Y964239D03*
X620899D03*
X629599Y954200D03*
X620899D03*
Y977625D03*
X629599D03*
Y970932D03*
X620899D03*
Y991011D03*
X629599D03*
Y984318D03*
X620899D03*
Y1031168D03*
X629599D03*
X620899Y1017782D03*
X629599D03*
X620899Y1024475D03*
X629599D03*
X620899Y1044554D03*
X629599D03*
X620899Y1037861D03*
X629599D03*
X620899Y1057940D03*
X629599D03*
Y1051247D03*
X620899D03*
Y1078018D03*
X629599D03*
X630399Y1071326D03*
X619999D03*
X620899Y1064633D03*
X629599D03*
X620899Y1088058D03*
X629599D03*
Y1094751D03*
X620899D03*
Y1108137D03*
X629599D03*
Y1101444D03*
X620899D03*
X630363Y1124674D03*
X620369Y1124969D03*
X630399Y1114829D03*
X620099D03*
X620899Y1131562D03*
X629599D03*
Y1144948D03*
X620899D03*
X629599Y1138255D03*
X620899D03*
X620511Y1161680D03*
X629833Y1161581D03*
X629599Y1151641D03*
X620899D03*
X629599Y1175066D03*
X620899D03*
X629599Y1168373D03*
X620899D03*
X630623Y1188452D03*
X620899D03*
X629599Y1181759D03*
X620899D03*
X629599Y1205184D03*
X620899D03*
Y1198491D03*
X629599D03*
X620899Y1225263D03*
X629599D03*
Y1218570D03*
X620899D03*
X629599Y1211877D03*
X620899D03*
X629599Y1241995D03*
X620899D03*
X630922Y1235302D03*
X620036D03*
X620899Y1248688D03*
X629599D03*
X625246Y1273164D03*
X627646D03*
X627631Y1578182D03*
X623371D03*
X627631Y1590094D03*
X623371D03*
X628671Y1602380D03*
Y1614292D03*
X620871D03*
Y1602380D03*
X616611Y1614292D03*
Y1602380D03*
X619488Y1679320D03*
Y1688391D03*
Y1693493D03*
Y1698030D03*
Y1683857D03*
Y1707666D03*
Y1712203D03*
Y1702564D03*
Y1730911D03*
Y1726377D03*
Y1721840D03*
Y1716737D03*
X637041Y766798D03*
X645741D03*
Y773491D03*
X637041D03*
X645741Y780184D03*
X637041D03*
Y803609D03*
X645741D03*
X637041Y796916D03*
X645741D03*
Y790223D03*
X637041D03*
X636221Y810302D03*
X646844D03*
X646774Y816995D03*
X637041D03*
X645741Y833727D03*
X637041D03*
Y827034D03*
X645741D03*
X637041Y847113D03*
X645801D03*
X637041Y840420D03*
X645741D03*
X646819Y853806D03*
X636332Y853955D03*
X645918Y863845D03*
X636266D03*
X637041Y877231D03*
X645741D03*
X637041Y870538D03*
X645741D03*
Y883924D03*
X637041D03*
Y900656D03*
X645741D03*
X637041Y890617D03*
X645741D03*
X637041Y914042D03*
X645741D03*
Y907349D03*
X637041D03*
X646393Y927526D03*
X636026Y927428D03*
X645741Y920735D03*
X637041D03*
X645741Y944160D03*
X637041D03*
X636170Y937467D03*
X646703D03*
X645741Y960892D03*
X637041D03*
Y950853D03*
X645741D03*
X637041Y980971D03*
X645741D03*
X637041Y974278D03*
X645741D03*
X637041Y967585D03*
X645741D03*
X637041Y987664D03*
X645741D03*
X637041Y1027822D03*
X645741D03*
Y1017782D03*
X637041D03*
X645741Y1047900D03*
X637041D03*
Y1041207D03*
X645741D03*
X637041Y1034515D03*
X645741D03*
X637041Y1061286D03*
X645741D03*
Y1054593D03*
X637041D03*
X636141Y1074672D03*
X646541D03*
X645741Y1067979D03*
X636841D03*
X637041Y1091404D03*
X645741D03*
Y1084711D03*
X636241D03*
X645741Y1111483D03*
X637041D03*
X645741Y1098097D03*
X637041D03*
X645741Y1104790D03*
X637041D03*
Y1121522D03*
X645741D03*
X637041Y1128915D03*
X645741Y1128215D03*
X646584Y1135108D03*
X635744Y1134908D03*
X645741Y1141601D03*
X637041D03*
X645741Y1148294D03*
X637041D03*
X645741Y1158333D03*
X637041D03*
Y1171719D03*
X645741D03*
Y1165026D03*
X637041D03*
Y1185105D03*
X645741D03*
Y1178412D03*
X637041D03*
X645741Y1208530D03*
X637041D03*
X645741Y1201837D03*
X637041D03*
Y1195144D03*
X645741D03*
X636005Y1221916D03*
X646570D03*
X645741Y1215223D03*
X637041D03*
X645741Y1238648D03*
X637041D03*
X635995Y1231862D03*
X646539Y1231955D03*
X645741Y1245341D03*
X637041D03*
X634213Y1258679D03*
X642746Y1273364D03*
X639946D03*
X647491Y1578088D03*
X639691Y1578182D03*
X635431D03*
X647491Y1590094D03*
X639691D03*
X635431D03*
X644991Y1614292D03*
Y1602380D03*
X632931D03*
Y1614292D03*
X640731D03*
Y1602380D03*
X650599Y770144D03*
X659299D03*
X650599Y783530D03*
X659299D03*
X650599Y776837D03*
X659299D03*
Y800263D03*
X650599D03*
Y793570D03*
X659299D03*
Y806955D03*
X650599D03*
X660432Y813648D03*
X650599D03*
X660199Y820341D03*
X650599D03*
X659299Y830381D03*
X650599D03*
X659299Y850459D03*
X650599D03*
X659299Y843766D03*
X650599D03*
Y837074D03*
X659299D03*
Y857152D03*
X650599D03*
X649563Y867192D03*
X660299D03*
X659299Y873885D03*
X650599D03*
Y880577D03*
X659299D03*
X650599Y893963D03*
X659299D03*
X650599Y887270D03*
X659299D03*
Y917389D03*
X650599D03*
X659299Y910696D03*
X650599D03*
Y904003D03*
X659299D03*
X660504Y924081D03*
X650599D03*
X660174Y930774D03*
X649661D03*
X659299Y947507D03*
X650599D03*
X659299Y940814D03*
X650599D03*
X659299Y964239D03*
X650599D03*
Y954200D03*
X659299D03*
Y977625D03*
X650599D03*
X659299Y970932D03*
X650599D03*
X659299Y991011D03*
X650599D03*
X659299Y984318D03*
X650599D03*
X659299Y1031168D03*
X650599D03*
X659299Y1017782D03*
X650599D03*
X659299Y1024475D03*
X650599D03*
X659299Y1044554D03*
X650599D03*
X659299Y1037861D03*
X650599D03*
X659299Y1051247D03*
X650599D03*
Y1057940D03*
X659299D03*
X660099Y1078018D03*
X649799D03*
X659299Y1071326D03*
X650599D03*
X659299Y1064633D03*
X650599D03*
X659299Y1094751D03*
X650599D03*
X660099Y1088058D03*
X649799D03*
X650599Y1108137D03*
X659299D03*
X650599Y1101444D03*
X659299D03*
X660199Y1124869D03*
X649932Y1124640D03*
X659299Y1114829D03*
X650599D03*
X659299Y1130762D03*
X650599D03*
X659299Y1138255D03*
X650599D03*
X659299Y1144948D03*
X650599D03*
X659299Y1151641D03*
X650599D03*
Y1161680D03*
X659299D03*
X650599Y1175066D03*
X659299D03*
X650599Y1168373D03*
X659299D03*
X650599Y1188452D03*
X659299D03*
X650599Y1181759D03*
X659299D03*
X650599Y1205184D03*
X659299D03*
X650599Y1198491D03*
X659299D03*
X660070Y1225263D03*
X649913D03*
X659299Y1218570D03*
X650599D03*
X659299Y1211877D03*
X650599D03*
X659299Y1241995D03*
X650599D03*
X660234Y1235302D03*
X649701D03*
X650599Y1248688D03*
X659299D03*
X659546Y1257664D03*
X656446Y1273364D03*
X653646D03*
X651751Y1578182D03*
X659551D03*
X651751Y1590094D03*
X659551D03*
X657051Y1602380D03*
Y1614292D03*
X652791Y1602286D03*
Y1614292D03*
X680299Y770144D03*
X675441Y766798D03*
X666741D03*
X680299Y783530D03*
Y776837D03*
X666741Y773491D03*
X675441D03*
X666741Y780184D03*
X675441D03*
Y803609D03*
X666741D03*
X680299Y800263D03*
Y793570D03*
X666741Y796916D03*
X675441D03*
X666741Y790223D03*
X675441D03*
X676403Y816995D03*
X665803D03*
X675441Y810302D03*
X666741D03*
X680299Y820341D03*
Y813648D03*
Y806955D03*
X675441Y833727D03*
X666741D03*
X676625Y827034D03*
X665876D03*
X680299Y830381D03*
X675441Y847113D03*
X666741D03*
X680299Y850459D03*
Y843766D03*
Y837074D03*
X666741Y840420D03*
X675441D03*
X676417Y853806D03*
X665890D03*
X680299Y867192D03*
Y857152D03*
X665916Y863845D03*
X676600D03*
X675441Y877231D03*
X666741D03*
X675441Y870538D03*
X666741D03*
Y883924D03*
X675441D03*
X680299Y880577D03*
Y873885D03*
X666741Y900656D03*
X675441D03*
X680299Y893963D03*
Y887270D03*
X666741Y890617D03*
X675441D03*
Y914042D03*
X666741D03*
X680299Y917389D03*
Y910696D03*
Y904003D03*
X666741Y907349D03*
X675441D03*
X676488Y927428D03*
X665896D03*
X675441Y920735D03*
X666741D03*
X680299Y930774D03*
Y924081D03*
X675441Y944160D03*
X666741D03*
X676359Y937467D03*
X665923D03*
X680299Y947507D03*
Y940814D03*
Y964239D03*
X675441Y960892D03*
X666741D03*
X680299Y954200D03*
X666741Y950853D03*
X675441D03*
Y980971D03*
X666741D03*
X680299Y970932D03*
X675441Y974278D03*
X666741D03*
X675441Y967585D03*
X666741D03*
X680299Y977625D03*
X675441Y987664D03*
X666741D03*
X680299Y991011D03*
Y984318D03*
Y1031168D03*
Y1024475D03*
X675441Y1027822D03*
X666741D03*
X675441Y1017782D03*
X666741D03*
X680299D03*
X675441Y1047900D03*
X666741D03*
X680299Y1037861D03*
X675441Y1041207D03*
X666741D03*
X675441Y1034515D03*
X666741D03*
X680299Y1044554D03*
Y1057940D03*
Y1051247D03*
X675441Y1054593D03*
X666741D03*
Y1061286D03*
X675441D03*
X676341Y1074672D03*
X665841D03*
X675441Y1067979D03*
X666741D03*
X680299Y1078018D03*
Y1071326D03*
Y1064633D03*
X675441Y1091404D03*
X666741D03*
X676241Y1084711D03*
X665941D03*
X680299Y1094751D03*
Y1088058D03*
X666741Y1111483D03*
X675441D03*
X680299Y1108137D03*
Y1101444D03*
X666741Y1104790D03*
X675441D03*
X666741Y1098097D03*
X675441D03*
X666741Y1128215D03*
X675441D03*
X680299Y1124869D03*
Y1114829D03*
X666741Y1121522D03*
X675441D03*
X680299Y1144948D03*
Y1138255D03*
Y1131562D03*
X666741Y1141601D03*
X675441D03*
X666741Y1134908D03*
X675441D03*
X676652Y1148294D03*
X665602D03*
X676241Y1158333D03*
X665941D03*
X680299Y1161680D03*
Y1151641D03*
X675441Y1165026D03*
X666741D03*
X680299Y1175066D03*
Y1168373D03*
X666741Y1171719D03*
X675441D03*
X680299Y1188452D03*
Y1181759D03*
X666741Y1185105D03*
X675441D03*
X666741Y1178412D03*
X675441D03*
X680299Y1205184D03*
Y1198491D03*
X666741Y1208530D03*
X675441D03*
X666741Y1201837D03*
X675441D03*
X666741Y1195144D03*
X675441D03*
X680299Y1218570D03*
Y1225263D03*
X676448Y1221916D03*
X665651D03*
X675441Y1215223D03*
X666741D03*
X680299Y1211877D03*
X675441Y1238648D03*
X666741D03*
X676462Y1231955D03*
X665912D03*
X680299Y1241995D03*
Y1235302D03*
X675441Y1245341D03*
X666741D03*
X676046Y1257964D03*
X680299Y1248688D03*
X672446Y1273364D03*
X669646D03*
X664851Y1602380D03*
Y1614292D03*
X696441Y766798D03*
X688999Y770144D03*
X696441Y773491D03*
Y780184D03*
X688999Y783530D03*
Y776837D03*
X696441Y803609D03*
Y796916D03*
Y790223D03*
X688999Y800263D03*
Y793570D03*
X696441Y816995D03*
Y810302D03*
X689888Y820341D03*
X688999Y813648D03*
Y806955D03*
X696441Y833727D03*
Y827034D03*
X688999Y830381D03*
X696441Y847113D03*
X688999Y850459D03*
X696441Y840420D03*
X688999Y843766D03*
Y837074D03*
X696441Y863845D03*
Y853806D03*
X688999Y867192D03*
X689896Y857152D03*
X696441Y883924D03*
Y877231D03*
Y870538D03*
X688999Y880577D03*
Y873885D03*
X696441Y900656D03*
Y890617D03*
X688999Y893963D03*
Y887270D03*
X696441Y914042D03*
Y907349D03*
X688999Y917389D03*
Y910696D03*
Y904003D03*
X696441Y927428D03*
Y920735D03*
X690104Y930774D03*
X688999Y924081D03*
X696441Y944160D03*
Y937467D03*
X688999Y947507D03*
Y940814D03*
X696441Y960892D03*
Y950853D03*
X688999Y964239D03*
Y954200D03*
X696441Y980971D03*
Y974278D03*
Y967585D03*
X688999Y970932D03*
Y977625D03*
X696441Y987664D03*
X688999Y991011D03*
Y984318D03*
X696441Y1027822D03*
Y1017782D03*
X688999Y1031168D03*
Y1024475D03*
Y1017782D03*
X696441Y1047900D03*
Y1041207D03*
Y1034515D03*
X688999Y1037861D03*
Y1044554D03*
X696441Y1054593D03*
Y1061286D03*
X688999Y1057940D03*
X696441Y1074672D03*
Y1067979D03*
X688999Y1077118D03*
Y1071326D03*
Y1064633D03*
X696441Y1091404D03*
Y1084711D03*
X688999Y1094751D03*
Y1088058D03*
X696441Y1111483D03*
Y1104790D03*
Y1098097D03*
X688999Y1108137D03*
Y1101444D03*
X696441Y1128215D03*
Y1121522D03*
X688999Y1124869D03*
Y1114829D03*
X696441Y1141601D03*
Y1134908D03*
X688999Y1144948D03*
Y1138255D03*
Y1131562D03*
X696441Y1158333D03*
Y1148294D03*
X688999Y1161680D03*
X689999Y1151641D03*
X696441Y1171719D03*
Y1165026D03*
X688999Y1175066D03*
Y1168373D03*
X696441Y1185105D03*
Y1178412D03*
X688999Y1188452D03*
Y1181759D03*
X696441Y1208530D03*
Y1201837D03*
Y1195144D03*
X688999Y1205184D03*
Y1198491D03*
X696441Y1221916D03*
Y1215223D03*
X688999Y1218570D03*
X689799Y1225263D03*
X688999Y1211877D03*
X696441Y1238648D03*
Y1231955D03*
X688999Y1241995D03*
Y1235302D03*
X688916Y1256964D03*
X696441Y1245341D03*
X688999Y1248688D03*
X686146Y1273364D03*
X683346D03*
X709999Y770144D03*
X705141Y766798D03*
X709999Y783530D03*
Y776837D03*
X705141Y773491D03*
Y780184D03*
X709999Y800263D03*
Y793570D03*
X705141Y803609D03*
Y796916D03*
Y790223D03*
X709999Y820341D03*
Y813648D03*
Y806955D03*
X705141Y816995D03*
Y810302D03*
X709999Y830381D03*
X705141Y833727D03*
Y827034D03*
Y847113D03*
X709999Y850459D03*
Y843766D03*
Y837074D03*
X705141Y840420D03*
Y863845D03*
Y853806D03*
X709999Y867192D03*
Y857152D03*
X705141Y883924D03*
Y877231D03*
Y870538D03*
X709999Y880577D03*
Y873885D03*
X705141Y900656D03*
Y890617D03*
X709999Y893963D03*
Y887270D03*
X705141Y914042D03*
Y907349D03*
X709999Y917389D03*
Y910696D03*
Y904003D03*
X705141Y927428D03*
Y920735D03*
X709999Y930774D03*
Y924081D03*
X705141Y944160D03*
Y937467D03*
X709999Y947507D03*
Y940814D03*
X705141Y960892D03*
Y950853D03*
X709999Y964239D03*
Y954200D03*
X705141Y980971D03*
Y974278D03*
Y967585D03*
X709999Y977625D03*
Y970932D03*
X705141Y987664D03*
X709999Y991011D03*
Y984318D03*
X705141Y1027822D03*
Y1017782D03*
X709999Y1031168D03*
Y1024475D03*
Y1017782D03*
X705141Y1047900D03*
Y1041207D03*
Y1034515D03*
X709999Y1044554D03*
Y1037861D03*
X705141Y1054593D03*
Y1061286D03*
X709999Y1057940D03*
Y1051247D03*
X705141Y1074672D03*
Y1067979D03*
X709999Y1078018D03*
Y1071326D03*
Y1064633D03*
X705141Y1091404D03*
Y1084711D03*
X709999Y1094751D03*
Y1088058D03*
X705141Y1111483D03*
Y1104790D03*
Y1098097D03*
X709999Y1108137D03*
Y1101444D03*
X705141Y1128215D03*
Y1121522D03*
X709999Y1124869D03*
Y1114829D03*
X705141Y1141601D03*
Y1134908D03*
X709999Y1144948D03*
Y1138255D03*
Y1131562D03*
X705141Y1158333D03*
Y1148294D03*
X709999Y1161680D03*
Y1151641D03*
X705141Y1171719D03*
Y1165026D03*
X709999Y1175066D03*
Y1168373D03*
X705141Y1185105D03*
Y1178412D03*
X709999Y1188452D03*
Y1181759D03*
X705141Y1208530D03*
Y1201837D03*
Y1195144D03*
X709999Y1205184D03*
Y1198491D03*
X705141Y1221916D03*
Y1215223D03*
X709999Y1225263D03*
Y1218570D03*
Y1211877D03*
X705141Y1238648D03*
Y1231955D03*
X709999Y1241995D03*
Y1235302D03*
X705141Y1245341D03*
X709999Y1248688D03*
X713046Y1273364D03*
X702146D03*
X699346D03*
X726141Y766798D03*
X718699Y770144D03*
X726141Y773491D03*
Y780184D03*
X718699Y783530D03*
Y776837D03*
X726141Y803609D03*
Y796916D03*
Y790223D03*
X718699Y800263D03*
Y793570D03*
X726141Y816995D03*
Y810302D03*
X718699Y820341D03*
Y813648D03*
Y806955D03*
X726141Y833727D03*
Y827034D03*
X718699Y830381D03*
X726141Y847113D03*
Y840420D03*
X718699Y850459D03*
Y843766D03*
Y837074D03*
X726141Y863845D03*
Y853806D03*
X718699Y867192D03*
Y857152D03*
X726141Y883924D03*
Y877231D03*
Y870538D03*
X718699Y880577D03*
Y873885D03*
X726141Y900656D03*
Y890617D03*
X718699Y893963D03*
Y887270D03*
X726141Y914042D03*
Y907349D03*
X718699Y917389D03*
Y910696D03*
Y904003D03*
X726141Y927428D03*
Y920735D03*
X718699Y930774D03*
Y924081D03*
X726141Y944160D03*
Y937467D03*
X718699Y947507D03*
Y940814D03*
X726141Y960892D03*
Y950853D03*
X718699Y964239D03*
Y954200D03*
X726141Y980971D03*
Y974278D03*
Y967585D03*
X718699Y977625D03*
Y970932D03*
X726141Y987664D03*
X718699Y991011D03*
Y984318D03*
X726141Y1027822D03*
Y1017782D03*
X718699Y1031168D03*
Y1024475D03*
Y1017782D03*
X726141Y1047900D03*
Y1041207D03*
Y1034515D03*
X718699Y1044554D03*
Y1037861D03*
X726141Y1061286D03*
Y1054593D03*
X718699Y1057940D03*
Y1051247D03*
X726141Y1074672D03*
Y1067979D03*
X718699Y1078018D03*
Y1071326D03*
Y1064633D03*
X726141Y1091404D03*
Y1084711D03*
X718699Y1094751D03*
Y1088058D03*
X726141Y1111483D03*
Y1104790D03*
Y1098097D03*
X718699Y1108137D03*
Y1101444D03*
X726141Y1128215D03*
Y1121522D03*
X718699Y1124869D03*
Y1114829D03*
X726141Y1141601D03*
Y1134908D03*
X718699Y1144948D03*
Y1138255D03*
Y1131562D03*
X726141Y1158333D03*
Y1148294D03*
X718699Y1161680D03*
Y1151641D03*
X726141Y1171719D03*
Y1165026D03*
X718699Y1175066D03*
Y1168373D03*
X726141Y1185105D03*
Y1178412D03*
X718699Y1188452D03*
Y1181759D03*
X726141Y1208530D03*
Y1201837D03*
Y1195144D03*
X718699Y1205184D03*
Y1198491D03*
X726141Y1221916D03*
Y1215223D03*
X718699Y1225263D03*
Y1218570D03*
Y1211877D03*
X726141Y1238648D03*
Y1231955D03*
X718699Y1241995D03*
Y1235302D03*
X726141Y1245341D03*
X719046Y1257064D03*
X718699Y1248688D03*
X729046Y1273364D03*
X715846D03*
X739699Y770144D03*
X734841Y766798D03*
X739699Y783530D03*
Y776837D03*
X734841Y773491D03*
Y780184D03*
X739699Y800263D03*
Y793570D03*
X734841Y803609D03*
Y796916D03*
Y790223D03*
X739699Y820341D03*
Y813648D03*
Y806955D03*
X734841Y816995D03*
Y810302D03*
X739699Y830381D03*
X734841Y833727D03*
Y827034D03*
X739699Y850459D03*
Y843766D03*
Y837074D03*
X734841Y847113D03*
Y840420D03*
X739699Y867192D03*
Y857152D03*
X734841Y863845D03*
Y853806D03*
X739699Y880577D03*
Y873885D03*
X734841Y883924D03*
Y877231D03*
Y870538D03*
X739699Y893963D03*
Y887270D03*
X734841Y900656D03*
Y890617D03*
X739699Y917389D03*
Y910696D03*
Y904003D03*
X734841Y914042D03*
Y907349D03*
X739699Y930774D03*
Y924081D03*
X734841Y927428D03*
Y920735D03*
X739699Y947507D03*
Y940814D03*
X734841Y944160D03*
Y937467D03*
X739699Y964239D03*
Y954200D03*
X734841Y960892D03*
Y950853D03*
X739699Y977625D03*
Y970932D03*
X734841Y980971D03*
Y974278D03*
Y967585D03*
X739699Y991011D03*
Y984318D03*
X734841Y987664D03*
X739699Y1031168D03*
Y1024475D03*
Y1017782D03*
X734841Y1027822D03*
Y1017782D03*
X739699Y1044554D03*
Y1037861D03*
X734841Y1047900D03*
Y1041207D03*
Y1034515D03*
X739699Y1057940D03*
Y1051247D03*
X734841Y1061286D03*
Y1054593D03*
X739699Y1078018D03*
Y1071326D03*
Y1064633D03*
X734841Y1074672D03*
Y1067979D03*
X739699Y1094751D03*
Y1088058D03*
X734841Y1091404D03*
Y1084711D03*
X739699Y1108137D03*
Y1101444D03*
X734841Y1111483D03*
Y1104790D03*
Y1098097D03*
X739699Y1124869D03*
Y1114829D03*
X734841Y1128215D03*
Y1121522D03*
X739699Y1144948D03*
Y1138255D03*
Y1131562D03*
X734841Y1141601D03*
Y1134908D03*
X739699Y1161680D03*
Y1151641D03*
X734841Y1158333D03*
Y1148294D03*
X739699Y1175066D03*
Y1168373D03*
X734841Y1171719D03*
Y1165026D03*
X739699Y1188452D03*
Y1181759D03*
X734841Y1185105D03*
Y1178412D03*
X739699Y1205184D03*
Y1198491D03*
X734841Y1208530D03*
Y1201837D03*
Y1195144D03*
X739699Y1225263D03*
Y1218570D03*
Y1211877D03*
X734841Y1221916D03*
Y1215223D03*
X739699Y1241995D03*
Y1235302D03*
X734841Y1238648D03*
Y1231955D03*
X739699Y1248688D03*
X734841Y1245341D03*
X745546Y1273364D03*
X742746D03*
X731372Y1273464D03*
X755841Y766798D03*
X748399Y770144D03*
X755841Y780184D03*
Y773491D03*
X748399Y783530D03*
Y776837D03*
X755841Y803609D03*
Y796916D03*
Y790223D03*
X748399Y800263D03*
Y793570D03*
X755841Y816995D03*
Y810302D03*
X748399Y820341D03*
Y813648D03*
Y806955D03*
X755841Y833727D03*
Y827034D03*
X748399Y830381D03*
X755841Y847113D03*
Y840420D03*
X748399Y850459D03*
Y843766D03*
Y837074D03*
X755841Y863845D03*
Y853806D03*
X748399Y867192D03*
Y857152D03*
X755841Y883924D03*
Y877231D03*
Y870538D03*
X748399Y880577D03*
Y873885D03*
X755841Y900656D03*
Y890617D03*
X748399Y893963D03*
Y887270D03*
X755841Y914042D03*
Y907349D03*
X748399Y917389D03*
Y910696D03*
Y904003D03*
X755841Y927428D03*
Y920735D03*
X748399Y930774D03*
Y924081D03*
X755841Y944160D03*
Y937467D03*
X748399Y947507D03*
Y940814D03*
X755841Y960892D03*
Y950853D03*
X748399Y964239D03*
Y954200D03*
X755841Y980971D03*
Y974278D03*
Y967585D03*
X748399Y977625D03*
Y970932D03*
X755841Y987664D03*
X748399Y991011D03*
Y984318D03*
X755841Y1027822D03*
Y1017782D03*
X748399Y1031168D03*
Y1024475D03*
Y1017782D03*
X755841Y1047900D03*
Y1041207D03*
Y1034515D03*
X748399Y1044554D03*
Y1037861D03*
X755841Y1054593D03*
Y1061286D03*
X748399Y1057940D03*
X755841Y1067979D03*
Y1074672D03*
X748399Y1078018D03*
Y1071326D03*
Y1064633D03*
X755841Y1084711D03*
Y1091404D03*
X748399Y1094751D03*
Y1088058D03*
X755841Y1111483D03*
Y1104790D03*
Y1098097D03*
X748399Y1108137D03*
Y1101444D03*
X755841Y1128215D03*
Y1121522D03*
X748399Y1124869D03*
Y1114829D03*
X755841Y1141601D03*
Y1134908D03*
X748399Y1144948D03*
Y1138255D03*
Y1131562D03*
X755841Y1158333D03*
Y1148294D03*
X748399Y1161680D03*
Y1151641D03*
X755841Y1171719D03*
Y1165026D03*
X748399Y1175066D03*
Y1168373D03*
X755841Y1185105D03*
Y1178412D03*
X748399Y1188452D03*
Y1181759D03*
X755841Y1208530D03*
Y1201837D03*
Y1195144D03*
X748399Y1205184D03*
Y1198491D03*
X755841Y1221916D03*
Y1215223D03*
X748399Y1225263D03*
Y1218570D03*
Y1211877D03*
X755841Y1238648D03*
Y1231955D03*
X748399Y1241995D03*
Y1235302D03*
X755841Y1245341D03*
X748283Y1256964D03*
X748399Y1248688D03*
X758746Y1273364D03*
X761546D03*
X769399Y770144D03*
X778099D03*
X764541Y766798D03*
X769399Y783530D03*
X778099D03*
X769399Y776837D03*
X778099D03*
X764541Y780184D03*
Y773491D03*
X769399Y800263D03*
X778099D03*
X769399Y793570D03*
X778099D03*
X764541Y803609D03*
Y796916D03*
Y790223D03*
X769399Y820341D03*
X778099D03*
X769399Y813648D03*
X778099D03*
X769399Y806955D03*
X778099D03*
X764541Y816995D03*
Y810302D03*
X769399Y830381D03*
X778099D03*
X764541Y833727D03*
Y827034D03*
X769399Y850459D03*
X778099D03*
Y843766D03*
X769399D03*
Y837074D03*
X778099D03*
X764541Y847113D03*
Y840420D03*
X778099Y867192D03*
X769399D03*
Y857152D03*
X778099D03*
X764541Y863845D03*
Y853806D03*
X769399Y880577D03*
X778099D03*
X769399Y873885D03*
X778099D03*
X764541Y883924D03*
Y877231D03*
Y870538D03*
X778099Y893963D03*
X769399D03*
Y887270D03*
X778099D03*
X764541Y900656D03*
Y890617D03*
X769399Y917389D03*
X778099D03*
X769399Y910696D03*
X778099D03*
X769399Y904003D03*
X778099D03*
X764541Y914042D03*
Y907349D03*
X769399Y930774D03*
X778099D03*
X769399Y924081D03*
X778099D03*
X764541Y927428D03*
Y920735D03*
X769399Y947507D03*
X778099D03*
X769399Y940814D03*
X778099D03*
X764541Y944160D03*
Y937467D03*
X769399Y964239D03*
X778099D03*
X769399Y954200D03*
X778099D03*
X764541Y960892D03*
Y950853D03*
X769399Y977625D03*
X778099D03*
X769399Y970932D03*
X778099D03*
X764541Y980971D03*
Y974278D03*
Y967585D03*
X769399Y991011D03*
X778099D03*
X769399Y984318D03*
X778099D03*
X764541Y987664D03*
X769399Y1031168D03*
X778099D03*
X769399Y1024475D03*
X778099D03*
X769399Y1017782D03*
X778099D03*
X764541Y1027822D03*
Y1017782D03*
X778099Y1044554D03*
X769399D03*
Y1037861D03*
X778099D03*
X764541Y1047900D03*
Y1041207D03*
Y1034515D03*
X769399Y1057940D03*
X778099D03*
X769399Y1051247D03*
X778099D03*
X764541Y1054593D03*
Y1061286D03*
X778099Y1078018D03*
X769399D03*
X778099Y1071326D03*
X769399D03*
Y1064633D03*
X778099D03*
X764541Y1067979D03*
Y1074672D03*
X778099Y1094751D03*
X769399D03*
X778099Y1088058D03*
X769399D03*
X764541Y1084711D03*
Y1091404D03*
X778099Y1108137D03*
X769399D03*
X778099Y1101444D03*
X769399D03*
X764541Y1111483D03*
Y1104790D03*
Y1098097D03*
X778099Y1124869D03*
X769399D03*
X778099Y1114829D03*
X769399D03*
X764541Y1128215D03*
Y1121522D03*
X778099Y1144948D03*
X769399D03*
X778099Y1138255D03*
X769399D03*
X778099Y1131562D03*
X769399D03*
X764541Y1141601D03*
Y1134908D03*
X778099Y1161680D03*
X769399D03*
X778099Y1151641D03*
X769399D03*
X764541Y1158333D03*
Y1148294D03*
X778099Y1175066D03*
X769399D03*
X778099Y1168373D03*
X769399D03*
X764541Y1171719D03*
Y1165026D03*
X778099Y1188452D03*
X769399D03*
X778099Y1181759D03*
X769399D03*
X764541Y1185105D03*
Y1178412D03*
X769399Y1205184D03*
X778099D03*
Y1198491D03*
X769399D03*
X764541Y1208530D03*
Y1201837D03*
Y1195144D03*
X778099Y1225263D03*
X769399D03*
X778099Y1218570D03*
X769399D03*
Y1211877D03*
X778099D03*
X764541Y1221916D03*
Y1215223D03*
X778099Y1241995D03*
X769399D03*
X778099Y1235302D03*
X769399D03*
X764541Y1238648D03*
Y1231955D03*
X778346Y1257264D03*
X778099Y1248688D03*
X769399D03*
X764541Y1245341D03*
X772446Y1273364D03*
X775246D03*
X785541Y766798D03*
X794241D03*
X785541Y773491D03*
X794241D03*
X785541Y780184D03*
X794241D03*
X785541Y803609D03*
X794241D03*
X785541Y790223D03*
X794241D03*
X785541Y796916D03*
X794241D03*
X785541Y816995D03*
X794241D03*
X785541Y810302D03*
X794241D03*
X785541Y833727D03*
X794241D03*
X785541Y827034D03*
X794241D03*
X785541Y840420D03*
X794241D03*
X785541Y847113D03*
X794241D03*
X785541Y853806D03*
X794241D03*
X785541Y863845D03*
X794241D03*
X785541Y883924D03*
X794241D03*
X785541Y870538D03*
X794241D03*
X785541Y877231D03*
X794241D03*
X785541Y900656D03*
X794241D03*
X785541Y890617D03*
X794241D03*
X785541Y907349D03*
X794241D03*
X785541Y914042D03*
X794241D03*
X785541Y920735D03*
X794241D03*
X785541Y927428D03*
X794241D03*
X785541Y937467D03*
X794241D03*
X785541Y944160D03*
X794241D03*
X785541Y960892D03*
X794241D03*
X785541Y950853D03*
X794241D03*
X785541Y980971D03*
X794241D03*
X785541Y974278D03*
X794241D03*
X785541Y967585D03*
X794241D03*
X785541Y987664D03*
X794241D03*
X785541Y1027822D03*
X794241D03*
X785541Y1017782D03*
X794241D03*
X785541Y1047900D03*
X794241D03*
X785541Y1041207D03*
X794241D03*
X785541Y1034515D03*
X794241D03*
X785541Y1054593D03*
X794241D03*
X785541Y1061286D03*
X794241D03*
X785541Y1074672D03*
X794241D03*
X785541Y1067979D03*
X794241D03*
X785541Y1091404D03*
X794241D03*
X785541Y1084711D03*
X794241D03*
X785541Y1111483D03*
X794241D03*
X785541Y1104790D03*
X794241D03*
X785541Y1098097D03*
X794241D03*
X785541Y1128215D03*
X794241D03*
X785541Y1121522D03*
X794241D03*
X785541Y1141601D03*
X794241D03*
X785541Y1134908D03*
X794241D03*
X785541Y1158333D03*
X794241D03*
X785541Y1148294D03*
X794241D03*
X785541Y1171719D03*
X794241D03*
X785541Y1165026D03*
X794241D03*
X785541Y1178412D03*
X794241D03*
X785541Y1185105D03*
X794241D03*
X785541Y1208530D03*
X794241D03*
X785541Y1195144D03*
X794241D03*
X785541Y1201837D03*
X794241D03*
X785541Y1221916D03*
X794241D03*
X785541Y1215223D03*
X794241D03*
X785541Y1238648D03*
X794241D03*
X785541Y1231955D03*
X794241D03*
X785541Y1245341D03*
X794241D03*
X788446Y1273364D03*
X791246D03*
X799099Y770144D03*
X807799D03*
X799099Y783530D03*
X807799D03*
X799099Y776837D03*
X807799D03*
X799099Y800263D03*
X807799D03*
X799099Y793570D03*
X807799D03*
X799099Y820341D03*
X807799D03*
X799099Y806955D03*
X807799D03*
X799099Y813648D03*
X807799D03*
X799099Y830381D03*
X807799D03*
X799099Y850459D03*
X807799D03*
X799099Y837074D03*
X807799D03*
X799099Y843766D03*
X807799D03*
X799099Y867192D03*
X807799D03*
X799099Y857152D03*
X807799D03*
X799099Y873885D03*
X807799D03*
X799099Y880577D03*
X807799D03*
X799099Y887270D03*
X807799D03*
X799099Y893963D03*
X807799D03*
X799099Y917389D03*
X807799D03*
X799099Y904003D03*
X807799D03*
X799099Y910696D03*
X807799D03*
X799099Y930774D03*
X807799D03*
X799099Y924081D03*
X807799D03*
X799099Y947507D03*
X807799D03*
X799099Y940814D03*
X807799D03*
X799099Y964239D03*
X807799D03*
X799099Y954200D03*
X807799D03*
X799099Y970932D03*
X807799D03*
X799099Y977625D03*
X807799D03*
X799099Y991011D03*
X807799D03*
X799099Y984318D03*
X807799D03*
X799099Y1031168D03*
X807799D03*
X799099Y1024475D03*
X807799D03*
X799099Y1017782D03*
X807799D03*
X799099Y1037861D03*
X807799D03*
X799099Y1044554D03*
X807799D03*
X799099Y1057940D03*
X807799D03*
X799099Y1051247D03*
X807799D03*
X799099Y1078018D03*
X807799D03*
X799099Y1071326D03*
X807799D03*
X799099Y1064633D03*
X807799D03*
X799099Y1094751D03*
X807799D03*
X799099Y1088058D03*
X807799D03*
X799099Y1108137D03*
X807799D03*
X799099Y1101444D03*
X807799D03*
X799099Y1124869D03*
X807799D03*
X799099Y1114829D03*
X807799D03*
X799099Y1144948D03*
X807799D03*
X799099Y1138255D03*
X807799D03*
X799099Y1131562D03*
X807799D03*
X799099Y1161680D03*
X807799D03*
X799099Y1151641D03*
X807799D03*
X799099Y1175066D03*
X807799D03*
X799099Y1168373D03*
X807799D03*
X799099Y1188452D03*
X807799D03*
X799099Y1181759D03*
X807799D03*
X799099Y1205184D03*
X807799D03*
X799099Y1198491D03*
X807799D03*
X799099Y1225263D03*
X807799D03*
X799099Y1211877D03*
X807799D03*
X799099Y1218570D03*
X807799D03*
X799099Y1241995D03*
X807799D03*
X799099Y1235302D03*
X807799D03*
X799099Y1248688D03*
X807799D03*
X808046Y1257664D03*
X804946Y1273364D03*
X802146D03*
X815241Y766798D03*
X823941D03*
X815241Y773491D03*
X823941D03*
X815241Y780184D03*
X823941D03*
X815241Y803609D03*
X823941D03*
X815241Y790223D03*
X823941D03*
X815241Y796916D03*
X823941D03*
X815241Y816995D03*
X823941D03*
X815241Y810302D03*
X823941D03*
X815241Y833727D03*
X823941D03*
X815241Y827034D03*
X823941D03*
X815241Y840420D03*
X823941D03*
X815241Y847113D03*
X823941D03*
X815241Y853806D03*
X823941D03*
X815241Y863845D03*
X823941D03*
X815241Y883924D03*
X823941D03*
X815241Y870538D03*
X823941D03*
X815241Y877231D03*
X823941D03*
X815241Y900656D03*
X823941D03*
X815241Y890617D03*
X823941D03*
X815241Y907349D03*
X823941D03*
X815241Y914042D03*
X823941D03*
X815241Y920735D03*
X823941D03*
X815241Y927428D03*
X823941D03*
X815241Y937467D03*
X823941D03*
X815241Y944160D03*
X823941D03*
X815241Y960892D03*
X823941D03*
X815241Y950853D03*
X823941D03*
X815241Y980971D03*
X823941D03*
X815241Y974278D03*
X823941D03*
X815241Y967585D03*
X823941D03*
X815241Y987664D03*
X823941D03*
X815241Y1027822D03*
X823941D03*
X815241Y1017782D03*
X823941D03*
X815241Y1047900D03*
X823941D03*
X815241Y1041207D03*
X823941D03*
X815241Y1034515D03*
X823941D03*
X815241Y1054593D03*
X823941D03*
X815241Y1061286D03*
X823941D03*
X815241Y1074672D03*
X823941D03*
X815241Y1067979D03*
X823941D03*
X815241Y1091404D03*
X823941D03*
X815241Y1084711D03*
X823941D03*
X815241Y1111483D03*
X823941D03*
X815241Y1104790D03*
X823941D03*
X815241Y1098097D03*
X823941D03*
X815241Y1128215D03*
X823941D03*
X815241Y1121522D03*
X823941D03*
X815241Y1141601D03*
X823941D03*
X815241Y1134908D03*
X823941D03*
X815241Y1158333D03*
X823941D03*
X815241Y1148294D03*
X823941D03*
X815241Y1171719D03*
X823941D03*
X815241Y1165026D03*
X823941D03*
X815241Y1178412D03*
X823941D03*
X815241Y1185105D03*
X823941D03*
X815241Y1208530D03*
X823941D03*
X815241Y1195144D03*
X823941D03*
X815241Y1201837D03*
X823941D03*
X815241Y1221916D03*
X823941D03*
X815241Y1215223D03*
X823941D03*
X815241Y1238648D03*
X823941D03*
X815241Y1231955D03*
X823941D03*
X815241Y1245341D03*
X823941D03*
X820946Y1273364D03*
X818146D03*
X828799Y770144D03*
X837499D03*
X828799Y783530D03*
X837499D03*
X828799Y776837D03*
X837499D03*
Y800263D03*
X828799D03*
X837499Y793570D03*
X828799D03*
Y820341D03*
X837499D03*
X828799Y813648D03*
X837499D03*
X828799Y806955D03*
X837499D03*
X828799Y830381D03*
X837499D03*
X828799Y850459D03*
X837499D03*
X828799Y843766D03*
X837499D03*
X828799Y837074D03*
X837499D03*
X828799Y867192D03*
X837499D03*
X828799Y857152D03*
X837499D03*
X828799Y880577D03*
X837499D03*
X828799Y873885D03*
X837499D03*
X828799Y893963D03*
X837499D03*
X828799Y887270D03*
X837499D03*
X828799Y917389D03*
X837499D03*
Y904003D03*
X828799D03*
X837499Y910696D03*
X828799D03*
Y930774D03*
X837499D03*
X828799Y924081D03*
X837499D03*
X828799Y947507D03*
X837499D03*
X828799Y940814D03*
X837499D03*
X828799Y964239D03*
X837499D03*
X828799Y954200D03*
X837499D03*
X828799Y977625D03*
X837499D03*
X828799Y970932D03*
X837499D03*
X828799Y991011D03*
X837499D03*
X828799Y984318D03*
X837499D03*
X828799Y1031168D03*
X837499D03*
X828799Y1024475D03*
X837499D03*
X828799Y1017782D03*
X837499D03*
X828799Y1044554D03*
X837499D03*
X828799Y1037861D03*
X837499D03*
X828799Y1057940D03*
X837499D03*
X828799Y1051247D03*
X837499D03*
X828799Y1078018D03*
X837499D03*
X828799Y1071326D03*
X837499D03*
X828799Y1064633D03*
X837499D03*
X828799Y1094751D03*
X837499D03*
Y1088058D03*
X828799D03*
X837499Y1108137D03*
X828799D03*
Y1101444D03*
X837499D03*
Y1124869D03*
X828799D03*
X837499Y1114829D03*
X828799D03*
X837499Y1144948D03*
X828799D03*
X837499Y1138255D03*
X828799D03*
X837499Y1131562D03*
X828799D03*
X837499Y1161680D03*
X828799D03*
X837499Y1151641D03*
X828799D03*
X837499Y1175066D03*
X828799D03*
X837499Y1168373D03*
X828799D03*
Y1188452D03*
X837499D03*
Y1181759D03*
X828799D03*
X837499Y1205184D03*
X828799D03*
X837499Y1198491D03*
X828799D03*
X837499Y1225263D03*
X828799D03*
X837499Y1218570D03*
X828799D03*
X837499Y1211877D03*
X828799D03*
X837499Y1241995D03*
X828799D03*
X837499Y1235302D03*
X828799D03*
X837499Y1248688D03*
X828799D03*
X837846Y1256964D03*
X839246Y1273064D03*
X842046D03*
X831846Y1273364D03*
X834646D03*
X844941Y766798D03*
X853641D03*
X844941Y780184D03*
X853641D03*
X844941Y773491D03*
X853641D03*
X844941Y803609D03*
X853641D03*
X844941Y796916D03*
X853641D03*
X844941Y790223D03*
X853641D03*
X844941Y816995D03*
X853641D03*
X844941Y810302D03*
X853641D03*
X844941Y833727D03*
X853641D03*
X844941Y827034D03*
X853641D03*
X844941Y847113D03*
X853641D03*
X844941Y840420D03*
X853641D03*
X844941Y863845D03*
X853641D03*
X844941Y853806D03*
X853641D03*
X844941Y883924D03*
X853641D03*
X844941Y877231D03*
X853641D03*
X844941Y870538D03*
X853641D03*
X844941Y900656D03*
X853641D03*
X844941Y890617D03*
X853641D03*
X844941Y914042D03*
X853641D03*
X844941Y907349D03*
X853641D03*
X844941Y927428D03*
X853641D03*
X844941Y920735D03*
X853641D03*
X844941Y944160D03*
X853641D03*
X844941Y937467D03*
X853641D03*
X844941Y960892D03*
X853641D03*
X844941Y950853D03*
X853641D03*
X844941Y980971D03*
X853641D03*
X844941Y974278D03*
X853641D03*
X844941Y967585D03*
X853641D03*
X844941Y987664D03*
X853641D03*
X844941Y1027822D03*
X853641D03*
X844941Y1017782D03*
X853641D03*
X844941Y1047900D03*
X853641D03*
X844941Y1041207D03*
X853641D03*
X844941Y1034515D03*
X853641D03*
X844941Y1061286D03*
X853641D03*
X844941Y1054593D03*
X853641D03*
X844941Y1074672D03*
X853641D03*
X844941Y1067979D03*
X853641D03*
X844941Y1091404D03*
X853641D03*
X844941Y1084711D03*
X853641D03*
X844941Y1111483D03*
X853641D03*
X844941Y1104790D03*
X853641D03*
X844941Y1098097D03*
X853641D03*
X844941Y1128215D03*
X853641D03*
X844941Y1121522D03*
X853641D03*
X844941Y1141601D03*
X853641D03*
X844941Y1134908D03*
X853641D03*
X844941Y1158333D03*
X853641D03*
X844941Y1148294D03*
X853641D03*
X844941Y1171719D03*
X853641D03*
X844941Y1165026D03*
X853641D03*
X844941Y1185105D03*
X853641D03*
X844941Y1178412D03*
X853641D03*
X844941Y1208530D03*
X853641D03*
X844941Y1201837D03*
X853641D03*
X844941Y1195144D03*
X853641D03*
X844941Y1221916D03*
X853641D03*
X844941Y1215223D03*
X853641D03*
X844941Y1238648D03*
X853641D03*
X844941Y1231955D03*
X853641D03*
X844941Y1245341D03*
X853641D03*
X1003841Y770144D03*
Y783530D03*
Y776837D03*
Y800263D03*
Y793570D03*
Y820341D03*
Y813648D03*
Y806955D03*
Y830381D03*
Y850459D03*
Y843766D03*
Y837074D03*
Y867192D03*
Y857152D03*
Y880577D03*
Y873885D03*
Y893963D03*
Y887270D03*
Y917389D03*
Y910696D03*
Y904003D03*
Y930774D03*
Y924081D03*
Y947507D03*
Y940814D03*
Y964239D03*
Y954200D03*
Y977625D03*
Y970932D03*
Y991011D03*
Y984318D03*
Y1031168D03*
Y1024475D03*
Y1017782D03*
Y1044554D03*
Y1037861D03*
Y1057940D03*
Y1051247D03*
Y1078018D03*
Y1071326D03*
Y1064633D03*
Y1094751D03*
Y1088058D03*
Y1108137D03*
Y1101444D03*
Y1124869D03*
Y1114829D03*
Y1144948D03*
Y1138255D03*
Y1131562D03*
Y1161680D03*
Y1151641D03*
Y1175066D03*
Y1168373D03*
Y1188452D03*
Y1181759D03*
Y1205184D03*
Y1198491D03*
Y1225263D03*
Y1218570D03*
Y1211877D03*
Y1241995D03*
Y1235302D03*
Y1248688D03*
X1019983Y766798D03*
X1012541Y770144D03*
X1019983Y780184D03*
Y773491D03*
X1012541Y783530D03*
Y776837D03*
X1019983Y803609D03*
Y796916D03*
Y790223D03*
X1012541Y800263D03*
Y793570D03*
X1019983Y816995D03*
Y810302D03*
X1012541Y820341D03*
Y813648D03*
Y806955D03*
X1019983Y833727D03*
Y827034D03*
X1012541Y830381D03*
X1019983Y847113D03*
Y840420D03*
X1012541Y850459D03*
Y843766D03*
Y837074D03*
X1019983Y863845D03*
Y853806D03*
X1012541Y867192D03*
Y857152D03*
X1019983Y883924D03*
Y877231D03*
Y870538D03*
X1012541Y880577D03*
Y873885D03*
X1019983Y900656D03*
Y890617D03*
X1012541Y893963D03*
Y887270D03*
X1019983Y914042D03*
Y907349D03*
X1012541Y917389D03*
Y910696D03*
Y904003D03*
X1019983Y927428D03*
Y920735D03*
X1012541Y930774D03*
Y924081D03*
X1019983Y944160D03*
Y937467D03*
X1012541Y947507D03*
Y940814D03*
X1019983Y960892D03*
Y950853D03*
X1012541Y964239D03*
Y954200D03*
X1019983Y980971D03*
Y974278D03*
Y967585D03*
X1012541Y977625D03*
Y970932D03*
X1019983Y987664D03*
X1012541Y991011D03*
Y984318D03*
X1019983Y1027822D03*
Y1017782D03*
X1012541Y1031168D03*
Y1024475D03*
Y1017782D03*
X1019983Y1047900D03*
Y1041207D03*
Y1034515D03*
X1012541Y1044554D03*
Y1037861D03*
X1019983Y1061286D03*
Y1054593D03*
X1012541Y1057940D03*
Y1051247D03*
X1019983Y1067979D03*
Y1074672D03*
X1012541Y1078018D03*
Y1071326D03*
Y1064633D03*
X1019983Y1091404D03*
Y1084711D03*
X1012541Y1094751D03*
Y1088058D03*
X1019983Y1111483D03*
Y1104790D03*
Y1098097D03*
X1012541Y1108137D03*
Y1101444D03*
X1019983Y1128215D03*
Y1121522D03*
X1012541Y1124869D03*
Y1114829D03*
X1019983Y1141601D03*
Y1134908D03*
X1012541Y1144948D03*
Y1138255D03*
Y1131562D03*
X1019983Y1158333D03*
Y1148294D03*
X1012541Y1161680D03*
Y1151641D03*
X1019983Y1171719D03*
Y1165026D03*
X1012541Y1175066D03*
Y1168373D03*
X1019983Y1185105D03*
Y1178412D03*
X1012541Y1188452D03*
Y1181759D03*
X1019983Y1208530D03*
Y1201837D03*
Y1195144D03*
X1012541Y1205184D03*
Y1198491D03*
X1019983Y1221916D03*
Y1215223D03*
X1012541Y1225263D03*
Y1218570D03*
Y1211877D03*
X1019983Y1238648D03*
Y1231955D03*
X1012541Y1241995D03*
Y1235302D03*
X1012543Y1257198D03*
X1019983Y1245341D03*
X1012541Y1248688D03*
X1017111Y1273299D03*
X1014111D03*
X1033541Y770144D03*
X1028683Y766798D03*
X1033541Y783530D03*
Y776837D03*
X1028683Y780184D03*
Y773491D03*
X1033541Y800263D03*
Y793570D03*
X1028683Y803609D03*
Y796916D03*
Y790223D03*
X1033541Y820341D03*
Y813648D03*
Y806955D03*
X1028683Y816995D03*
Y810302D03*
X1033541Y830381D03*
X1028683Y833727D03*
Y827034D03*
X1033541Y850459D03*
Y843766D03*
Y837074D03*
X1028683Y847113D03*
Y840420D03*
X1033541Y867192D03*
Y857152D03*
X1028683Y863845D03*
Y853806D03*
X1033541Y880577D03*
Y873885D03*
X1028683Y883924D03*
Y877231D03*
Y870538D03*
X1033541Y893963D03*
Y887270D03*
X1028683Y900656D03*
Y890617D03*
X1033541Y917389D03*
Y910696D03*
Y904003D03*
X1028683Y914042D03*
Y907349D03*
X1033541Y930774D03*
Y924081D03*
X1028683Y927428D03*
Y920735D03*
X1033541Y947507D03*
Y940814D03*
X1028683Y944160D03*
Y937467D03*
X1033541Y964239D03*
Y954200D03*
X1028683Y960892D03*
Y950853D03*
X1033541Y977625D03*
Y970932D03*
X1028683Y980971D03*
Y974278D03*
Y967585D03*
X1033541Y991011D03*
Y984318D03*
X1028683Y987664D03*
X1033541Y1031168D03*
Y1017782D03*
Y1024475D03*
X1028683Y1027822D03*
Y1017782D03*
X1033541Y1044554D03*
Y1037861D03*
X1028683Y1047900D03*
Y1041207D03*
Y1034515D03*
X1033541Y1057940D03*
Y1051247D03*
X1028683Y1061286D03*
Y1054593D03*
X1033541Y1078018D03*
Y1071326D03*
Y1064633D03*
X1028683Y1067979D03*
Y1074672D03*
X1033541Y1094751D03*
Y1088058D03*
X1028683Y1091404D03*
Y1084711D03*
X1033541Y1108137D03*
Y1101444D03*
X1028683Y1111483D03*
Y1104790D03*
Y1098097D03*
X1033541Y1114829D03*
Y1124869D03*
X1028683Y1128215D03*
Y1121522D03*
X1033541Y1144948D03*
Y1138255D03*
Y1131562D03*
X1028683Y1141601D03*
Y1134908D03*
X1033541Y1161680D03*
Y1151641D03*
X1028683Y1158333D03*
Y1148294D03*
X1033541Y1175066D03*
Y1168373D03*
X1028683Y1171719D03*
Y1165026D03*
X1033541Y1188452D03*
Y1181759D03*
X1028683Y1185105D03*
Y1178412D03*
X1033541Y1205184D03*
Y1198491D03*
X1028683Y1208530D03*
Y1201837D03*
Y1195144D03*
X1033541Y1225263D03*
Y1218570D03*
Y1211877D03*
X1028683Y1221916D03*
Y1215223D03*
X1033541Y1241995D03*
Y1235302D03*
X1028683Y1238648D03*
Y1231955D03*
X1033541Y1248688D03*
X1028683Y1245341D03*
X1036588Y1273344D03*
X1022888D03*
X1025688D03*
X1049683Y766798D03*
X1042241Y770144D03*
X1049683Y780184D03*
Y773491D03*
X1042241Y783530D03*
Y776837D03*
X1049683Y803609D03*
Y796916D03*
Y790223D03*
X1042241Y800263D03*
Y793570D03*
X1049683Y816995D03*
Y810302D03*
X1042241Y820341D03*
Y813648D03*
Y806955D03*
X1049683Y833727D03*
Y827034D03*
X1042241Y830381D03*
X1049683Y847113D03*
Y840420D03*
X1042241Y850459D03*
Y843766D03*
Y837074D03*
X1049683Y863845D03*
Y853806D03*
X1042241Y867192D03*
Y857152D03*
X1049683Y883924D03*
Y877231D03*
Y870538D03*
X1042241Y880577D03*
Y873885D03*
X1049683Y900656D03*
Y890617D03*
X1042241Y893963D03*
Y887270D03*
X1049683Y914042D03*
Y907349D03*
X1042241Y917389D03*
Y910696D03*
Y904003D03*
X1049683Y927428D03*
Y920735D03*
X1042241Y930774D03*
Y924081D03*
X1049683Y944160D03*
Y937467D03*
X1042241Y947507D03*
Y940814D03*
X1049683Y960892D03*
Y950853D03*
X1042241Y964239D03*
Y954200D03*
X1049683Y980971D03*
Y974278D03*
Y967585D03*
X1042241Y977625D03*
Y970932D03*
X1049683Y987664D03*
X1042241Y991011D03*
Y984318D03*
X1049683Y1027822D03*
Y1017782D03*
X1042241Y1031168D03*
Y1017782D03*
Y1024475D03*
X1049683Y1047900D03*
Y1041207D03*
Y1034515D03*
X1042241Y1044554D03*
Y1037861D03*
X1049683Y1061286D03*
Y1054593D03*
X1042241Y1057940D03*
Y1051247D03*
X1049683Y1074672D03*
Y1067979D03*
X1042241Y1078018D03*
Y1071326D03*
Y1064633D03*
X1049683Y1091404D03*
Y1084711D03*
X1042241Y1094751D03*
Y1088058D03*
X1049683Y1111483D03*
Y1104790D03*
Y1098097D03*
X1042241Y1108137D03*
Y1101444D03*
Y1114829D03*
X1049683Y1128215D03*
Y1121522D03*
X1042241Y1124869D03*
X1049683Y1141601D03*
Y1134908D03*
X1042241Y1144948D03*
Y1138255D03*
Y1131562D03*
Y1161680D03*
X1049683Y1158333D03*
Y1148294D03*
X1042241Y1151641D03*
X1049683Y1171719D03*
Y1165026D03*
X1042241Y1175066D03*
Y1168373D03*
X1049683Y1185105D03*
Y1178412D03*
X1042241Y1188452D03*
Y1181759D03*
X1049683Y1208530D03*
Y1201837D03*
Y1195144D03*
X1042241Y1205184D03*
Y1198491D03*
X1049683Y1215223D03*
Y1221916D03*
X1042241Y1225263D03*
Y1218570D03*
Y1211877D03*
X1049683Y1238648D03*
Y1231955D03*
X1042241Y1241995D03*
Y1235302D03*
X1042331Y1257488D03*
X1049683Y1245341D03*
X1042241Y1248688D03*
X1052588Y1273344D03*
X1039388D03*
X1063241Y770144D03*
X1058383Y766798D03*
X1063241Y783530D03*
Y776837D03*
X1058383Y780184D03*
Y773491D03*
X1063241Y800263D03*
Y793570D03*
X1058383Y803609D03*
Y796916D03*
Y790223D03*
X1063241Y820341D03*
Y813648D03*
Y806955D03*
X1058383Y816995D03*
Y810302D03*
X1063241Y830381D03*
X1058383Y833727D03*
Y827034D03*
X1063241Y850459D03*
Y843766D03*
Y837074D03*
X1058383Y847113D03*
Y840420D03*
X1063241Y867192D03*
Y857152D03*
X1058383Y863845D03*
Y853806D03*
X1063241Y880577D03*
Y873885D03*
X1058383Y883924D03*
Y877231D03*
Y870538D03*
X1063241Y893963D03*
Y887270D03*
X1058383Y900656D03*
Y890617D03*
X1063241Y917389D03*
Y910696D03*
Y904003D03*
X1058383Y914042D03*
Y907349D03*
X1063241Y930774D03*
Y924081D03*
X1058383Y927428D03*
Y920735D03*
X1063241Y947507D03*
Y940814D03*
X1058383Y944160D03*
Y937467D03*
X1063241Y964239D03*
Y954200D03*
X1058383Y960892D03*
Y950853D03*
X1063241Y977625D03*
Y970932D03*
X1058383Y980971D03*
Y974278D03*
Y967585D03*
X1063241Y991011D03*
Y984318D03*
X1058383Y987664D03*
X1063241Y1031168D03*
Y1024475D03*
Y1017782D03*
X1058383Y1027822D03*
Y1017782D03*
X1063241Y1044554D03*
Y1037861D03*
X1058383Y1047900D03*
Y1041207D03*
Y1034515D03*
X1063241Y1057940D03*
Y1051247D03*
X1058383Y1061286D03*
Y1054593D03*
X1063241Y1078018D03*
Y1071326D03*
Y1064633D03*
X1058383Y1074672D03*
Y1067979D03*
X1063241Y1094751D03*
Y1088058D03*
X1058383Y1091404D03*
Y1084711D03*
X1063241Y1108137D03*
Y1101444D03*
X1058383Y1111483D03*
Y1104790D03*
Y1098097D03*
X1063241Y1124869D03*
Y1114829D03*
X1058383Y1128215D03*
Y1121522D03*
X1063241Y1144948D03*
Y1138255D03*
Y1131562D03*
X1058383Y1141601D03*
Y1134908D03*
X1063241Y1161680D03*
Y1151641D03*
X1058383Y1158333D03*
Y1148294D03*
X1063241Y1175066D03*
Y1168373D03*
X1058383Y1171719D03*
Y1165026D03*
X1063241Y1188452D03*
Y1181759D03*
X1058383Y1185105D03*
Y1178412D03*
X1063241Y1205184D03*
Y1198491D03*
X1058383Y1208530D03*
Y1201837D03*
Y1195144D03*
X1063241Y1225263D03*
Y1218570D03*
Y1211877D03*
X1058383Y1215223D03*
Y1221916D03*
X1063241Y1241995D03*
Y1235302D03*
X1058383Y1238648D03*
Y1231955D03*
X1063241Y1248688D03*
X1058383Y1245341D03*
X1069088Y1273344D03*
X1066288D03*
X1055388D03*
X1079383Y766798D03*
X1071941Y770144D03*
X1079383Y780184D03*
Y773491D03*
X1071941Y783530D03*
Y776837D03*
X1079383Y803609D03*
Y796916D03*
Y790223D03*
X1071941Y800263D03*
Y793570D03*
X1079383Y816995D03*
Y810302D03*
X1071941Y820341D03*
Y813648D03*
Y806955D03*
X1079383Y833727D03*
Y827034D03*
X1071941Y830381D03*
X1079383Y847113D03*
Y840420D03*
X1071941Y850459D03*
Y843766D03*
Y837074D03*
X1079383Y863845D03*
Y853806D03*
X1071941Y867192D03*
Y857152D03*
X1079383Y883924D03*
Y877231D03*
Y870538D03*
X1071941Y880577D03*
Y873885D03*
X1079383Y900656D03*
Y890617D03*
X1071941Y893963D03*
Y887270D03*
X1079383Y914042D03*
Y907349D03*
X1071941Y917389D03*
Y910696D03*
Y904003D03*
X1079383Y927428D03*
Y920735D03*
X1071941Y930774D03*
Y924081D03*
X1079383Y944160D03*
Y937467D03*
X1071941Y947507D03*
Y940814D03*
X1079383Y960892D03*
Y950853D03*
X1071941Y964239D03*
Y954200D03*
X1079383Y980971D03*
Y974278D03*
Y967585D03*
X1071941Y977625D03*
Y970932D03*
X1079383Y987664D03*
X1071941Y991011D03*
Y984318D03*
X1079383Y1027822D03*
Y1017782D03*
X1071941Y1031168D03*
Y1024475D03*
Y1017782D03*
X1079383Y1047900D03*
Y1041207D03*
Y1034515D03*
X1071941Y1044554D03*
Y1037861D03*
X1079383Y1061286D03*
Y1054593D03*
X1071941Y1057940D03*
Y1051247D03*
X1079383Y1074672D03*
Y1067979D03*
X1071941Y1078018D03*
Y1071326D03*
Y1064633D03*
X1079383Y1091404D03*
Y1084711D03*
X1071941Y1094751D03*
Y1088058D03*
X1079383Y1111483D03*
Y1104790D03*
Y1098097D03*
X1071941Y1108137D03*
Y1101444D03*
X1079383Y1128215D03*
Y1121522D03*
X1071941Y1124869D03*
Y1114829D03*
X1079383Y1141601D03*
Y1134908D03*
X1071941Y1144948D03*
Y1138255D03*
Y1131562D03*
X1079383Y1158333D03*
Y1148294D03*
X1071941Y1161680D03*
Y1151641D03*
X1079383Y1171719D03*
Y1165026D03*
X1071941Y1175066D03*
Y1168373D03*
X1079383Y1185105D03*
Y1178412D03*
X1071941Y1188452D03*
Y1181759D03*
X1079383Y1208530D03*
Y1201837D03*
Y1195144D03*
X1071941Y1205184D03*
Y1198491D03*
X1079383Y1221916D03*
Y1215223D03*
X1071941Y1225263D03*
Y1218570D03*
Y1211877D03*
X1079383Y1238648D03*
Y1231955D03*
X1071941Y1241995D03*
Y1235302D03*
X1071991Y1257262D03*
X1079383Y1245341D03*
X1071941Y1248688D03*
X1085088Y1273344D03*
X1082288D03*
X1092941Y770144D03*
X1101641D03*
X1088083Y766798D03*
X1092941Y783530D03*
X1101641D03*
X1092941Y776837D03*
X1101641D03*
X1088083Y780184D03*
Y773491D03*
X1101641Y800263D03*
X1092941D03*
X1101641Y793570D03*
X1092941D03*
X1088083Y803609D03*
Y796916D03*
Y790223D03*
X1101641Y820341D03*
X1092941D03*
X1101641Y813648D03*
X1092941D03*
X1101641Y806955D03*
X1092941D03*
X1088083Y816995D03*
Y810302D03*
X1101641Y830381D03*
X1092941D03*
X1088083Y833727D03*
Y827034D03*
X1101641Y850459D03*
X1092941D03*
X1101641Y843766D03*
X1092941D03*
X1101641Y837074D03*
X1092941D03*
X1088083Y847113D03*
Y840420D03*
X1101641Y867192D03*
X1092941D03*
X1101641Y857152D03*
X1092941D03*
X1088083Y863845D03*
Y853806D03*
X1101641Y880577D03*
X1092941D03*
X1101641Y873885D03*
X1092941D03*
X1088083Y883924D03*
Y877231D03*
Y870538D03*
X1101641Y893963D03*
X1092941D03*
X1101641Y887270D03*
X1092941D03*
X1088083Y900656D03*
Y890617D03*
X1101641Y917389D03*
X1092941D03*
X1101641Y910696D03*
X1092941D03*
X1101641Y904003D03*
X1092941D03*
X1088083Y914042D03*
Y907349D03*
X1101641Y930774D03*
X1092941D03*
X1101641Y924081D03*
X1092941D03*
X1088083Y927428D03*
Y920735D03*
X1101641Y947507D03*
X1092941D03*
X1101641Y940814D03*
X1092941D03*
X1088083Y944160D03*
Y937467D03*
X1101641Y964239D03*
X1092941D03*
X1101641Y954200D03*
X1092941D03*
X1088083Y960892D03*
Y950853D03*
X1101641Y977625D03*
X1092941D03*
X1101641Y970932D03*
X1092941D03*
X1088083Y980971D03*
Y974278D03*
Y967585D03*
X1101641Y991011D03*
X1092941D03*
X1101641Y984318D03*
X1092941D03*
X1088083Y987664D03*
X1101641Y1031168D03*
X1092941D03*
X1101641Y1024475D03*
X1092941D03*
X1101641Y1017782D03*
X1092941D03*
X1088083Y1027822D03*
Y1017782D03*
X1101641Y1044554D03*
X1092941D03*
X1101641Y1037861D03*
X1092941D03*
X1088083Y1047900D03*
Y1041207D03*
Y1034515D03*
X1101641Y1057940D03*
X1092941D03*
X1101641Y1051247D03*
X1092941D03*
X1088083Y1061286D03*
Y1054593D03*
X1101641Y1078018D03*
X1092941D03*
X1101641Y1071326D03*
X1092941D03*
X1101641Y1064633D03*
X1092941D03*
X1088083Y1074672D03*
Y1067979D03*
X1101641Y1094751D03*
X1092941D03*
X1101641Y1088058D03*
X1092941D03*
X1088083Y1091404D03*
Y1084711D03*
X1101641Y1108137D03*
X1092941D03*
X1101641Y1101444D03*
X1092941D03*
X1088083Y1111483D03*
Y1104790D03*
Y1098097D03*
X1101641Y1124869D03*
X1092941D03*
X1101641Y1114829D03*
X1092941D03*
X1088083Y1128215D03*
Y1121522D03*
X1101641Y1144948D03*
X1092941D03*
X1101641Y1138255D03*
X1092941D03*
X1101641Y1131562D03*
X1092941D03*
X1088083Y1141601D03*
Y1134908D03*
X1092941Y1161680D03*
X1101641D03*
Y1151641D03*
X1092941D03*
X1088083Y1158333D03*
Y1148294D03*
X1101641Y1175066D03*
X1092941D03*
X1101641Y1168373D03*
X1092941D03*
X1088083Y1171719D03*
Y1165026D03*
X1101641Y1181759D03*
X1092941D03*
Y1188452D03*
X1101641D03*
X1088083Y1185105D03*
Y1178412D03*
X1092941Y1205184D03*
X1101641D03*
X1092941Y1198491D03*
X1101641D03*
X1088083Y1208530D03*
Y1201837D03*
Y1195144D03*
X1101641Y1225263D03*
X1092941D03*
X1101641Y1218570D03*
X1092941D03*
Y1211877D03*
X1101641D03*
X1088083Y1221916D03*
Y1215223D03*
X1101641Y1241995D03*
X1092941D03*
X1101641Y1235302D03*
X1092941D03*
X1088083Y1238648D03*
Y1231955D03*
X1101554Y1257102D03*
X1101641Y1248688D03*
X1092941D03*
X1088083Y1245341D03*
X1098788Y1273344D03*
X1095988D03*
X1109083Y766798D03*
X1117783D03*
Y780184D03*
X1109083D03*
X1117783Y773491D03*
X1109083D03*
X1117783Y803609D03*
X1109083D03*
X1117783Y796916D03*
X1109083D03*
Y790223D03*
X1117783D03*
Y816995D03*
X1109083D03*
X1117783Y810302D03*
X1109083D03*
X1117783Y833727D03*
X1109083D03*
X1117783Y827034D03*
X1109083D03*
X1117783Y847113D03*
X1109083D03*
X1117783Y840420D03*
X1109083D03*
X1117783Y863845D03*
X1109083D03*
X1117783Y853806D03*
X1109083D03*
X1117783Y883924D03*
X1109083D03*
X1117783Y877231D03*
X1109083D03*
X1117783Y870538D03*
X1109083D03*
X1117783Y900656D03*
X1109083D03*
X1117783Y890617D03*
X1109083D03*
X1117783Y914042D03*
X1109083D03*
X1117783Y907349D03*
X1109083D03*
X1117783Y927428D03*
X1109083D03*
X1117783Y920735D03*
X1109083D03*
X1117783Y944160D03*
X1109083D03*
X1117783Y937467D03*
X1109083D03*
X1117783Y960892D03*
X1109083D03*
X1117783Y950853D03*
X1109083D03*
X1117783Y980971D03*
X1109083D03*
X1117783Y974278D03*
X1109083D03*
X1117783Y967585D03*
X1109083D03*
X1117783Y987664D03*
X1109083D03*
X1117783Y1027822D03*
X1109083D03*
X1117783Y1017782D03*
X1109083D03*
X1117783Y1047900D03*
X1109083D03*
X1117783Y1041207D03*
X1109083D03*
X1117783Y1034515D03*
X1109083D03*
X1117783Y1061286D03*
X1109083D03*
X1117783Y1054593D03*
X1109083D03*
X1117783Y1074672D03*
X1109083D03*
X1117783Y1067979D03*
X1109083D03*
X1117783Y1091404D03*
X1109083D03*
X1117783Y1084711D03*
X1109083D03*
X1117783Y1111483D03*
X1109083D03*
X1117783Y1104790D03*
X1109083D03*
X1117783Y1098097D03*
X1109083D03*
X1117783Y1128215D03*
X1109083D03*
X1117783Y1121522D03*
X1109083D03*
X1117783Y1141601D03*
X1109083D03*
X1117783Y1134908D03*
X1109083D03*
X1117783Y1158333D03*
X1109083D03*
X1117783Y1148294D03*
X1109083D03*
X1117783Y1171719D03*
X1109083D03*
X1117783Y1165026D03*
X1109083D03*
X1117783Y1185105D03*
X1109083D03*
X1117783Y1178412D03*
X1109083D03*
X1117783Y1208530D03*
X1109083D03*
X1117783Y1201837D03*
X1109083D03*
X1117783Y1195144D03*
X1109083D03*
X1117783Y1221916D03*
X1109083D03*
X1117783Y1215223D03*
X1109083D03*
X1117783Y1238648D03*
X1109083D03*
X1117783Y1231955D03*
X1109083D03*
X1117783Y1245341D03*
X1109083D03*
X1111988Y1273344D03*
X1114788D03*
X1131341Y770144D03*
X1122641D03*
X1131341Y783530D03*
X1122641D03*
X1131341Y776837D03*
X1122641D03*
X1131341Y800263D03*
X1122641D03*
X1131341Y793570D03*
X1122641D03*
X1131341Y820341D03*
X1122641D03*
X1131341Y813648D03*
X1122641D03*
X1131341Y806955D03*
X1122641D03*
X1131341Y830381D03*
X1122641D03*
X1131341Y850459D03*
X1122641D03*
X1131341Y843766D03*
X1122641D03*
X1131341Y837074D03*
X1122641D03*
X1131341Y867192D03*
X1122641D03*
X1131341Y857152D03*
X1122641D03*
X1131341Y880577D03*
X1122641D03*
X1131341Y873885D03*
X1122641D03*
X1131341Y893963D03*
X1122641D03*
X1131341Y887270D03*
X1122641D03*
X1131341Y917389D03*
X1122641D03*
X1131341Y910696D03*
X1122641D03*
X1131341Y904003D03*
X1122641D03*
X1131341Y930774D03*
X1122641D03*
X1131341Y924081D03*
X1122641D03*
Y947507D03*
X1131341D03*
Y940814D03*
X1122641D03*
X1131341Y964239D03*
X1122641D03*
X1131341Y954200D03*
X1122641D03*
X1131341Y977625D03*
X1122641D03*
X1131341Y970932D03*
X1122641D03*
X1131341Y991011D03*
X1122641D03*
X1131341Y984318D03*
X1122641D03*
X1131341Y1031168D03*
X1122641D03*
X1131341Y1024475D03*
X1122641D03*
X1131341Y1017782D03*
X1122641D03*
X1131341Y1044554D03*
X1122641D03*
X1131341Y1037861D03*
X1122641D03*
X1131341Y1057940D03*
X1122641D03*
X1131341Y1051247D03*
X1122641D03*
X1131341Y1078018D03*
X1122641D03*
X1131341Y1071326D03*
X1122641D03*
X1131341Y1064633D03*
X1122641D03*
X1131341Y1094751D03*
X1122641D03*
X1131341Y1088058D03*
X1122641D03*
X1131341Y1108137D03*
X1122641D03*
X1131341Y1101444D03*
X1122641D03*
X1131341Y1124869D03*
X1122641D03*
X1131341Y1114829D03*
X1122641D03*
X1131341Y1144948D03*
X1122641D03*
X1131341Y1138255D03*
X1122641D03*
X1131341Y1131562D03*
X1122641D03*
X1131341Y1161680D03*
X1122641D03*
X1131341Y1151641D03*
X1122641D03*
X1131341Y1175066D03*
X1122641D03*
X1131341Y1168373D03*
X1122641D03*
X1131341Y1188452D03*
X1122641D03*
X1131341Y1181759D03*
X1122641D03*
X1131341Y1205184D03*
X1122641D03*
X1131341Y1198491D03*
X1122641D03*
X1131341Y1225263D03*
X1122641D03*
X1131341Y1218570D03*
X1122641D03*
X1131341Y1211877D03*
X1122641D03*
X1131341Y1241995D03*
X1122641D03*
X1131341Y1235302D03*
X1122641D03*
X1131434Y1257291D03*
X1122641Y1248688D03*
X1131341D03*
X1126188Y1273344D03*
X1128988D03*
X1152341Y770144D03*
X1147483Y766798D03*
X1138783D03*
X1152341Y783530D03*
Y776837D03*
X1147483Y780184D03*
X1138783D03*
Y773491D03*
X1147483D03*
X1152341Y800263D03*
X1147483Y803609D03*
X1138783D03*
X1152341Y793570D03*
X1147483Y796916D03*
X1138783D03*
X1147483Y790223D03*
X1138783D03*
X1152341Y820341D03*
X1147483Y816995D03*
X1138783D03*
X1152341Y813648D03*
Y806955D03*
X1147483Y810302D03*
X1138783D03*
X1147483Y833727D03*
X1138783D03*
X1152341Y830381D03*
X1147483Y827034D03*
X1138783D03*
X1152341Y850459D03*
Y843766D03*
Y837074D03*
X1147483Y847113D03*
X1138783D03*
X1147483Y840420D03*
X1138783D03*
X1152341Y867192D03*
Y857152D03*
X1147483Y863845D03*
X1138783D03*
X1147483Y853806D03*
X1138783D03*
X1152341Y880577D03*
Y873885D03*
X1147483Y883924D03*
X1138783D03*
X1147483Y877231D03*
X1138783D03*
X1147483Y870538D03*
X1138783D03*
X1152341Y893963D03*
Y887270D03*
X1138783Y900656D03*
X1147483D03*
X1138783Y890617D03*
X1147483D03*
X1152341Y917389D03*
Y910696D03*
Y904003D03*
X1147483Y914042D03*
X1138783D03*
X1147483Y907349D03*
X1138783D03*
X1152341Y930774D03*
Y924081D03*
X1147483Y927428D03*
X1138783D03*
X1147483Y920735D03*
X1138783D03*
X1152341Y947507D03*
Y940814D03*
X1147483Y944160D03*
X1138783D03*
X1147483Y937467D03*
X1138783D03*
X1152341Y964239D03*
Y954200D03*
X1147483Y960892D03*
X1138783D03*
X1147483Y950853D03*
X1138783D03*
X1152341Y977625D03*
Y970932D03*
X1147483Y980971D03*
X1138783D03*
X1147483Y974278D03*
X1138783D03*
X1147483Y967585D03*
X1138783D03*
X1152341Y991011D03*
Y984318D03*
X1147483Y987664D03*
X1138783D03*
X1152341Y1031168D03*
Y1024475D03*
Y1017782D03*
X1147483Y1027822D03*
X1138783D03*
X1147483Y1017782D03*
X1138783D03*
X1152341Y1044554D03*
Y1037861D03*
X1138783Y1047900D03*
X1147483D03*
Y1041207D03*
X1138783D03*
X1147483Y1034515D03*
X1138783D03*
X1152341Y1057940D03*
Y1051247D03*
X1147483Y1061286D03*
X1138783D03*
X1147483Y1054593D03*
X1138783D03*
X1152341Y1078018D03*
Y1071326D03*
Y1064633D03*
X1147483Y1074672D03*
X1138783D03*
X1147483Y1067979D03*
X1138783D03*
X1152341Y1094751D03*
Y1088058D03*
X1147483Y1091404D03*
X1138783D03*
X1147483Y1084711D03*
X1138783D03*
X1152341Y1108137D03*
Y1101444D03*
X1147483Y1111483D03*
X1138783D03*
X1147483Y1104790D03*
X1138783D03*
X1147483Y1098097D03*
X1138783D03*
X1152341Y1124869D03*
Y1114829D03*
X1147483Y1128215D03*
X1138783D03*
X1147483Y1121522D03*
X1138783D03*
X1152341Y1144948D03*
Y1138255D03*
Y1131562D03*
X1147483Y1141601D03*
X1138783D03*
X1147483Y1134908D03*
X1138783D03*
X1152341Y1161680D03*
Y1151641D03*
X1147483Y1158333D03*
X1138783D03*
Y1148294D03*
X1147483D03*
X1152341Y1175066D03*
Y1168373D03*
X1147483Y1171719D03*
X1138783D03*
X1147483Y1165026D03*
X1138783D03*
X1152341Y1188452D03*
Y1181759D03*
X1147483Y1185105D03*
X1138783D03*
X1147483Y1178412D03*
X1138783D03*
X1152341Y1205184D03*
Y1198491D03*
X1147483Y1208530D03*
X1138783D03*
X1147483Y1201837D03*
X1138783D03*
X1147483Y1195144D03*
X1138783D03*
X1152341Y1225263D03*
Y1218570D03*
Y1211877D03*
X1147483Y1221916D03*
X1138783D03*
X1147483Y1215223D03*
X1138783D03*
X1152341Y1241995D03*
Y1235302D03*
X1147483Y1238648D03*
X1138783D03*
X1147483Y1231955D03*
X1138783D03*
X1152341Y1248688D03*
X1147483Y1245341D03*
X1138783D03*
X1152381Y1269684D03*
X1147681D03*
X1138201Y1270277D03*
X1168483Y766798D03*
X1161041Y770144D03*
X1168483Y780184D03*
Y773491D03*
X1161041Y783530D03*
Y776837D03*
X1168483Y803609D03*
Y796916D03*
Y790223D03*
X1161041Y800263D03*
Y793570D03*
X1168483Y816995D03*
Y810302D03*
X1161041Y820341D03*
Y813648D03*
Y806955D03*
X1168483Y833727D03*
X1167633Y827034D03*
X1161041Y830381D03*
X1168483Y847113D03*
Y840420D03*
X1161041Y850459D03*
Y843766D03*
Y837074D03*
X1167633Y863845D03*
X1161041Y867192D03*
X1168483Y853806D03*
X1161041Y857152D03*
X1168483Y883924D03*
Y877231D03*
Y870538D03*
X1161041Y880577D03*
Y873885D03*
X1168483Y900656D03*
Y890617D03*
X1161041Y893963D03*
Y887270D03*
X1168483Y914042D03*
Y907349D03*
X1161041Y917389D03*
Y910696D03*
Y904003D03*
X1167633Y927428D03*
X1168483Y920735D03*
X1161041Y930774D03*
Y924081D03*
X1168483Y937467D03*
Y944160D03*
X1161041Y947507D03*
Y940814D03*
X1168483Y960892D03*
Y950853D03*
X1161041Y964239D03*
Y954200D03*
X1168483Y974278D03*
Y980971D03*
Y967585D03*
X1161041Y977625D03*
Y970932D03*
X1168483Y987664D03*
X1161041Y991011D03*
Y984318D03*
X1168483Y1027822D03*
Y1017782D03*
X1161041Y1031168D03*
Y1024475D03*
Y1017782D03*
X1168483Y1047900D03*
Y1041207D03*
Y1034515D03*
X1161041Y1044554D03*
Y1037861D03*
X1168483Y1054593D03*
Y1061286D03*
X1161041Y1057940D03*
Y1051247D03*
X1168483Y1074672D03*
Y1067979D03*
X1161041Y1078018D03*
Y1071326D03*
Y1064633D03*
X1168483Y1091404D03*
X1167633Y1084711D03*
X1161041Y1094751D03*
Y1088058D03*
X1168483Y1111483D03*
Y1104790D03*
Y1098097D03*
X1161041Y1108137D03*
Y1101444D03*
X1168483Y1128215D03*
Y1121522D03*
X1161041Y1124869D03*
Y1114829D03*
X1168483Y1141601D03*
Y1134908D03*
X1161041Y1144948D03*
Y1138255D03*
Y1131562D03*
X1167633Y1158333D03*
X1168483Y1148294D03*
X1161041Y1161680D03*
Y1151641D03*
X1168483Y1171719D03*
Y1165026D03*
X1161041Y1175066D03*
Y1168373D03*
X1168483Y1185105D03*
Y1178412D03*
X1161041Y1188452D03*
Y1181759D03*
X1168483Y1208530D03*
Y1201837D03*
Y1195144D03*
X1161041Y1205184D03*
Y1198491D03*
X1168483Y1221916D03*
Y1215223D03*
X1161041Y1225263D03*
Y1218570D03*
Y1211877D03*
X1168483Y1238648D03*
X1167633Y1231955D03*
X1161041Y1241995D03*
Y1235302D03*
X1161065Y1258871D03*
X1168483Y1245341D03*
X1161041Y1248688D03*
X1161781Y1269684D03*
X1182041Y770144D03*
X1177183Y766798D03*
X1182041Y783530D03*
Y776837D03*
X1177183Y780184D03*
Y773491D03*
X1182041Y800263D03*
Y793570D03*
X1177183Y803609D03*
Y796916D03*
Y790223D03*
X1182041Y813648D03*
Y806955D03*
X1181191Y820341D03*
X1177183Y816995D03*
Y810302D03*
X1181191Y830381D03*
X1177183Y833727D03*
Y827034D03*
X1182041Y850459D03*
Y837074D03*
Y843766D03*
X1177183Y847113D03*
Y840420D03*
X1181191Y867192D03*
X1177183Y863845D03*
X1181191Y857152D03*
X1177183Y853806D03*
X1182041Y873885D03*
Y880577D03*
X1177183Y883924D03*
Y877231D03*
Y870538D03*
X1182041Y893963D03*
Y887270D03*
X1177183Y900656D03*
Y890617D03*
X1182041Y917389D03*
Y910696D03*
Y904003D03*
X1177183Y914042D03*
Y907349D03*
X1181191Y930774D03*
Y924081D03*
X1177183Y927428D03*
Y920735D03*
X1182041Y940814D03*
Y947507D03*
X1177183Y937467D03*
Y944160D03*
X1182041Y964239D03*
Y954200D03*
X1177183Y960892D03*
Y950853D03*
X1182041Y970932D03*
Y977625D03*
X1177183Y974278D03*
Y980971D03*
Y967585D03*
X1182041Y991011D03*
Y984318D03*
X1177183Y987664D03*
X1182041Y1031168D03*
Y1017782D03*
Y1024475D03*
X1177183Y1027822D03*
Y1017782D03*
X1182041Y1044554D03*
Y1037861D03*
X1177183Y1047900D03*
Y1041207D03*
Y1034515D03*
X1182041Y1057940D03*
Y1051247D03*
X1177183Y1054593D03*
Y1061286D03*
X1181191Y1078018D03*
X1182041Y1071326D03*
Y1064633D03*
X1177183Y1074672D03*
Y1067979D03*
X1182041Y1094751D03*
X1181191Y1088058D03*
X1177183Y1091404D03*
Y1084711D03*
X1182041Y1101444D03*
Y1108137D03*
X1177183Y1111483D03*
Y1104790D03*
Y1098097D03*
X1182041Y1114829D03*
Y1124869D03*
X1177183Y1128215D03*
Y1121522D03*
X1182041Y1144948D03*
Y1138255D03*
Y1131562D03*
X1177183Y1141601D03*
Y1134908D03*
X1181191Y1161680D03*
Y1151641D03*
X1177183Y1158333D03*
Y1148294D03*
X1182041Y1168373D03*
Y1175066D03*
X1177183Y1171719D03*
Y1165026D03*
X1182041Y1188452D03*
Y1181759D03*
X1177183Y1185105D03*
Y1178412D03*
X1182041Y1205184D03*
Y1198491D03*
X1177183Y1208530D03*
Y1201837D03*
Y1195144D03*
X1181191Y1225263D03*
X1182041Y1211877D03*
Y1218570D03*
X1177183Y1221916D03*
Y1215223D03*
X1182041Y1241995D03*
X1181191Y1235302D03*
X1177183Y1238648D03*
Y1231955D03*
X1182041Y1248688D03*
X1177183Y1245341D03*
X1176867Y1270029D03*
X1198183Y766798D03*
X1190741Y770144D03*
X1198183Y780184D03*
Y773491D03*
X1190741Y783530D03*
Y776837D03*
X1198183Y803609D03*
Y796916D03*
Y790223D03*
X1190741Y800263D03*
Y793570D03*
X1197333Y816995D03*
X1198183Y810302D03*
X1190741Y813648D03*
Y806955D03*
X1191591Y820341D03*
X1198183Y833727D03*
X1197333Y827034D03*
X1191591Y830381D03*
X1198183Y847113D03*
Y840420D03*
X1190741Y850459D03*
Y837074D03*
Y843766D03*
X1197333Y863845D03*
X1191591Y867192D03*
X1198183Y853806D03*
X1191591Y857152D03*
X1198183Y877231D03*
X1197333Y870538D03*
X1198183Y883924D03*
X1190741Y873885D03*
Y880577D03*
X1198183Y900656D03*
Y890617D03*
X1190741Y893963D03*
Y887270D03*
X1198183Y914042D03*
Y907349D03*
X1190741Y917389D03*
Y910696D03*
Y904003D03*
X1197383Y927428D03*
X1198183Y920735D03*
X1191591Y930774D03*
Y924081D03*
X1198183Y944160D03*
X1197333Y937467D03*
X1190741Y940814D03*
Y947507D03*
X1198183Y960892D03*
Y950853D03*
X1190741Y964239D03*
Y954200D03*
X1198183Y980971D03*
Y974278D03*
Y967585D03*
X1190741Y970932D03*
Y977625D03*
X1198183Y987664D03*
X1190741Y991011D03*
Y984318D03*
X1198183Y1027822D03*
Y1017782D03*
X1190741Y1031168D03*
Y1017782D03*
Y1024475D03*
X1198183Y1047900D03*
Y1041207D03*
Y1034515D03*
X1190741Y1044554D03*
Y1037861D03*
X1198183Y1054593D03*
Y1061286D03*
X1190741Y1057940D03*
Y1051247D03*
X1197333Y1074672D03*
X1198183Y1067979D03*
X1191591Y1078018D03*
X1190741Y1071326D03*
Y1064633D03*
X1198183Y1091404D03*
X1197333Y1084711D03*
X1190741Y1094751D03*
X1191591Y1088058D03*
X1198183Y1111483D03*
Y1098097D03*
Y1104790D03*
X1190741Y1101444D03*
Y1108137D03*
X1198183Y1128215D03*
Y1121522D03*
X1190741Y1114829D03*
Y1124869D03*
X1198183Y1141601D03*
X1197333Y1134908D03*
X1190741Y1144948D03*
Y1138255D03*
Y1131562D03*
X1198183Y1158333D03*
X1197333Y1148294D03*
X1191591Y1161680D03*
Y1151641D03*
X1198183Y1165026D03*
Y1171719D03*
X1190741Y1168373D03*
Y1175066D03*
X1198183Y1185105D03*
Y1178412D03*
X1190741Y1188452D03*
Y1181759D03*
X1198183Y1208530D03*
Y1201837D03*
Y1195144D03*
X1190741Y1205184D03*
Y1198491D03*
X1198183Y1221916D03*
Y1215223D03*
X1191591Y1225263D03*
X1190741Y1211877D03*
Y1218570D03*
X1197333Y1238648D03*
Y1231955D03*
X1190741Y1241995D03*
X1191591Y1235302D03*
X1198183Y1245341D03*
X1190966Y1258711D03*
X1190741Y1248688D03*
X1191538Y1270004D03*
X1194572Y1578182D03*
Y1590094D03*
X1199872Y1614292D03*
Y1602380D03*
X1211741Y770144D03*
X1206883Y766798D03*
X1211741Y783530D03*
Y776837D03*
X1206883Y780184D03*
Y773491D03*
X1211741Y800263D03*
Y793570D03*
X1206883Y803609D03*
Y796916D03*
Y790223D03*
X1210891Y820341D03*
Y813648D03*
X1211741Y806955D03*
X1207148Y817554D03*
X1206883Y810302D03*
X1211741Y830381D03*
X1206883Y833727D03*
X1207733Y827034D03*
X1211741Y850459D03*
Y837074D03*
Y843766D03*
X1206883Y847113D03*
Y840420D03*
X1210891Y867492D03*
X1207733Y863845D03*
X1210891Y857152D03*
X1206883Y853806D03*
X1211741Y874185D03*
Y880577D03*
X1206883Y877231D03*
X1207201Y871084D03*
X1206883Y883924D03*
X1211741Y893963D03*
Y887270D03*
X1206883Y900656D03*
Y890617D03*
X1211741Y917389D03*
Y910696D03*
Y904003D03*
X1206883Y914042D03*
Y907349D03*
X1211741Y930774D03*
Y924081D03*
X1207683Y927428D03*
X1206883Y920735D03*
X1211741Y947507D03*
X1211001Y940814D03*
X1206883Y944660D03*
X1207733Y937467D03*
X1211741Y964239D03*
Y954200D03*
X1206883Y960892D03*
Y950853D03*
X1211741Y977625D03*
Y970932D03*
X1206883Y980971D03*
Y974278D03*
Y967585D03*
X1211741Y991011D03*
X1206883Y987664D03*
X1211741Y984318D03*
Y1031168D03*
X1206883Y1027822D03*
Y1017782D03*
X1211741D03*
Y1024475D03*
Y1044554D03*
Y1037861D03*
X1206883Y1047900D03*
Y1041207D03*
Y1034515D03*
X1211741Y1051247D03*
Y1057940D03*
X1206883Y1054593D03*
Y1061286D03*
X1210891Y1078018D03*
X1211741Y1064633D03*
Y1071326D03*
X1207733Y1074672D03*
X1206883Y1067979D03*
X1211741Y1094751D03*
X1210891Y1088058D03*
X1206883Y1091404D03*
Y1084711D03*
X1211741Y1108137D03*
Y1101444D03*
X1206883Y1111483D03*
Y1098097D03*
Y1104790D03*
X1210891Y1124869D03*
X1211741Y1114829D03*
X1206883Y1128215D03*
Y1121522D03*
X1211741Y1144948D03*
Y1138255D03*
X1210891Y1131562D03*
X1206883Y1141601D03*
X1207733Y1134908D03*
X1211741Y1151641D03*
Y1161680D03*
X1206883Y1158333D03*
X1207733Y1148294D03*
X1211741Y1175066D03*
Y1168373D03*
X1206883Y1165026D03*
Y1171719D03*
X1211741Y1188452D03*
Y1181759D03*
X1206883Y1185105D03*
Y1178412D03*
X1211741Y1205184D03*
Y1198491D03*
X1206883Y1208530D03*
Y1201837D03*
Y1195144D03*
X1210891Y1225263D03*
X1211741Y1218570D03*
Y1211877D03*
X1206883Y1221916D03*
Y1215223D03*
X1211741Y1241995D03*
X1211328Y1234977D03*
X1207733Y1238648D03*
Y1231955D03*
X1206883Y1245341D03*
X1211741Y1248688D03*
X1204608Y1273119D03*
X1202043Y1273123D03*
X1202372Y1578182D03*
X1214432D03*
X1206632D03*
X1202372Y1590094D03*
X1214432D03*
X1206632D03*
X1207672Y1602380D03*
Y1614292D03*
X1211932D03*
Y1602380D03*
X1227883Y766798D03*
X1220441Y770144D03*
X1227883Y780184D03*
Y773491D03*
X1220441Y783530D03*
Y776837D03*
X1227883Y803609D03*
Y796916D03*
Y790223D03*
X1220441Y800263D03*
Y793570D03*
X1227033Y816995D03*
X1227883Y810302D03*
X1221291Y820341D03*
Y813648D03*
X1220441Y806955D03*
X1227883Y833727D03*
X1227033Y827034D03*
X1220441Y830381D03*
X1227883Y847113D03*
Y840420D03*
X1220441Y850459D03*
Y837074D03*
Y843766D03*
X1227033Y863845D03*
X1221291Y867192D03*
X1227033Y853806D03*
X1221291Y857152D03*
X1227883Y870538D03*
Y883924D03*
Y877231D03*
X1220441Y873885D03*
Y880577D03*
X1227033Y900656D03*
X1227883Y890617D03*
X1220441Y893963D03*
Y887270D03*
X1227883Y914042D03*
Y907349D03*
X1220441Y917389D03*
Y910696D03*
Y904003D03*
X1227033Y927428D03*
X1227883Y920735D03*
X1221291Y930774D03*
X1220441Y924081D03*
X1227883Y944160D03*
X1227033Y937467D03*
X1220441Y947507D03*
X1221291Y940814D03*
X1227883Y960892D03*
Y950853D03*
X1220441Y964239D03*
Y954200D03*
X1227883Y974278D03*
Y967585D03*
X1220441Y977625D03*
Y970932D03*
X1227883Y980971D03*
Y987664D03*
X1220441Y991011D03*
Y984318D03*
X1227883Y1027822D03*
X1220441Y1031168D03*
X1227883Y1017782D03*
X1220441D03*
Y1024475D03*
X1227883Y1047900D03*
Y1041207D03*
Y1034515D03*
X1220441Y1044554D03*
Y1037861D03*
X1227883Y1061286D03*
Y1054593D03*
X1220441Y1051247D03*
Y1057940D03*
X1227033Y1074672D03*
Y1067979D03*
X1221291Y1078018D03*
X1220441Y1064633D03*
Y1071326D03*
X1227883Y1091404D03*
Y1084711D03*
X1220441Y1094751D03*
X1221291Y1088058D03*
X1227883Y1104790D03*
X1227033Y1111483D03*
X1227883Y1098097D03*
X1220441Y1108137D03*
Y1101444D03*
X1227883Y1128215D03*
X1227033Y1121522D03*
X1221291Y1124869D03*
X1220441Y1114829D03*
X1227883Y1134908D03*
Y1141601D03*
X1220441Y1144948D03*
Y1138255D03*
X1221291Y1131562D03*
X1227883Y1158333D03*
Y1148294D03*
X1220441Y1151641D03*
Y1161680D03*
X1227883Y1171719D03*
Y1165026D03*
X1220441Y1175066D03*
Y1168373D03*
X1227883Y1185105D03*
Y1178412D03*
X1220441Y1188452D03*
Y1181759D03*
X1227883Y1208530D03*
Y1201837D03*
X1227033Y1195144D03*
X1220441Y1205184D03*
Y1198491D03*
X1227033Y1221916D03*
X1227883Y1215223D03*
X1221291Y1225263D03*
X1220441Y1218570D03*
Y1211877D03*
X1227883Y1238648D03*
X1227033Y1231955D03*
X1220441Y1241995D03*
X1221291Y1235302D03*
X1220441Y1248688D03*
X1227883Y1245341D03*
X1220601Y1269684D03*
X1220931Y1260093D03*
X1233327Y1274515D03*
X1231377Y1275855D03*
X1218692Y1578182D03*
X1226492D03*
X1230752D03*
X1218692Y1590094D03*
X1226492D03*
X1230752D03*
X1219732Y1614292D03*
Y1602380D03*
X1231792Y1614292D03*
Y1602380D03*
X1223992D03*
Y1614292D03*
X1236583Y766798D03*
Y780184D03*
Y773491D03*
Y803609D03*
Y796916D03*
Y790223D03*
X1237433Y816995D03*
X1236583Y810302D03*
Y833727D03*
X1237433Y827034D03*
X1236583Y847113D03*
Y840420D03*
X1237433Y863845D03*
Y853806D03*
X1236583Y870538D03*
Y883924D03*
Y877231D03*
Y900656D03*
Y890617D03*
Y914042D03*
Y907349D03*
X1237433Y927428D03*
X1236583Y920735D03*
Y944160D03*
X1237433Y937467D03*
X1236583Y960892D03*
Y950853D03*
Y974278D03*
Y967585D03*
Y980971D03*
Y987664D03*
Y1027822D03*
Y1017782D03*
Y1047900D03*
Y1041207D03*
Y1034515D03*
Y1061286D03*
Y1054593D03*
X1237433Y1074672D03*
Y1067979D03*
X1236583Y1091404D03*
Y1084711D03*
Y1104790D03*
X1237433Y1111483D03*
X1236583Y1098097D03*
Y1128215D03*
X1237433Y1121522D03*
X1236583Y1134908D03*
Y1141601D03*
Y1158333D03*
Y1148294D03*
Y1171719D03*
Y1165026D03*
Y1185105D03*
Y1178412D03*
Y1208530D03*
Y1201837D03*
Y1195144D03*
X1237433Y1221916D03*
X1236583Y1215223D03*
Y1238648D03*
X1237433Y1231955D03*
X1236583Y1245341D03*
X1238552Y1578182D03*
X1242812D03*
X1238552Y1590094D03*
X1242812D03*
X1236052Y1602380D03*
Y1614292D03*
X1243852D03*
Y1602380D03*
X1248112D03*
Y1614292D03*
X1241142Y1675383D03*
Y1679920D03*
X1249016Y1679320D03*
X1241142Y1684454D03*
Y1689556D03*
Y1694093D03*
Y1698627D03*
X1249016Y1688391D03*
Y1693493D03*
Y1698030D03*
Y1683857D03*
X1241142Y1703729D03*
Y1708266D03*
Y1712800D03*
X1249016Y1707666D03*
Y1712203D03*
Y1702564D03*
X1241142Y1726974D03*
Y1722440D03*
Y1717903D03*
X1249016Y1730911D03*
Y1726377D03*
Y1721840D03*
Y1716737D03*
X1250612Y1578182D03*
X1262672D03*
X1254872D03*
X1250612Y1590094D03*
X1262672D03*
X1254872D03*
X1255912Y1614292D03*
Y1602380D03*
X1260172D03*
Y1614292D03*
X1256890Y1675383D03*
Y1679920D03*
X1264764Y1679320D03*
X1256890Y1684454D03*
Y1689556D03*
Y1694093D03*
Y1698627D03*
X1264764Y1688391D03*
Y1693493D03*
Y1698030D03*
Y1683857D03*
X1256890Y1703729D03*
Y1708266D03*
Y1712800D03*
X1264764Y1707666D03*
Y1712203D03*
Y1702564D03*
X1256890Y1726974D03*
Y1722440D03*
Y1717903D03*
X1264764Y1730911D03*
Y1726377D03*
Y1721840D03*
Y1716737D03*
X1266932Y1578182D03*
X1274732D03*
X1278992D03*
X1266932Y1590094D03*
X1274732D03*
X1278992D03*
X1267972Y1614292D03*
Y1602380D03*
X1272232D03*
Y1614292D03*
X1280032D03*
Y1602380D03*
X1272638Y1675383D03*
Y1679920D03*
X1280512Y1679320D03*
X1272638Y1684454D03*
Y1689556D03*
Y1694093D03*
Y1698627D03*
X1280512Y1688391D03*
Y1693493D03*
Y1698030D03*
Y1683857D03*
X1272638Y1703729D03*
Y1708266D03*
Y1712800D03*
X1280512Y1707666D03*
Y1712203D03*
Y1702564D03*
X1272638Y1726974D03*
Y1722440D03*
Y1717903D03*
X1280512Y1730911D03*
Y1726377D03*
Y1721840D03*
Y1716737D03*
X1286792Y1578182D03*
X1298852D03*
X1291052D03*
X1286792Y1590094D03*
X1298852D03*
X1291052D03*
X1284292Y1602380D03*
Y1614292D03*
X1292092D03*
Y1602380D03*
X1296352D03*
Y1614292D03*
X1296260Y1679320D03*
X1288386Y1675383D03*
Y1679920D03*
X1296260Y1688391D03*
Y1693493D03*
Y1698030D03*
Y1683857D03*
X1288386Y1684454D03*
Y1689556D03*
Y1694093D03*
Y1698627D03*
X1296260Y1707666D03*
Y1712203D03*
Y1702564D03*
X1288386Y1703729D03*
Y1708266D03*
Y1712800D03*
X1296260Y1730911D03*
Y1726377D03*
Y1721840D03*
Y1716737D03*
X1288386Y1726974D03*
Y1722440D03*
Y1717903D03*
X1314353Y1124651D03*
X1303112Y1578182D03*
X1310912D03*
X1315172D03*
X1303112Y1590094D03*
X1310912D03*
X1315172D03*
X1304152Y1602380D03*
Y1614292D03*
X1308412Y1602380D03*
Y1614292D03*
X1308071Y1675383D03*
Y1679920D03*
Y1684454D03*
Y1689556D03*
Y1694093D03*
Y1698627D03*
Y1703729D03*
Y1708266D03*
Y1712800D03*
Y1726974D03*
Y1722440D03*
Y1717903D03*
X1328721Y854584D03*
X1323171Y870606D03*
Y889832D03*
X1319849Y1091513D03*
X1318053Y1124651D03*
X1321753Y1131060D03*
X1322972Y1578182D03*
X1327232D03*
X1322972Y1590094D03*
X1327232D03*
X1316212Y1614292D03*
Y1602380D03*
X1328272D03*
Y1614292D03*
X1320472Y1602380D03*
Y1614292D03*
X1323819Y1675383D03*
Y1679920D03*
X1315945Y1679320D03*
X1323819Y1684454D03*
Y1689556D03*
Y1694093D03*
Y1698627D03*
X1315945Y1688391D03*
Y1693493D03*
Y1698030D03*
Y1683857D03*
X1323819Y1703729D03*
Y1708266D03*
Y1712800D03*
X1315945Y1707666D03*
Y1712203D03*
Y1702564D03*
X1323819Y1726974D03*
Y1722440D03*
Y1717903D03*
X1315945Y1730911D03*
Y1726377D03*
Y1721840D03*
Y1716737D03*
X1336121Y880219D03*
Y899445D03*
X1347220D03*
X1336121Y918670D03*
X1341671Y941100D03*
X1336121Y937896D03*
X1347220D03*
X1345804Y1006093D03*
X1342104Y1076587D03*
X1335032Y1578182D03*
X1347092D03*
X1339292D03*
X1335032Y1590094D03*
X1347092D03*
X1339292D03*
X1340332Y1602380D03*
Y1614292D03*
X1332532Y1602380D03*
Y1614292D03*
X1344592Y1602380D03*
Y1614292D03*
X1339567Y1675383D03*
Y1679920D03*
X1331693Y1679320D03*
X1347441D03*
X1339567Y1684454D03*
Y1689556D03*
Y1694093D03*
Y1698627D03*
X1331693Y1688391D03*
Y1693493D03*
Y1698030D03*
Y1683857D03*
X1347441Y1688391D03*
Y1693493D03*
Y1698030D03*
Y1683857D03*
X1339567Y1703729D03*
Y1708266D03*
Y1712800D03*
X1331693Y1707666D03*
Y1712203D03*
Y1702564D03*
X1347441Y1707666D03*
Y1712203D03*
Y1702564D03*
X1339567Y1726974D03*
Y1722440D03*
Y1717903D03*
X1331693Y1730911D03*
Y1726377D03*
Y1721840D03*
Y1716737D03*
X1347441Y1730911D03*
Y1726377D03*
Y1721840D03*
Y1716737D03*
X1354620Y931488D03*
X1355053Y1060565D03*
X1351352Y1578182D03*
X1359152D03*
X1363412D03*
X1351352Y1590094D03*
X1359152D03*
X1363412D03*
X1352392Y1602380D03*
Y1614292D03*
X1356652Y1602380D03*
Y1614292D03*
X1363189Y1679320D03*
X1355315Y1675383D03*
Y1679920D03*
X1363189Y1688391D03*
Y1693493D03*
Y1698030D03*
Y1683857D03*
X1355315Y1684454D03*
Y1689556D03*
Y1694093D03*
Y1698627D03*
X1363189Y1707666D03*
Y1712203D03*
Y1702564D03*
X1355315Y1703729D03*
Y1708266D03*
Y1712800D03*
X1363189Y1730911D03*
Y1726377D03*
Y1721840D03*
Y1716737D03*
X1355315Y1726974D03*
Y1722440D03*
Y1717903D03*
X1373120Y899445D03*
Y931488D03*
Y937896D03*
X1371212Y1578088D03*
X1375472Y1578182D03*
X1371212Y1590094D03*
X1375472D03*
X1364452Y1602380D03*
Y1614292D03*
X1376512Y1602286D03*
Y1614292D03*
X1368712Y1602380D03*
Y1614292D03*
X1393716Y985579D03*
X1391326D03*
Y1014539D03*
X1393716D03*
X1393903Y1115039D03*
X1392053Y1118243D03*
X1390203Y1121447D03*
X1388353Y1124651D03*
Y1118243D03*
X1390204Y1134264D03*
X1388354Y1131060D03*
X1383272Y1578182D03*
Y1590094D03*
X1380772Y1602380D03*
Y1614292D03*
X1388572D03*
Y1602380D03*
X1411971Y851380D03*
Y864197D03*
Y877014D03*
Y889832D03*
Y902649D03*
X1404571Y921875D03*
X1410121Y944304D03*
Y957122D03*
Y950713D03*
Y963530D03*
Y976347D03*
Y969939D03*
Y982756D03*
X1410553Y1009297D03*
Y1002888D03*
Y1028523D03*
Y1022114D03*
Y1015705D03*
X1405004Y1044544D03*
X1410553Y1034931D03*
X1406854Y1047749D03*
X1399453D03*
X1408703Y1050952D03*
X1401304Y1057361D03*
X1410553Y1060565D03*
Y1054157D03*
X1408703Y1076587D03*
X1406853Y1073383D03*
X1403153D03*
Y1066974D03*
X1401304Y1076587D03*
X1399453Y1066974D03*
X1410553Y1073383D03*
Y1066974D03*
X1403154Y1079791D03*
X1410553D03*
X1408703Y1089404D03*
Y1082995D03*
X1405003D03*
X1401304Y1089404D03*
X1410553Y1092608D03*
Y1086200D03*
X1408703Y1095813D03*
X1405003D03*
X1403153Y1099017D03*
X1401303Y1102221D03*
X1399453Y1105426D03*
X1397604Y1108630D03*
X1410553Y1105426D03*
X1399453Y1111834D03*
X1410553D03*
X1399453Y1124651D03*
Y1118243D03*
X1397604Y1115039D03*
X1410553Y1124651D03*
Y1118243D03*
X1399454Y1137469D03*
X1399453Y1131060D03*
X1410554Y1137769D03*
X1410553Y1131060D03*
X1426771Y851380D03*
Y877014D03*
X1413820Y912262D03*
X1423070Y941100D03*
X1423071Y947509D03*
Y960326D03*
Y953917D03*
Y966735D03*
Y979552D03*
Y973143D03*
X1423503Y1006093D03*
Y999684D03*
Y1012501D03*
Y1025318D03*
Y1018910D03*
Y1031727D03*
X1429053Y1041340D03*
X1423503Y1038136D03*
X1429053Y1092608D03*
X1427204Y1089404D03*
X1427203Y1095812D03*
X1429053Y1099017D03*
X1423503Y1108630D03*
Y1102221D03*
Y1121447D03*
Y1115039D03*
Y1127856D03*
Y1134264D03*
X1432320Y912262D03*
X1437871Y921875D03*
X1438402Y942151D03*
X1440702D03*
X1443002D03*
X1430564Y949138D03*
X1440015Y956539D03*
X1430564Y951438D03*
X1442413Y956539D03*
X1430534Y963828D03*
Y966128D03*
X1440015Y971139D03*
X1442413Y971099D03*
X1430404Y981208D03*
Y978908D03*
X1440015Y985579D03*
X1430604Y995298D03*
Y992998D03*
X1442413Y985579D03*
X1440015Y1014539D03*
Y1000059D03*
X1430584Y1009408D03*
Y1007108D03*
X1442413Y1014539D03*
Y1000059D03*
X1436454Y1105426D03*
X1434604Y1102221D03*
X1432753Y1099017D03*
X1440154Y1105426D03*
X1438304Y1108630D03*
X1440154Y1111834D03*
X1434604Y1121447D03*
Y1115039D03*
X1443854Y1124651D03*
X1443853Y1118243D03*
X1442004Y1121447D03*
Y1115039D03*
X1434604Y1127856D03*
Y1134264D03*
X1450820Y899445D03*
Y912262D03*
X1445703Y1115039D03*
X1447553Y1118243D03*
X1445704Y1127856D03*
X1445703Y1140973D03*
X1447554Y1137469D03*
Y1131060D03*
X1460095Y1578182D03*
Y1590094D03*
X1465620Y912262D03*
X1471604Y1108630D03*
X1469753Y1111834D03*
X1472155Y1578182D03*
X1467895D03*
X1472155Y1590094D03*
X1467895D03*
X1477455Y1602380D03*
Y1614292D03*
X1473195D03*
Y1602380D03*
X1465395D03*
Y1614292D03*
X1484120Y937896D03*
X1485971Y947509D03*
X1491953Y1086200D03*
X1492015Y1578182D03*
X1484215D03*
X1479955D03*
X1492015Y1590094D03*
X1484215D03*
X1479955D03*
X1489515Y1614292D03*
Y1602380D03*
X1485255D03*
Y1614292D03*
X1508335Y1578182D03*
X1496275D03*
X1504075D03*
X1508335Y1590094D03*
X1496275D03*
X1504075D03*
X1501575Y1614292D03*
Y1602380D03*
X1509375D03*
Y1614292D03*
X1497315Y1602380D03*
Y1614292D03*
X1505315Y1675383D03*
Y1679920D03*
Y1684454D03*
Y1689556D03*
Y1694093D03*
Y1698627D03*
Y1703729D03*
Y1708266D03*
Y1712800D03*
Y1726974D03*
Y1722440D03*
Y1717903D03*
X1511871Y928283D03*
X1519271D03*
X1515571D03*
X1524820Y925079D03*
X1513720D03*
X1524820Y944304D03*
X1513720D03*
X1520395Y1578182D03*
X1516135D03*
X1520395Y1590094D03*
X1516135D03*
X1525695Y1614292D03*
Y1602380D03*
X1521435D03*
Y1614292D03*
X1513635D03*
Y1602380D03*
X1521063Y1675383D03*
Y1679920D03*
X1513189Y1679320D03*
X1521063Y1684454D03*
Y1689556D03*
Y1694093D03*
Y1698627D03*
X1513189Y1688391D03*
Y1693493D03*
Y1698030D03*
Y1683857D03*
X1521063Y1703729D03*
Y1708266D03*
Y1712800D03*
X1513189Y1707666D03*
Y1712203D03*
Y1702564D03*
X1521063Y1726974D03*
Y1722440D03*
Y1717903D03*
X1513189Y1730911D03*
Y1726377D03*
Y1721840D03*
Y1716737D03*
X1540255Y1578182D03*
X1532455D03*
X1528195D03*
X1540255Y1590094D03*
X1532455D03*
X1528195D03*
X1537755Y1614292D03*
Y1602380D03*
X1533495D03*
Y1614292D03*
X1536811Y1675383D03*
Y1679920D03*
X1528937Y1679320D03*
X1536811Y1684454D03*
Y1689556D03*
Y1694093D03*
Y1698627D03*
X1528937Y1688391D03*
Y1693493D03*
Y1698030D03*
Y1683857D03*
X1536811Y1703729D03*
Y1708266D03*
Y1712800D03*
X1528937Y1707666D03*
Y1712203D03*
Y1702564D03*
X1536811Y1726974D03*
Y1722440D03*
Y1717903D03*
X1528937Y1730911D03*
Y1726377D03*
Y1721840D03*
Y1716737D03*
X1556575Y1578182D03*
X1544515D03*
X1552315D03*
X1556575Y1590094D03*
X1544515D03*
X1552315D03*
X1549815Y1614292D03*
Y1602380D03*
X1557615D03*
Y1614292D03*
X1545555Y1602380D03*
Y1614292D03*
X1552559Y1675383D03*
Y1679920D03*
X1544685Y1679320D03*
X1552559Y1684454D03*
Y1689556D03*
Y1694093D03*
Y1698627D03*
X1544685Y1688391D03*
Y1693493D03*
Y1698030D03*
Y1683857D03*
X1552559Y1703729D03*
Y1708266D03*
Y1712800D03*
X1544685Y1707666D03*
Y1712203D03*
Y1702564D03*
X1552559Y1726974D03*
Y1722440D03*
Y1717903D03*
X1544685Y1730911D03*
Y1726377D03*
Y1721840D03*
Y1716737D03*
X1568635Y1578182D03*
X1564375D03*
X1568635Y1590094D03*
X1564375D03*
X1573935Y1614292D03*
Y1602380D03*
X1569675Y1614292D03*
Y1602380D03*
X1561875Y1614292D03*
Y1602380D03*
X1560433Y1679320D03*
X1572244Y1675383D03*
Y1679920D03*
X1560433Y1688391D03*
Y1693493D03*
Y1698030D03*
Y1683857D03*
X1572244Y1684454D03*
Y1689556D03*
Y1694093D03*
Y1698627D03*
X1560433Y1707666D03*
Y1712203D03*
Y1702564D03*
X1572244Y1703729D03*
Y1708266D03*
Y1712800D03*
X1560433Y1730911D03*
Y1726377D03*
Y1721840D03*
Y1716737D03*
X1572244Y1726974D03*
Y1722440D03*
Y1717903D03*
X1588495Y1578182D03*
X1580695D03*
X1576435D03*
X1588495Y1590094D03*
X1580695D03*
X1576435D03*
X1585995Y1614292D03*
Y1602380D03*
X1581735D03*
Y1614292D03*
X1587992Y1675383D03*
Y1679920D03*
X1580118Y1679320D03*
X1587992Y1684454D03*
Y1689556D03*
Y1694093D03*
Y1698627D03*
X1580118Y1688391D03*
Y1693493D03*
Y1698030D03*
Y1683857D03*
X1587992Y1703729D03*
Y1708266D03*
Y1712800D03*
X1580118Y1707666D03*
Y1712203D03*
Y1702564D03*
X1587992Y1726974D03*
Y1722440D03*
Y1717903D03*
X1580118Y1730911D03*
Y1726377D03*
Y1721840D03*
Y1716737D03*
X1597041Y770144D03*
X1605741D03*
Y776837D03*
X1597041D03*
X1605741Y783530D03*
X1597041D03*
X1605741Y793570D03*
X1597041D03*
X1596988Y800263D03*
X1605741D03*
X1595774Y806955D03*
X1606934D03*
X1596218Y813648D03*
X1606735D03*
X1597041Y820341D03*
X1605741D03*
X1597041Y830381D03*
X1605741D03*
Y837074D03*
X1597041D03*
Y843766D03*
X1605741D03*
X1596147Y850459D03*
X1606896D03*
X1596200Y857152D03*
X1606623D03*
X1597041Y867192D03*
X1605741D03*
X1597041Y873885D03*
X1605741D03*
X1597041Y880577D03*
X1605741D03*
X1597041Y887270D03*
X1605741D03*
X1606898Y893963D03*
X1597041D03*
X1605741Y904003D03*
X1597041D03*
Y917389D03*
X1605741D03*
X1597041Y910696D03*
X1605741D03*
X1597041Y924081D03*
X1605741D03*
X1606541Y930697D03*
X1596047Y930774D03*
X1596106Y940814D03*
X1606919D03*
X1605741Y947507D03*
X1597041D03*
X1605741Y954200D03*
X1597041D03*
Y964239D03*
X1605741D03*
X1597041Y977625D03*
X1605741D03*
Y970932D03*
X1597041D03*
Y984318D03*
X1605741D03*
X1597041Y991011D03*
X1605741D03*
X1597041Y1024475D03*
X1605741D03*
X1597041Y1017782D03*
X1605741D03*
X1597041Y1031168D03*
X1605741D03*
X1597041Y1037861D03*
X1605741D03*
X1597041Y1044554D03*
X1605741D03*
Y1051247D03*
X1597041D03*
Y1057940D03*
X1605741D03*
X1597041Y1064633D03*
X1605741D03*
X1606541Y1071326D03*
X1596141D03*
X1597041Y1078018D03*
X1605741D03*
Y1094751D03*
X1597041D03*
Y1088058D03*
X1605741D03*
Y1101444D03*
X1597041D03*
Y1108137D03*
X1605741D03*
X1606541Y1114829D03*
X1596241D03*
X1596511Y1124969D03*
X1606505Y1124674D03*
X1605741Y1138255D03*
X1597041D03*
X1605741Y1144948D03*
X1597041D03*
Y1131562D03*
X1605741D03*
Y1151641D03*
X1597041D03*
X1596653Y1161680D03*
X1605975Y1161581D03*
X1605741Y1168373D03*
X1597041D03*
X1605741Y1175066D03*
X1597041D03*
X1605741Y1181759D03*
X1597041D03*
X1606765Y1188452D03*
X1597041D03*
Y1198491D03*
X1605741D03*
Y1205184D03*
X1597041D03*
Y1211877D03*
X1605741D03*
X1597041Y1218570D03*
X1605741D03*
X1597041Y1225263D03*
X1605741D03*
X1607064Y1235302D03*
X1596178D03*
X1605741Y1241995D03*
X1597041D03*
Y1248688D03*
X1605741D03*
X1603788Y1273144D03*
X1601388D03*
X1604815Y1578182D03*
X1592755D03*
X1600555D03*
X1604815Y1590094D03*
X1592755D03*
X1600555D03*
X1598055Y1614292D03*
Y1602380D03*
X1605855Y1614292D03*
Y1602380D03*
X1593795Y1614292D03*
Y1602380D03*
X1603740Y1675383D03*
Y1679920D03*
X1595866Y1679320D03*
X1603740Y1684454D03*
Y1689556D03*
Y1694093D03*
Y1698627D03*
X1595866Y1688391D03*
Y1693493D03*
Y1698030D03*
Y1683857D03*
X1603740Y1703729D03*
Y1708266D03*
Y1712800D03*
X1595866Y1707666D03*
Y1712203D03*
Y1702564D03*
X1603740Y1726974D03*
Y1722440D03*
Y1717903D03*
X1595866Y1730911D03*
Y1726377D03*
Y1721840D03*
Y1716737D03*
X1613183Y766798D03*
X1621883D03*
Y773491D03*
X1613183D03*
X1621883Y780184D03*
X1613183D03*
X1621883Y790223D03*
X1613183D03*
Y796916D03*
X1621883D03*
X1613183Y803609D03*
X1621883D03*
X1622916Y816995D03*
X1613183D03*
X1612363Y810302D03*
X1622986D03*
X1613183Y827034D03*
X1621883D03*
Y833727D03*
X1613183D03*
Y840420D03*
X1621883D03*
X1613183Y847113D03*
X1621943D03*
X1622060Y863845D03*
X1612408D03*
X1612474Y853955D03*
X1622961Y853806D03*
X1621883Y883924D03*
X1613183D03*
Y870538D03*
X1621883D03*
X1613183Y877231D03*
X1621883D03*
X1613183Y890617D03*
X1621883D03*
X1613183Y900656D03*
X1621883D03*
Y907349D03*
X1613183D03*
Y914042D03*
X1621883D03*
Y920735D03*
X1613183D03*
X1622535Y927526D03*
X1612168Y927428D03*
X1622845Y937467D03*
X1612312D03*
X1621883Y944160D03*
X1613183D03*
X1621883Y950853D03*
X1613183D03*
X1621883Y960892D03*
X1613183D03*
Y974278D03*
X1621883D03*
X1613183Y980971D03*
X1621883D03*
X1613183Y967585D03*
X1621883D03*
X1613183Y987664D03*
X1621883D03*
Y1017782D03*
X1613183D03*
Y1027822D03*
X1621883D03*
X1613183Y1034515D03*
X1621883D03*
X1613183Y1041207D03*
X1621883D03*
X1613183Y1047900D03*
X1621883D03*
Y1054593D03*
X1613183D03*
Y1061286D03*
X1621883D03*
Y1067979D03*
X1612983D03*
X1612283Y1074672D03*
X1622683D03*
X1621883Y1084711D03*
X1612383D03*
X1613183Y1091404D03*
X1621883D03*
Y1104790D03*
X1613183D03*
X1621883Y1098097D03*
X1613183D03*
X1621883Y1111483D03*
X1613183D03*
Y1128915D03*
X1621883Y1128215D03*
X1613183Y1121522D03*
X1621883D03*
Y1141601D03*
X1613183D03*
X1622726Y1135108D03*
X1611886Y1134908D03*
X1621883Y1158333D03*
X1613183D03*
X1621883Y1148294D03*
X1613183D03*
X1621883Y1165026D03*
X1613183D03*
Y1171719D03*
X1621883D03*
Y1178412D03*
X1613183D03*
X1621883Y1185105D03*
X1613183D03*
Y1195144D03*
X1621883D03*
Y1201837D03*
X1613183D03*
X1621883Y1208530D03*
X1613183D03*
X1621883Y1215223D03*
X1613183D03*
X1612147Y1221916D03*
X1622712D03*
X1612137Y1231862D03*
X1622681Y1231955D03*
X1621883Y1238648D03*
X1613183D03*
X1610150Y1257172D03*
X1621883Y1245341D03*
X1613183D03*
X1618888Y1273344D03*
X1616088D03*
X1616875Y1578182D03*
X1612615D03*
X1616875Y1590094D03*
X1612615D03*
X1622175Y1614292D03*
Y1602380D03*
X1617915Y1614292D03*
Y1602380D03*
X1610115Y1614292D03*
Y1602380D03*
X1619488Y1675383D03*
Y1679920D03*
X1611614Y1679320D03*
X1619488Y1684454D03*
Y1689556D03*
Y1694093D03*
Y1698627D03*
X1611614Y1688391D03*
Y1693493D03*
Y1698030D03*
Y1683857D03*
X1619488Y1703729D03*
Y1708266D03*
Y1712800D03*
X1611614Y1707666D03*
Y1712203D03*
Y1702564D03*
X1619488Y1726974D03*
Y1722440D03*
Y1717903D03*
X1611614Y1730911D03*
Y1726377D03*
Y1721840D03*
Y1716737D03*
X1626741Y770144D03*
X1635441D03*
X1626741Y776837D03*
X1635441D03*
X1626741Y783530D03*
X1635441D03*
X1626741Y793570D03*
X1635441D03*
Y800263D03*
X1626741D03*
X1636341Y820341D03*
X1626741D03*
X1636574Y813648D03*
X1626741D03*
X1635441Y806955D03*
X1626741D03*
X1635441Y830381D03*
X1626741D03*
X1635441Y837074D03*
X1626741D03*
Y843766D03*
X1635441D03*
Y850459D03*
X1626741D03*
X1625705Y867192D03*
X1636441D03*
X1635441Y857152D03*
X1626741D03*
Y880577D03*
X1635441D03*
Y873885D03*
X1626741D03*
Y887270D03*
X1635441D03*
X1626741Y893963D03*
X1635441D03*
X1626741Y904003D03*
X1635441D03*
Y910696D03*
X1626741D03*
X1635441Y917389D03*
X1626741D03*
X1636316Y930774D03*
X1625803D03*
X1636646Y924081D03*
X1626741D03*
X1635441Y940814D03*
X1626741D03*
X1635441Y947507D03*
X1626741D03*
X1635441Y954200D03*
X1626741D03*
Y964239D03*
X1635441D03*
Y977625D03*
X1626741D03*
X1635441Y970932D03*
X1626741D03*
X1635441Y984318D03*
X1626741D03*
Y991011D03*
X1635441D03*
Y1024475D03*
X1626741D03*
X1635441Y1017782D03*
X1626741D03*
X1635441Y1031168D03*
X1626741D03*
X1635441Y1037861D03*
X1626741D03*
X1635441Y1044554D03*
X1626741D03*
Y1057940D03*
X1635441D03*
Y1051247D03*
X1626741D03*
X1635441Y1064633D03*
X1626741D03*
X1635441Y1071326D03*
X1626741D03*
X1636241Y1078018D03*
X1625941D03*
Y1088058D03*
X1636241D03*
X1635441Y1094751D03*
X1626741D03*
Y1101444D03*
X1635441D03*
X1626741Y1108137D03*
X1635441D03*
X1626074Y1124640D03*
X1636341Y1124869D03*
X1635441Y1114829D03*
X1626741D03*
X1635441Y1144948D03*
X1626741D03*
X1635441Y1138255D03*
X1626741D03*
X1635441Y1130762D03*
X1626741D03*
Y1161680D03*
X1635441D03*
Y1151641D03*
X1626741D03*
Y1168373D03*
X1635441D03*
X1626741Y1175066D03*
X1635441D03*
X1626741Y1181759D03*
X1635441D03*
X1626741Y1188452D03*
X1635441D03*
X1626741Y1198491D03*
X1635441D03*
X1626741Y1205184D03*
X1635441D03*
Y1211877D03*
X1626741D03*
X1635441Y1218570D03*
X1626741D03*
X1636212Y1225263D03*
X1626055D03*
X1636376Y1235302D03*
X1625843D03*
X1635441Y1241995D03*
X1626741D03*
X1635688Y1257664D03*
X1626741Y1248688D03*
X1635441D03*
X1629788Y1273344D03*
X1632588D03*
X1625729Y1266766D03*
X1636735Y1578088D03*
X1628935Y1578182D03*
X1624675D03*
X1636735Y1590094D03*
X1628935D03*
X1624675D03*
X1634235Y1614292D03*
Y1602380D03*
X1629975Y1614292D03*
Y1602380D03*
X1627362Y1679320D03*
Y1688391D03*
Y1693493D03*
Y1698030D03*
Y1683857D03*
Y1707666D03*
Y1712203D03*
Y1702564D03*
Y1730911D03*
Y1726377D03*
Y1721840D03*
Y1716737D03*
X1651583Y766798D03*
X1642883D03*
X1656441Y770144D03*
Y776837D03*
X1642883Y773491D03*
X1651583D03*
X1642883Y780184D03*
X1651583D03*
X1656441Y783530D03*
Y793570D03*
X1642883Y790223D03*
X1651583D03*
X1642883Y796916D03*
X1651583D03*
X1656441Y800263D03*
X1651583Y803609D03*
X1642883D03*
X1656441Y806955D03*
Y813648D03*
Y820341D03*
X1651583Y810302D03*
X1642883D03*
X1652545Y816995D03*
X1641945D03*
X1656441Y830381D03*
X1652767Y827034D03*
X1642018D03*
X1651583Y833727D03*
X1642883D03*
X1656441Y837074D03*
Y843766D03*
X1642883Y840420D03*
X1651583D03*
X1656441Y850459D03*
X1651583Y847113D03*
X1642883D03*
X1642058Y863845D03*
X1652742D03*
X1656441Y857152D03*
Y867192D03*
X1652559Y853806D03*
X1642032D03*
X1656441Y873885D03*
Y880577D03*
X1642883Y883924D03*
X1651583D03*
Y870538D03*
X1642883D03*
X1651583Y877231D03*
X1642883D03*
X1656441Y887270D03*
Y893963D03*
X1642883Y890617D03*
X1651583D03*
X1642883Y900656D03*
X1651583D03*
X1656441Y904003D03*
Y910696D03*
X1642883Y907349D03*
X1651583D03*
X1656441Y917389D03*
X1651583Y914042D03*
X1642883D03*
X1656441Y924081D03*
Y930774D03*
X1652630Y927428D03*
X1642038D03*
X1651583Y920735D03*
X1642883D03*
X1656441Y940814D03*
Y947507D03*
X1652501Y937467D03*
X1642065D03*
X1651583Y944160D03*
X1642883D03*
X1656441Y954200D03*
X1642883Y950853D03*
X1651583D03*
Y960892D03*
X1642883D03*
X1656441Y964239D03*
Y977625D03*
Y970932D03*
X1651583Y967585D03*
X1642883D03*
X1651583Y974278D03*
X1642883D03*
X1651583Y980971D03*
X1642883D03*
X1656441Y984318D03*
Y991011D03*
X1651583Y987664D03*
X1642883D03*
X1651583Y1017782D03*
X1642883D03*
X1656441D03*
Y1024475D03*
X1651583Y1027822D03*
X1642883D03*
X1656441Y1031168D03*
Y1044554D03*
Y1037861D03*
X1651583Y1034515D03*
X1642883D03*
X1651583Y1041207D03*
X1642883D03*
X1651583Y1047900D03*
X1642883D03*
Y1061286D03*
X1651583D03*
X1656441Y1051247D03*
Y1057940D03*
X1651583Y1054593D03*
X1642883D03*
X1656441Y1064633D03*
Y1071326D03*
Y1078018D03*
X1652483Y1074672D03*
X1641983D03*
X1651583Y1067979D03*
X1642883D03*
X1656441Y1088058D03*
Y1094751D03*
X1652383Y1084711D03*
X1642083D03*
X1651583Y1091404D03*
X1642883D03*
X1656441Y1101444D03*
Y1108137D03*
X1642883Y1098097D03*
X1651583D03*
X1642883Y1104790D03*
X1651583D03*
X1642883Y1111483D03*
X1651583D03*
X1656441Y1114829D03*
Y1124869D03*
X1642883Y1121522D03*
X1651583D03*
X1642883Y1128215D03*
X1651583D03*
X1656441Y1131562D03*
Y1138255D03*
X1642883Y1134908D03*
X1651583D03*
X1642883Y1141601D03*
X1651583D03*
X1656441Y1144948D03*
Y1151641D03*
Y1161680D03*
X1652383Y1158333D03*
X1642083D03*
X1652794Y1148294D03*
X1641744D03*
X1656441Y1168373D03*
Y1175066D03*
X1642883Y1171719D03*
X1651583D03*
Y1165026D03*
X1642883D03*
X1656441Y1181759D03*
Y1188452D03*
X1651583Y1178412D03*
X1642883D03*
X1651583Y1185105D03*
X1642883D03*
X1656441Y1198491D03*
Y1205184D03*
X1642883Y1195144D03*
X1651583D03*
X1642883Y1201837D03*
X1651583D03*
X1642883Y1208530D03*
X1651583D03*
X1656441Y1211877D03*
X1652590Y1221916D03*
X1641793D03*
X1656441Y1225263D03*
Y1218570D03*
X1651583Y1215223D03*
X1642883D03*
X1656441Y1235302D03*
Y1241995D03*
X1652604Y1231955D03*
X1642054D03*
X1651583Y1238648D03*
X1642883D03*
X1656441Y1248688D03*
X1651583Y1245341D03*
X1642883D03*
X1648588Y1273344D03*
X1645788D03*
X1640995Y1578182D03*
X1648795D03*
X1640995Y1590094D03*
X1648795D03*
X1646295Y1614292D03*
Y1602380D03*
X1654095Y1614292D03*
Y1602380D03*
X1642035Y1614292D03*
Y1602286D03*
X1665141Y770144D03*
X1672583Y766798D03*
X1665141Y776837D03*
Y783530D03*
X1672583Y773491D03*
Y780184D03*
X1665141Y793570D03*
Y800263D03*
X1672583Y790223D03*
Y796916D03*
Y803609D03*
X1665141Y806955D03*
Y813648D03*
X1666030Y820341D03*
X1672583Y810302D03*
Y816995D03*
X1665141Y830381D03*
X1672583Y827034D03*
Y833727D03*
X1665141Y837074D03*
Y843766D03*
X1672583Y840420D03*
X1665141Y850459D03*
X1672583Y847113D03*
X1666038Y857152D03*
X1665141Y867192D03*
X1672583Y853806D03*
Y863845D03*
X1665141Y873885D03*
Y880577D03*
X1672583Y870538D03*
Y877231D03*
Y883924D03*
X1665141Y887270D03*
Y893963D03*
X1672583Y890617D03*
Y900656D03*
X1665141Y904003D03*
Y910696D03*
Y917389D03*
X1672583Y907349D03*
Y914042D03*
X1665141Y924081D03*
X1666246Y930774D03*
X1672583Y920735D03*
Y927428D03*
X1665141Y940814D03*
Y947507D03*
X1672583Y937467D03*
Y944160D03*
X1665141Y954200D03*
Y964239D03*
X1672583Y950853D03*
Y960892D03*
X1665141Y977625D03*
Y970932D03*
X1672583Y967585D03*
Y974278D03*
Y980971D03*
X1665141Y984318D03*
Y991011D03*
X1672583Y987664D03*
X1665141Y1017782D03*
Y1024475D03*
Y1031168D03*
X1672583Y1017782D03*
Y1027822D03*
X1665141Y1044554D03*
Y1037861D03*
X1672583Y1034515D03*
Y1041207D03*
Y1047900D03*
X1665141Y1057940D03*
X1672583Y1061286D03*
Y1054593D03*
X1665141Y1064633D03*
Y1071326D03*
Y1077118D03*
X1672583Y1067979D03*
Y1074672D03*
X1665141Y1088058D03*
Y1094751D03*
X1672583Y1084711D03*
Y1091404D03*
X1665141Y1101444D03*
Y1108137D03*
X1672583Y1098097D03*
Y1104790D03*
Y1111483D03*
X1665141Y1114829D03*
Y1124869D03*
X1672583Y1121522D03*
Y1128215D03*
X1665141Y1131562D03*
Y1138255D03*
Y1144948D03*
X1672583Y1134908D03*
Y1141601D03*
X1666141Y1151641D03*
X1665141Y1161680D03*
X1672583Y1148294D03*
Y1158333D03*
X1665141Y1168373D03*
Y1175066D03*
X1672583Y1165026D03*
Y1171719D03*
X1665141Y1181759D03*
Y1188452D03*
X1672583Y1178412D03*
Y1185105D03*
X1665141Y1198491D03*
Y1205184D03*
X1672583Y1195144D03*
Y1201837D03*
Y1208530D03*
X1665141Y1211877D03*
X1665941Y1225263D03*
X1665141Y1218570D03*
X1672583Y1215223D03*
Y1221916D03*
X1665141Y1235302D03*
Y1241995D03*
X1672583Y1231955D03*
Y1238648D03*
X1665141Y1248688D03*
X1672583Y1245341D03*
X1665688Y1257964D03*
X1659488Y1273344D03*
X1662288D03*
X1681283Y766798D03*
X1686141Y770144D03*
X1681283Y773491D03*
Y780184D03*
X1686141Y776837D03*
Y783530D03*
X1681283Y790223D03*
Y796916D03*
Y803609D03*
X1686141Y793570D03*
Y800263D03*
X1681283Y810302D03*
Y816995D03*
X1686141Y806955D03*
Y813648D03*
Y820341D03*
X1681283Y827034D03*
Y833727D03*
X1686141Y830381D03*
X1681283Y840420D03*
X1686141Y837074D03*
Y843766D03*
Y850459D03*
X1681283Y847113D03*
X1686141Y857152D03*
Y867192D03*
X1681283Y853806D03*
Y863845D03*
X1686141Y873885D03*
Y880577D03*
X1681283Y870538D03*
Y877231D03*
Y883924D03*
X1686141Y887270D03*
Y893963D03*
X1681283Y890617D03*
Y900656D03*
X1686141Y904003D03*
Y910696D03*
Y917389D03*
X1681283Y907349D03*
Y914042D03*
X1686141Y924081D03*
Y930774D03*
X1681283Y920735D03*
Y927428D03*
X1686141Y940814D03*
Y947507D03*
X1681283Y937467D03*
Y944160D03*
X1686141Y954200D03*
Y964239D03*
X1681283Y950853D03*
Y960892D03*
X1686141Y970932D03*
Y977625D03*
X1681283Y967585D03*
Y974278D03*
Y980971D03*
X1686141Y984318D03*
Y991011D03*
X1681283Y987664D03*
X1686141Y1017782D03*
Y1024475D03*
Y1031168D03*
X1681283Y1017782D03*
Y1027822D03*
X1686141Y1037861D03*
Y1044554D03*
X1681283Y1034515D03*
Y1041207D03*
Y1047900D03*
X1686141Y1051247D03*
Y1057940D03*
X1681283Y1061286D03*
Y1054593D03*
X1686141Y1064633D03*
Y1071326D03*
Y1078018D03*
X1681283Y1067979D03*
Y1074672D03*
X1686141Y1088058D03*
Y1094751D03*
X1681283Y1084711D03*
Y1091404D03*
X1686141Y1101444D03*
Y1108137D03*
X1681283Y1098097D03*
Y1104790D03*
Y1111483D03*
X1686141Y1114829D03*
Y1124869D03*
X1681283Y1121522D03*
Y1128215D03*
X1686141Y1131562D03*
Y1138255D03*
Y1144948D03*
X1681283Y1134908D03*
Y1141601D03*
X1686141Y1151641D03*
Y1161680D03*
X1681283Y1148294D03*
Y1158333D03*
X1686141Y1168373D03*
Y1175066D03*
X1681283Y1165026D03*
Y1171719D03*
X1686141Y1181759D03*
Y1188452D03*
X1681283Y1178412D03*
Y1185105D03*
X1686141Y1198491D03*
Y1205184D03*
X1681283Y1195144D03*
Y1201837D03*
Y1208530D03*
X1686141Y1211877D03*
Y1218570D03*
Y1225263D03*
X1681283Y1215223D03*
Y1221916D03*
Y1231955D03*
Y1238648D03*
X1686141Y1235302D03*
Y1241995D03*
X1681283Y1245341D03*
X1686141Y1248688D03*
X1675488Y1273344D03*
X1678288D03*
X1689188D03*
X1694841Y770144D03*
X1702283Y766798D03*
X1694841Y776837D03*
Y783530D03*
X1702283Y773491D03*
Y780184D03*
X1694841Y793570D03*
Y800263D03*
X1702283Y790223D03*
Y796916D03*
Y803609D03*
X1694841Y806955D03*
Y813648D03*
Y820341D03*
X1702283Y810302D03*
Y816995D03*
X1694841Y830381D03*
X1702283Y827034D03*
Y833727D03*
X1694841Y837074D03*
Y843766D03*
Y850459D03*
X1702283Y840420D03*
Y847113D03*
X1694841Y857152D03*
Y867192D03*
X1702283Y853806D03*
Y863845D03*
X1694841Y873885D03*
Y880577D03*
X1702283Y870538D03*
Y877231D03*
Y883924D03*
X1694841Y887270D03*
Y893963D03*
X1702283Y890617D03*
Y900656D03*
X1694841Y904003D03*
Y910696D03*
Y917389D03*
X1702283Y907349D03*
Y914042D03*
X1694841Y924081D03*
Y930774D03*
X1702283Y920735D03*
Y927428D03*
X1694841Y940814D03*
Y947507D03*
X1702283Y937467D03*
Y944160D03*
X1694841Y954200D03*
Y964239D03*
X1702283Y950853D03*
Y960892D03*
X1694841Y970932D03*
Y977625D03*
X1702283Y967585D03*
Y974278D03*
Y980971D03*
X1694841Y984318D03*
Y991011D03*
X1702283Y987664D03*
X1694841Y1017782D03*
Y1024475D03*
Y1031168D03*
X1702283Y1017782D03*
Y1027822D03*
X1694841Y1037861D03*
Y1044554D03*
X1702283Y1034515D03*
Y1041207D03*
Y1047900D03*
X1694841Y1051247D03*
Y1057940D03*
X1702283Y1054593D03*
Y1061286D03*
X1694841Y1064633D03*
Y1071326D03*
Y1078018D03*
X1702283Y1067979D03*
Y1074672D03*
X1694841Y1088058D03*
Y1094751D03*
X1702283Y1084711D03*
Y1091404D03*
X1694841Y1101444D03*
Y1108137D03*
X1702283Y1098097D03*
Y1104790D03*
Y1111483D03*
X1694841Y1114829D03*
Y1124869D03*
X1702283Y1121522D03*
Y1128215D03*
X1694841Y1131562D03*
Y1138255D03*
Y1144948D03*
X1702283Y1134908D03*
Y1141601D03*
X1694841Y1151641D03*
Y1161680D03*
X1702283Y1148294D03*
Y1158333D03*
X1694841Y1168373D03*
Y1175066D03*
X1702283Y1165026D03*
Y1171719D03*
X1694841Y1181759D03*
Y1188452D03*
X1702283Y1178412D03*
Y1185105D03*
X1694841Y1198491D03*
Y1205184D03*
X1702283Y1195144D03*
Y1201837D03*
Y1208530D03*
X1694841Y1211877D03*
Y1218570D03*
Y1225263D03*
X1702283Y1215223D03*
Y1221916D03*
X1694841Y1235302D03*
Y1241995D03*
X1702283Y1231955D03*
Y1238648D03*
X1694841Y1248688D03*
X1695188Y1257064D03*
X1702283Y1245341D03*
X1691988Y1273344D03*
X1705188D03*
X1710983Y766798D03*
X1715841Y770144D03*
X1710983Y773491D03*
Y780184D03*
X1715841Y783530D03*
Y776837D03*
X1710983Y790223D03*
Y796916D03*
Y803609D03*
X1715841Y793570D03*
Y800263D03*
X1710983Y810302D03*
Y816995D03*
X1715841Y806955D03*
Y813648D03*
Y820341D03*
X1710983Y827034D03*
Y833727D03*
X1715841Y830381D03*
X1710983Y840420D03*
Y847113D03*
X1715841Y837074D03*
Y843766D03*
Y850459D03*
X1710983Y853806D03*
Y863845D03*
X1715841Y857152D03*
Y867192D03*
X1710983Y870538D03*
Y877231D03*
Y883924D03*
X1715841Y873885D03*
Y880577D03*
X1710983Y890617D03*
Y900656D03*
X1715841Y893963D03*
Y887270D03*
X1710983Y907349D03*
Y914042D03*
X1715841Y904003D03*
Y910696D03*
Y917389D03*
X1710983Y920735D03*
Y927428D03*
X1715841Y924081D03*
Y930774D03*
X1710983Y937467D03*
Y944160D03*
X1715841Y940814D03*
Y947507D03*
X1710983Y950853D03*
Y960892D03*
X1715841Y954200D03*
Y964239D03*
X1710983Y967585D03*
Y974278D03*
Y980971D03*
X1715841Y970932D03*
Y977625D03*
X1710983Y987664D03*
X1715841Y984318D03*
Y991011D03*
X1710983Y1017782D03*
Y1027822D03*
X1715841Y1017782D03*
Y1024475D03*
Y1031168D03*
X1710983Y1034515D03*
Y1041207D03*
Y1047900D03*
X1715841Y1037861D03*
Y1044554D03*
X1710983Y1054593D03*
Y1061286D03*
X1715841Y1051247D03*
Y1057940D03*
X1710983Y1067979D03*
Y1074672D03*
X1715841Y1071326D03*
Y1064633D03*
Y1078018D03*
X1710983Y1084711D03*
Y1091404D03*
X1715841Y1088058D03*
Y1094751D03*
X1710983Y1098097D03*
Y1104790D03*
Y1111483D03*
X1715841Y1101444D03*
Y1108137D03*
X1710983Y1121522D03*
Y1128215D03*
X1715841Y1114829D03*
Y1124869D03*
X1710983Y1134908D03*
Y1141601D03*
X1715841Y1131562D03*
Y1138255D03*
Y1144948D03*
X1710983Y1148294D03*
Y1158333D03*
X1715841Y1151641D03*
Y1161680D03*
X1710983Y1165026D03*
Y1171719D03*
X1715841Y1168373D03*
Y1175066D03*
X1710983Y1178412D03*
Y1185105D03*
X1715841Y1181759D03*
Y1188452D03*
X1710983Y1195144D03*
Y1201837D03*
Y1208530D03*
X1715841Y1198491D03*
Y1205184D03*
X1710983Y1215223D03*
Y1221916D03*
X1715841Y1211877D03*
Y1218570D03*
Y1225263D03*
X1710983Y1231955D03*
Y1238648D03*
X1715841Y1235302D03*
Y1241995D03*
X1710983Y1245341D03*
X1715841Y1248688D03*
X1707514Y1273444D03*
X1718888Y1273344D03*
X1721688D03*
X1731983Y766798D03*
X1724541Y770144D03*
X1731983Y773491D03*
Y780184D03*
X1724541Y783530D03*
Y776837D03*
Y793570D03*
Y800263D03*
X1731983Y790223D03*
Y796916D03*
Y803609D03*
X1724541Y806955D03*
Y813648D03*
Y820341D03*
X1731983Y810302D03*
Y816995D03*
X1724541Y830381D03*
X1731983Y827034D03*
Y833727D03*
X1724541Y837074D03*
Y843766D03*
Y850459D03*
X1731983Y840420D03*
Y847113D03*
X1724541Y857152D03*
Y867192D03*
X1731983Y853806D03*
Y863845D03*
X1724541Y873885D03*
Y880577D03*
X1731983Y870538D03*
Y877231D03*
Y883924D03*
X1724541Y893963D03*
Y887270D03*
X1731983Y890617D03*
Y900656D03*
X1724541Y904003D03*
Y910696D03*
Y917389D03*
X1731983Y907349D03*
Y914042D03*
X1724541Y924081D03*
Y930774D03*
X1731983Y920735D03*
Y927428D03*
X1724541Y940814D03*
Y947507D03*
X1731983Y937467D03*
Y944160D03*
X1724541Y954200D03*
Y964239D03*
X1731983Y950853D03*
Y960892D03*
X1724541Y970932D03*
Y977625D03*
X1731983Y967585D03*
Y974278D03*
Y980971D03*
X1724541Y984318D03*
Y991011D03*
X1731983Y987664D03*
X1724541Y1017782D03*
Y1024475D03*
Y1031168D03*
X1731983Y1017782D03*
Y1027822D03*
X1724541Y1037861D03*
Y1044554D03*
X1731983Y1034515D03*
Y1041207D03*
Y1047900D03*
X1724541Y1057940D03*
X1731983Y1054593D03*
Y1061286D03*
X1724541Y1071326D03*
Y1064633D03*
Y1078018D03*
X1731983Y1074672D03*
Y1067979D03*
X1724541Y1088058D03*
Y1094751D03*
X1731983Y1084711D03*
Y1091404D03*
X1724541Y1101444D03*
Y1108137D03*
X1731983Y1098097D03*
Y1104790D03*
Y1111483D03*
X1724541Y1114829D03*
Y1124869D03*
X1731983Y1121522D03*
Y1128215D03*
X1724541Y1131562D03*
Y1138255D03*
Y1144948D03*
X1731983Y1134908D03*
Y1141601D03*
X1724541Y1151641D03*
Y1161680D03*
X1731983Y1148294D03*
Y1158333D03*
X1724541Y1168373D03*
Y1175066D03*
X1731983Y1165026D03*
Y1171719D03*
X1724541Y1181759D03*
Y1188452D03*
X1731983Y1178412D03*
Y1185105D03*
X1724541Y1198491D03*
Y1205184D03*
X1731983Y1195144D03*
Y1201837D03*
Y1208530D03*
X1724541Y1211877D03*
Y1218570D03*
Y1225263D03*
X1731983Y1215223D03*
Y1221916D03*
X1724541Y1235302D03*
Y1241995D03*
X1731983Y1231955D03*
Y1238648D03*
X1724541Y1248688D03*
X1724588Y1257164D03*
X1731983Y1245341D03*
X1734888Y1273344D03*
X1737688D03*
X1740683Y766798D03*
X1745541Y770144D03*
X1754241D03*
X1740683Y773491D03*
Y780184D03*
X1745541Y776837D03*
X1754241D03*
X1745541Y783530D03*
X1754241D03*
X1740683Y790223D03*
Y796916D03*
Y803609D03*
X1745541Y793570D03*
X1754241D03*
X1745541Y800263D03*
X1754241D03*
X1740683Y810302D03*
Y816995D03*
X1745541Y806955D03*
X1754241D03*
X1745541Y813648D03*
X1754241D03*
X1745541Y820341D03*
X1754241D03*
X1740683Y827034D03*
Y833727D03*
X1745541Y830381D03*
X1754241D03*
X1740683Y840420D03*
Y847113D03*
X1754241Y843766D03*
X1745541D03*
Y837074D03*
X1754241D03*
X1745541Y850459D03*
X1754241D03*
X1740683Y853806D03*
Y863845D03*
X1745541Y857152D03*
X1754241D03*
Y867192D03*
X1745541D03*
X1740683Y870538D03*
Y877231D03*
Y883924D03*
X1745541Y873885D03*
X1754241D03*
X1745541Y880577D03*
X1754241D03*
X1740683Y890617D03*
Y900656D03*
X1754241Y893963D03*
X1745541D03*
Y887270D03*
X1754241D03*
X1740683Y907349D03*
Y914042D03*
X1754241Y904003D03*
X1745541D03*
X1754241Y910696D03*
X1745541D03*
X1754241Y917389D03*
X1745541D03*
X1740683Y920735D03*
Y927428D03*
X1754241Y924081D03*
X1745541D03*
X1754241Y930774D03*
X1745541D03*
X1740683Y937467D03*
Y944160D03*
X1754241Y940814D03*
X1745541D03*
X1754241Y947507D03*
X1745541D03*
X1740683Y950853D03*
Y960892D03*
X1754241Y954200D03*
X1745541D03*
X1754241Y964239D03*
X1745541D03*
X1740683Y967585D03*
Y974278D03*
Y980971D03*
X1754241Y970932D03*
X1745541D03*
X1754241Y977625D03*
X1745541D03*
X1740683Y987664D03*
X1754241Y984318D03*
X1745541D03*
X1754241Y991011D03*
X1745541D03*
X1740683Y1017782D03*
Y1027822D03*
X1754241Y1017782D03*
X1745541D03*
Y1024475D03*
X1754241D03*
X1745541Y1031168D03*
X1754241D03*
X1740683Y1034515D03*
Y1041207D03*
Y1047900D03*
X1754241Y1044554D03*
X1745541D03*
Y1037861D03*
X1754241D03*
X1740683Y1054593D03*
Y1061286D03*
X1745541Y1051247D03*
X1754241D03*
X1745541Y1057940D03*
X1754241D03*
X1740683Y1074672D03*
Y1067979D03*
X1754241Y1071326D03*
X1745541D03*
Y1064633D03*
X1754241D03*
Y1078018D03*
X1745541D03*
X1740683Y1084711D03*
Y1091404D03*
X1754241Y1088058D03*
X1745541D03*
X1754241Y1094751D03*
X1745541D03*
X1740683Y1098097D03*
Y1104790D03*
Y1111483D03*
X1754241Y1101444D03*
X1745541D03*
X1754241Y1108137D03*
X1745541D03*
X1740683Y1121522D03*
Y1128215D03*
X1754241Y1114829D03*
X1745541D03*
X1754241Y1124869D03*
X1745541D03*
X1740683Y1134908D03*
Y1141601D03*
X1754241Y1131562D03*
X1745541D03*
X1754241Y1138255D03*
X1745541D03*
X1754241Y1144948D03*
X1745541D03*
X1740683Y1148294D03*
Y1158333D03*
X1754241Y1151641D03*
X1745541D03*
X1754241Y1161680D03*
X1745541D03*
X1740683Y1165026D03*
Y1171719D03*
X1745541Y1175066D03*
X1754241D03*
Y1168373D03*
X1745541D03*
X1740683Y1178412D03*
Y1185105D03*
X1745541Y1181759D03*
X1754241D03*
Y1188452D03*
X1745541D03*
X1740683Y1195144D03*
Y1201837D03*
Y1208530D03*
X1754241Y1198491D03*
X1745541D03*
X1754241Y1205184D03*
X1745541D03*
X1740683Y1215223D03*
Y1221916D03*
X1754241Y1211877D03*
X1745541D03*
X1754241Y1218570D03*
X1745541D03*
X1754241Y1225263D03*
X1745541D03*
X1740683Y1231955D03*
Y1238648D03*
X1754241Y1235302D03*
X1745541D03*
X1754241Y1241995D03*
X1745541D03*
X1740683Y1245341D03*
X1754241Y1248688D03*
X1745541D03*
X1754488Y1257264D03*
X1751388Y1273344D03*
X1748588D03*
X1749088Y1310474D03*
X1746288D03*
X1770383Y766798D03*
X1761683D03*
X1770383Y773491D03*
X1761683D03*
Y780184D03*
X1770383D03*
X1761683Y790223D03*
X1770383D03*
X1761683Y796916D03*
X1770383D03*
X1761683Y803609D03*
X1770383D03*
X1761683Y810302D03*
X1770383D03*
X1761683Y816995D03*
X1770383D03*
X1761683Y827034D03*
X1770383D03*
X1761683Y833727D03*
X1770383D03*
X1761683Y840420D03*
X1770383D03*
X1761683Y847113D03*
X1770383D03*
X1761683Y853806D03*
X1770383D03*
X1761683Y863845D03*
X1770383D03*
X1761683Y870538D03*
X1770383D03*
X1761683Y877231D03*
X1770383D03*
X1761683Y883924D03*
X1770383D03*
X1761683Y890617D03*
X1770383D03*
X1761683Y900656D03*
X1770383D03*
X1761683Y907349D03*
X1770383D03*
X1761683Y914042D03*
X1770383D03*
Y927428D03*
X1761683D03*
Y920735D03*
X1770383D03*
X1761683Y937467D03*
X1770383D03*
X1761683Y944160D03*
X1770383D03*
X1761683Y950853D03*
X1770383D03*
X1761683Y960892D03*
X1770383D03*
X1761683Y967585D03*
X1770383D03*
X1761683Y974278D03*
X1770383D03*
X1761683Y980971D03*
X1770383D03*
X1761683Y987664D03*
X1770383D03*
X1761683Y1017782D03*
X1770383D03*
X1761683Y1027822D03*
X1770383D03*
X1761683Y1034515D03*
X1770383D03*
X1761683Y1041207D03*
X1770383D03*
X1761683Y1047900D03*
X1770383D03*
X1761683Y1054593D03*
X1770383D03*
X1761683Y1061286D03*
X1770383D03*
X1761683Y1067979D03*
X1770383D03*
X1761683Y1074672D03*
X1770383D03*
X1761683Y1084711D03*
X1770383D03*
X1761683Y1091404D03*
X1770383D03*
Y1098097D03*
X1761683D03*
Y1104790D03*
X1770383D03*
X1761683Y1111483D03*
X1770383D03*
X1761683Y1121522D03*
X1770383D03*
X1761683Y1128215D03*
X1770383D03*
X1761683Y1134908D03*
X1770383D03*
X1761683Y1141601D03*
X1770383D03*
X1761683Y1148294D03*
X1770383D03*
X1761683Y1158333D03*
X1770383D03*
X1761683Y1165026D03*
X1770383D03*
X1761683Y1171719D03*
X1770383D03*
X1761683Y1178412D03*
X1770383D03*
X1761683Y1185105D03*
X1770383D03*
X1761683Y1195144D03*
X1770383D03*
X1761683Y1201837D03*
X1770383D03*
X1761683Y1208530D03*
X1770383D03*
X1761683Y1215223D03*
X1770383D03*
X1761683Y1221916D03*
X1770383D03*
X1761683Y1231955D03*
X1770383D03*
X1761683Y1238648D03*
X1770383D03*
X1761683Y1245341D03*
X1770383D03*
X1767388Y1273344D03*
X1764588D03*
X1775241Y770144D03*
X1783941D03*
X1775241Y776837D03*
X1783941D03*
X1775241Y783530D03*
X1783941D03*
X1775241Y793570D03*
X1783941D03*
X1775241Y800263D03*
X1783941D03*
X1775241Y806955D03*
X1783941D03*
X1775241Y813648D03*
X1783941D03*
X1775241Y820341D03*
X1783941D03*
Y830381D03*
X1775241D03*
Y837074D03*
X1783941D03*
X1775241Y843766D03*
X1783941D03*
X1775241Y850459D03*
X1783941D03*
X1775241Y857152D03*
X1783941D03*
X1775241Y867192D03*
X1783941D03*
X1775241Y873885D03*
X1783941D03*
X1775241Y880577D03*
X1783941D03*
X1775241Y887270D03*
X1783941D03*
X1775241Y893963D03*
X1783941D03*
X1775241Y904003D03*
X1783941D03*
X1775241Y910696D03*
X1783941D03*
X1775241Y917389D03*
X1783941D03*
X1775241Y924081D03*
X1783941D03*
X1775241Y930774D03*
X1783941D03*
X1775241Y940814D03*
X1783941D03*
X1775241Y947507D03*
X1783941D03*
X1775241Y954200D03*
X1783941D03*
X1775241Y964239D03*
X1783941D03*
X1775241Y970932D03*
X1783941D03*
X1775241Y977625D03*
X1783941D03*
X1775241Y984318D03*
X1783941D03*
X1775241Y991011D03*
X1783941D03*
X1775241Y1017782D03*
X1783941D03*
X1775241Y1024475D03*
X1783941D03*
X1775241Y1031168D03*
X1783941D03*
X1775241Y1037861D03*
X1783941D03*
X1775241Y1044554D03*
X1783941D03*
X1775241Y1051247D03*
X1783941D03*
X1775241Y1057940D03*
X1783941D03*
X1775241Y1064633D03*
X1783941D03*
X1775241Y1071326D03*
X1783941D03*
X1775241Y1078018D03*
X1783941D03*
X1775241Y1088058D03*
X1783941D03*
X1775241Y1094751D03*
X1783941D03*
X1775241Y1101444D03*
X1783941D03*
X1775241Y1108137D03*
X1783941D03*
X1775241Y1114829D03*
X1783941D03*
X1775241Y1124869D03*
X1783941D03*
X1775241Y1131562D03*
X1783941D03*
X1775241Y1138255D03*
X1783941D03*
X1775241Y1144948D03*
X1783941D03*
Y1151641D03*
X1775241D03*
Y1161680D03*
X1783941D03*
X1775241Y1168373D03*
X1783941D03*
X1775241Y1175066D03*
X1783941D03*
X1775241Y1181759D03*
X1783941D03*
X1775241Y1188452D03*
X1783941D03*
X1775241Y1198491D03*
X1783941D03*
X1775241Y1205184D03*
X1783941D03*
X1775241Y1211877D03*
X1783941D03*
X1775241Y1218570D03*
X1783941D03*
X1775241Y1225263D03*
X1783941D03*
X1775241Y1235302D03*
X1783941D03*
X1775241Y1241995D03*
X1783941D03*
X1784188Y1257664D03*
X1775241Y1248688D03*
X1783941D03*
X1781088Y1273344D03*
X1778288D03*
X1791383Y766798D03*
X1800083D03*
X1791383Y773491D03*
X1800083D03*
X1791383Y780184D03*
X1800083D03*
X1791383Y790223D03*
X1800083D03*
X1791383Y796916D03*
X1800083D03*
X1791383Y803609D03*
X1800083D03*
X1791383Y810302D03*
X1800083D03*
X1791383Y816995D03*
X1800083D03*
X1791383Y827034D03*
X1800083D03*
Y833727D03*
X1791383D03*
Y840420D03*
X1800083D03*
X1791383Y847113D03*
X1800083D03*
X1791383Y853806D03*
X1800083D03*
X1791383Y863845D03*
X1800083D03*
X1791383Y870538D03*
X1800083D03*
X1791383Y877231D03*
X1800083D03*
X1791383Y883924D03*
X1800083D03*
X1791383Y890617D03*
X1800083D03*
X1791383Y900656D03*
X1800083D03*
X1791383Y907349D03*
X1800083D03*
X1791383Y914042D03*
X1800083D03*
X1791383Y920735D03*
X1800083D03*
X1791383Y927428D03*
X1800083D03*
X1791383Y937467D03*
X1800083D03*
X1791383Y944160D03*
X1800083D03*
Y950853D03*
X1791383D03*
Y960892D03*
X1800083D03*
X1791383Y967585D03*
X1800083D03*
X1791383Y974278D03*
X1800083D03*
X1791383Y980971D03*
X1800083D03*
X1791383Y987664D03*
X1800083D03*
X1791383Y1017782D03*
X1800083D03*
X1791383Y1027822D03*
X1800083D03*
X1791383Y1034515D03*
X1800083D03*
X1791383Y1041207D03*
X1800083D03*
X1791383Y1047900D03*
X1800083D03*
X1791383Y1054593D03*
X1800083D03*
X1791383Y1061286D03*
X1800083D03*
X1791383Y1067979D03*
X1800083D03*
X1791383Y1074672D03*
X1800083D03*
X1791383Y1084711D03*
X1800083D03*
X1791383Y1091404D03*
X1800083D03*
X1791383Y1098097D03*
X1800083D03*
X1791383Y1104790D03*
X1800083D03*
X1791383Y1111483D03*
X1800083D03*
X1791383Y1121522D03*
X1800083D03*
X1791383Y1128215D03*
X1800083D03*
Y1134908D03*
X1791383D03*
Y1141601D03*
X1800083D03*
X1791383Y1148294D03*
X1800083D03*
X1791383Y1158333D03*
X1800083D03*
X1791383Y1165026D03*
X1800083D03*
X1791383Y1171719D03*
X1800083D03*
X1791383Y1178412D03*
X1800083D03*
X1791383Y1185105D03*
X1800083D03*
X1791383Y1195144D03*
X1800083D03*
X1791383Y1201837D03*
X1800083D03*
X1791383Y1208530D03*
X1800083D03*
X1791383Y1215223D03*
X1800083D03*
X1791383Y1221916D03*
X1800083D03*
X1791383Y1231955D03*
X1800083D03*
X1791383Y1238648D03*
X1800083D03*
X1791383Y1245341D03*
X1800083D03*
X1797088Y1273344D03*
X1794288D03*
X1804941Y770144D03*
X1813641D03*
X1804941Y776837D03*
X1813641D03*
X1804941Y783530D03*
X1813641D03*
X1804941Y793570D03*
X1813641D03*
X1804941Y800263D03*
X1813641D03*
X1804941Y806955D03*
X1813641D03*
X1804941Y813648D03*
X1813641D03*
X1804941Y820341D03*
X1813641D03*
X1804941Y830381D03*
X1813641D03*
X1804941Y843766D03*
X1813641D03*
X1804941Y837074D03*
X1813641D03*
X1804941Y850459D03*
X1813641D03*
X1804941Y857152D03*
X1813641D03*
Y867192D03*
X1804941D03*
Y873885D03*
X1813641D03*
X1804941Y880577D03*
X1813641D03*
X1804941Y887270D03*
X1813641D03*
X1804941Y893963D03*
X1813641D03*
X1804941Y904003D03*
X1813641D03*
X1804941Y910696D03*
X1813641D03*
X1804941Y917389D03*
X1813641D03*
X1804941Y924081D03*
X1813641D03*
X1804941Y930774D03*
X1813641D03*
X1804941Y940814D03*
X1813641D03*
X1804941Y947507D03*
X1813641D03*
X1804941Y954200D03*
X1813641D03*
X1804941Y964239D03*
X1813641D03*
X1804941Y970932D03*
X1813641D03*
X1804941Y977625D03*
X1813641D03*
X1804941Y984318D03*
X1813641D03*
X1804941Y991011D03*
X1813641D03*
X1804941Y1017782D03*
X1813641D03*
X1804941Y1024475D03*
X1813641D03*
X1804941Y1031168D03*
X1813641D03*
X1804941Y1037861D03*
X1813641D03*
X1804941Y1044554D03*
X1813641D03*
Y1057940D03*
X1804941D03*
Y1051247D03*
X1813641D03*
X1804941Y1064633D03*
X1813641D03*
Y1071326D03*
X1804941D03*
X1813641Y1078018D03*
X1804941D03*
X1813641Y1088058D03*
X1804941D03*
X1813641Y1094751D03*
X1804941D03*
X1813641Y1101444D03*
X1804941D03*
X1813641Y1108137D03*
X1804941D03*
X1813641Y1114829D03*
X1804941D03*
X1813641Y1124869D03*
X1804941D03*
X1813641Y1131562D03*
X1804941D03*
X1813641Y1138255D03*
X1804941D03*
X1813641Y1144948D03*
X1804941D03*
X1813641Y1151641D03*
X1804941D03*
X1813641Y1161680D03*
X1804941D03*
X1813641Y1168373D03*
X1804941D03*
X1813641Y1175066D03*
X1804941D03*
X1813641Y1181759D03*
X1804941D03*
X1813641Y1188452D03*
X1804941D03*
X1813641Y1198491D03*
X1804941D03*
X1813641Y1205184D03*
X1804941D03*
X1813641Y1211877D03*
X1804941D03*
X1813641Y1218570D03*
X1804941D03*
X1813641Y1225263D03*
X1804941D03*
X1813641Y1235302D03*
X1804941D03*
X1813641Y1241995D03*
X1804941D03*
X1813641Y1248688D03*
X1804941D03*
X1819054Y1253986D03*
X1818188Y1273044D03*
X1810788Y1273344D03*
X1807988D03*
X1815388Y1273044D03*
X1829783Y766798D03*
X1821083D03*
X1829783Y773491D03*
X1821083D03*
X1829783Y780184D03*
X1821083D03*
X1829783Y790223D03*
X1821083D03*
X1829783Y796916D03*
X1821083D03*
X1829783Y803609D03*
X1821083D03*
X1829783Y810302D03*
X1821083D03*
X1829783Y816995D03*
X1821083D03*
X1829783Y827034D03*
X1821083D03*
X1829783Y833727D03*
X1821083D03*
Y847113D03*
X1829783D03*
Y840420D03*
X1821083D03*
X1829783Y853806D03*
X1821083D03*
X1829783Y863845D03*
X1821083D03*
X1829783Y870538D03*
X1821083D03*
X1829783Y877231D03*
X1821083D03*
X1829783Y883924D03*
X1821083D03*
X1829783Y890617D03*
X1821083D03*
X1829783Y900656D03*
X1821083D03*
X1829783Y907349D03*
X1821083D03*
X1829783Y914042D03*
X1821083D03*
X1829783Y920735D03*
X1821083D03*
X1829783Y927428D03*
X1821083D03*
X1829783Y937467D03*
X1821083D03*
X1829783Y944160D03*
X1821083D03*
X1829783Y950853D03*
X1821083D03*
X1829783Y960892D03*
X1821083D03*
X1829783Y967585D03*
X1821083D03*
X1829783Y974278D03*
X1821083D03*
X1829783Y980971D03*
X1821083D03*
X1829783Y987664D03*
X1821083D03*
X1829783Y1017782D03*
X1821083D03*
X1829783Y1027822D03*
X1821083D03*
X1829783Y1034515D03*
X1821083D03*
X1829783Y1041207D03*
X1821083D03*
X1829783Y1047900D03*
X1821083D03*
X1829783Y1054593D03*
X1821083D03*
X1829783Y1061286D03*
X1821083D03*
X1829783Y1067979D03*
X1821083D03*
Y1074672D03*
X1829783D03*
X1821083Y1084711D03*
X1829783D03*
X1821083Y1091404D03*
X1829783D03*
X1821083Y1098097D03*
X1829783D03*
X1821083Y1104790D03*
X1829783D03*
X1821083Y1111483D03*
X1829783D03*
X1821083Y1121522D03*
X1829783D03*
X1821083Y1128215D03*
X1829783D03*
X1821083Y1134908D03*
X1829783D03*
X1821083Y1141601D03*
X1829783D03*
X1821083Y1148294D03*
X1829783D03*
X1821083Y1158333D03*
X1829783D03*
X1821083Y1165026D03*
X1829783D03*
X1821083Y1171719D03*
X1829783D03*
X1821083Y1178412D03*
X1829783D03*
X1821083Y1185105D03*
X1829783D03*
X1821083Y1195144D03*
X1829783D03*
X1821083Y1201837D03*
X1829783D03*
X1821083Y1208530D03*
X1829783D03*
X1821083Y1215223D03*
X1829783D03*
X1821083Y1221916D03*
X1829783D03*
X1821083Y1231955D03*
X1829783D03*
X1821083Y1238648D03*
X1829783D03*
Y1245341D03*
X1821083D03*
G54D58*
X841240Y1420330D03*
X1016240D03*
G54D64*
X986642Y-27947D03*
X986627Y-25432D03*
Y-21558D03*
X986642Y-17918D03*
X986627Y-15403D03*
Y-11529D03*
X986642Y-7889D03*
X986627Y-5374D03*
Y4655D03*
X986642Y2140D03*
X986627Y14684D03*
X986642Y12169D03*
X986627Y8529D03*
X986642Y22698D03*
X989910Y22684D03*
X986627Y19058D03*
Y25213D03*
X989895Y25199D03*
X1296019Y-35472D03*
Y-31598D03*
X1296034Y-37987D03*
Y-27958D03*
X1296019Y-25443D03*
Y-21569D03*
X1296034Y-17929D03*
X1296019Y-15414D03*
Y-11540D03*
X1296034Y-7900D03*
X1296019Y-5385D03*
Y4644D03*
X1296034Y2129D03*
X1296019Y-1511D03*
Y14673D03*
X1296034Y12158D03*
X1296019Y8518D03*
X1296034Y22687D03*
X1296019Y19047D03*
Y25202D03*
X1299302Y22673D03*
X1299287Y25188D03*
X1488393Y-27958D03*
X1488378Y-25443D03*
X1488393Y-37987D03*
X1488378Y-35472D03*
Y-31598D03*
X1488393Y-17929D03*
X1488378Y-15414D03*
Y-11540D03*
Y-21569D03*
X1488393Y2129D03*
X1488378Y4644D03*
X1488393Y-7900D03*
X1488378Y-5385D03*
Y-1511D03*
Y14673D03*
X1488393Y12158D03*
Y22687D03*
X1491661Y22673D03*
X1488378Y8518D03*
Y19047D03*
Y25202D03*
X1491646Y25188D03*
G54D72*
X1879155Y344948D03*
Y592848D03*
X1900275Y-19342D03*
X1889155Y344948D03*
Y592848D03*
X1900275Y716808D03*
X1910275Y-19342D03*
Y716808D03*
X1931395Y592868D03*
X1921395D03*
X1952395Y-19152D03*
X1942395D03*
X1963362Y593010D03*
X1984482Y-19180D03*
X1973362Y593010D03*
X1994482Y-19180D03*
X2015452Y593020D03*
X2005452D03*
X2026452Y-19000D03*
X2036452D03*
X2047419Y593162D03*
X2057419D03*
G54D25*
X57646Y12480D03*
X137272D03*
X186622D03*
X266858D03*
X315598D03*
X502528Y33268D03*
X582154D03*
X631504D03*
X711740D03*
X760480D03*
X1532055Y12480D03*
X1611681D03*
X1661031D03*
X1741267D03*
X1790007D03*
G54D65*
X1077638Y133866D03*
G54D47*
X460000Y278543D03*
G54D70*
X1771457Y1634646D03*
G54D59*
X900196Y175197D03*
X944684Y155216D03*
G54D79*
X1903086Y1318228D03*
X1902402Y1683256D03*
X1950484Y1683497D03*
X1993147Y1682875D03*
G54D77*
X1880836Y1317164D03*
X1881165Y1682207D03*
X1929695Y1683220D03*
X1971555Y1683130D03*
%LPC*%
G75*
G54D80*
G01X-6350Y-464479D02*
Y-539479D01*
X493650D01*
Y-464479D01*
X-6350D01*
G01X5650Y-529479D02*
Y-534479D01*
G01X4193Y-529479D02*
X7107D01*
G01X12017Y-534479D02*
X9483D01*
Y-529479D01*
X12017D01*
G01X11003Y-531896D02*
X9483D01*
G01X14583Y-529479D02*
Y-534479D01*
X17117D01*
G01X20950Y-534646D02*
X20823Y-534562D01*
Y-534396D01*
X20950Y-534312D01*
X21077Y-534396D01*
Y-534562D01*
X20950Y-534646D01*
G01Y-532396D02*
X20823Y-532312D01*
Y-532146D01*
X20950Y-532062D01*
X21077Y-532146D01*
Y-532312D01*
X20950Y-532396D01*
G01X25733Y-536146D02*
X25100Y-535312D01*
X24783Y-534479D01*
Y-531146D01*
X25100Y-530312D01*
X25733Y-529479D01*
G01X31150D02*
X30643Y-529646D01*
X30263Y-530062D01*
X30010Y-530562D01*
X29820Y-531229D01*
X29757Y-531979D01*
X29820Y-532729D01*
X30010Y-533396D01*
X30263Y-533896D01*
X30643Y-534312D01*
X31150Y-534479D01*
X31657Y-534312D01*
X32037Y-533896D01*
X32290Y-533396D01*
X32480Y-532729D01*
X32543Y-531979D01*
X32480Y-531229D01*
X32290Y-530562D01*
X32037Y-530062D01*
X31657Y-529646D01*
X31150Y-529479D01*
G01X34857Y-533479D02*
X35237Y-534062D01*
X35743Y-534396D01*
X36313Y-534479D01*
X36820Y-534396D01*
X37327Y-533979D01*
X37643Y-533479D01*
X37707Y-532979D01*
X37580Y-532396D01*
X37137Y-531979D01*
X36693Y-531812D01*
X36123D01*
G01X36693D02*
X37073Y-531562D01*
X37390Y-531146D01*
X37517Y-530646D01*
X37390Y-530146D01*
X37073Y-529729D01*
X36503Y-529479D01*
X35933Y-529562D01*
X35363Y-529896D01*
G01X41667Y-536146D02*
X42300Y-535312D01*
X42617Y-534479D01*
Y-531146D01*
X42300Y-530312D01*
X41667Y-529479D01*
G01X45057Y-533479D02*
X45437Y-534062D01*
X45943Y-534396D01*
X46513Y-534479D01*
X47020Y-534396D01*
X47527Y-533979D01*
X47843Y-533479D01*
X47907Y-532979D01*
X47780Y-532396D01*
X47337Y-531979D01*
X46893Y-531812D01*
X46323D01*
G01X46893D02*
X47273Y-531562D01*
X47590Y-531146D01*
X47717Y-530646D01*
X47590Y-530146D01*
X47273Y-529729D01*
X46703Y-529479D01*
X46133Y-529562D01*
X45563Y-529896D01*
G01X50347Y-530312D02*
X50727Y-529812D01*
X51170Y-529562D01*
X51677Y-529479D01*
X52310Y-529646D01*
X52753Y-530062D01*
X52880Y-530562D01*
X52817Y-531062D01*
X52563Y-531479D01*
X51297Y-532312D01*
X50727Y-532896D01*
X50347Y-533729D01*
X50220Y-534479D01*
X52880D01*
G01X56523D02*
X56650Y-533396D01*
X56840Y-532479D01*
X57093Y-531646D01*
X57410Y-530729D01*
X57917Y-529479D01*
X55383D01*
G01X60927Y-532812D02*
X62573D01*
G01X65647Y-530312D02*
X66027Y-529812D01*
X66470Y-529562D01*
X66977Y-529479D01*
X67610Y-529646D01*
X68053Y-530062D01*
X68180Y-530562D01*
X68117Y-531062D01*
X67863Y-531479D01*
X66597Y-532312D01*
X66027Y-532896D01*
X65647Y-533729D01*
X65520Y-534479D01*
X68180D01*
G01X70557Y-533479D02*
X70937Y-534062D01*
X71443Y-534396D01*
X72013Y-534479D01*
X72520Y-534396D01*
X73027Y-533979D01*
X73343Y-533479D01*
X73407Y-532979D01*
X73280Y-532396D01*
X72837Y-531979D01*
X72393Y-531812D01*
X71823D01*
G01X72393D02*
X72773Y-531562D01*
X73090Y-531146D01*
X73217Y-530646D01*
X73090Y-530146D01*
X72773Y-529729D01*
X72203Y-529479D01*
X71633Y-529562D01*
X71063Y-529896D01*
G01X77810Y-534479D02*
Y-529479D01*
X75467Y-533062D01*
X78633D01*
G01X80757Y-533729D02*
X81137Y-534146D01*
X81580Y-534396D01*
X82150Y-534479D01*
X82720Y-534312D01*
X83163Y-533979D01*
X83480Y-533396D01*
X83543Y-532729D01*
X83417Y-532062D01*
X83100Y-531646D01*
X82657Y-531312D01*
X82213Y-531229D01*
X81770Y-531312D01*
X81200Y-531646D01*
X81390Y-529479D01*
X83100D01*
G01X91147Y-534479D02*
Y-529479D01*
X93553D01*
G01X92667Y-531896D02*
X91147D01*
G01X95867Y-534479D02*
X97450Y-529479D01*
X99033Y-534479D01*
G01X98463Y-532729D02*
X96437D01*
G01X101220Y-534479D02*
X103880Y-529479D01*
G01X101220D02*
X103880Y-534479D01*
G01X107650Y-534646D02*
X107523Y-534562D01*
Y-534396D01*
X107650Y-534312D01*
X107777Y-534396D01*
Y-534562D01*
X107650Y-534646D01*
G01Y-532396D02*
X107523Y-532312D01*
Y-532146D01*
X107650Y-532062D01*
X107777Y-532146D01*
Y-532312D01*
X107650Y-532396D01*
G01X112433Y-536146D02*
X111800Y-535312D01*
X111483Y-534479D01*
Y-531146D01*
X111800Y-530312D01*
X112433Y-529479D01*
G01X117850D02*
X117343Y-529646D01*
X116963Y-530062D01*
X116710Y-530562D01*
X116520Y-531229D01*
X116457Y-531979D01*
X116520Y-532729D01*
X116710Y-533396D01*
X116963Y-533896D01*
X117343Y-534312D01*
X117850Y-534479D01*
X118357Y-534312D01*
X118737Y-533896D01*
X118990Y-533396D01*
X119180Y-532729D01*
X119243Y-531979D01*
X119180Y-531229D01*
X118990Y-530562D01*
X118737Y-530062D01*
X118357Y-529646D01*
X117850Y-529479D01*
G01X121557Y-533479D02*
X121937Y-534062D01*
X122443Y-534396D01*
X123013Y-534479D01*
X123520Y-534396D01*
X124027Y-533979D01*
X124343Y-533479D01*
X124407Y-532979D01*
X124280Y-532396D01*
X123837Y-531979D01*
X123393Y-531812D01*
X122823D01*
G01X123393D02*
X123773Y-531562D01*
X124090Y-531146D01*
X124217Y-530646D01*
X124090Y-530146D01*
X123773Y-529729D01*
X123203Y-529479D01*
X122633Y-529562D01*
X122063Y-529896D01*
G01X128367Y-536146D02*
X129000Y-535312D01*
X129317Y-534479D01*
Y-531146D01*
X129000Y-530312D01*
X128367Y-529479D01*
G01X131757Y-533479D02*
X132137Y-534062D01*
X132643Y-534396D01*
X133213Y-534479D01*
X133720Y-534396D01*
X134227Y-533979D01*
X134543Y-533479D01*
X134607Y-532979D01*
X134480Y-532396D01*
X134037Y-531979D01*
X133593Y-531812D01*
X133023D01*
G01X133593D02*
X133973Y-531562D01*
X134290Y-531146D01*
X134417Y-530646D01*
X134290Y-530146D01*
X133973Y-529729D01*
X133403Y-529479D01*
X132833Y-529562D01*
X132263Y-529896D01*
G01X137173Y-533896D02*
X137617Y-534312D01*
X138123Y-534479D01*
X138630Y-534312D01*
X139073Y-533812D01*
X139390Y-533062D01*
X139517Y-532312D01*
Y-531396D01*
X139390Y-530646D01*
X139073Y-529979D01*
X138693Y-529646D01*
X138250Y-529479D01*
X137743Y-529646D01*
X137363Y-529979D01*
X137110Y-530479D01*
X136983Y-531146D01*
X137110Y-531729D01*
X137427Y-532312D01*
X137807Y-532646D01*
X138250Y-532729D01*
X138757Y-532562D01*
X139137Y-532146D01*
X139517Y-531396D01*
G01X143223Y-534479D02*
X143350Y-533396D01*
X143540Y-532479D01*
X143793Y-531646D01*
X144110Y-530729D01*
X144617Y-529479D01*
X142083D01*
G01X147627Y-532812D02*
X149273D01*
G01X152157Y-533479D02*
X152537Y-534062D01*
X153043Y-534396D01*
X153613Y-534479D01*
X154120Y-534396D01*
X154627Y-533979D01*
X154943Y-533479D01*
X155007Y-532979D01*
X154880Y-532396D01*
X154437Y-531979D01*
X153993Y-531812D01*
X153423D01*
G01X153993D02*
X154373Y-531562D01*
X154690Y-531146D01*
X154817Y-530646D01*
X154690Y-530146D01*
X154373Y-529729D01*
X153803Y-529479D01*
X153233Y-529562D01*
X152663Y-529896D01*
G01X157447Y-532396D02*
X157890Y-531812D01*
X158270Y-531479D01*
X158777Y-531312D01*
X159220Y-531479D01*
X159537Y-531812D01*
X159790Y-532312D01*
X159853Y-532896D01*
X159790Y-533396D01*
X159537Y-533896D01*
X159157Y-534312D01*
X158713Y-534479D01*
X158207Y-534312D01*
X157763Y-533812D01*
X157510Y-533062D01*
X157447Y-532229D01*
X157573Y-531146D01*
X157763Y-530562D01*
X158080Y-529979D01*
X158523Y-529562D01*
X158967Y-529479D01*
X159410Y-529646D01*
X159727Y-530062D01*
G01X163750Y-534479D02*
Y-529479D01*
X162990Y-530479D01*
G01Y-534479D02*
X164510D01*
G01X169610D02*
Y-529479D01*
X167267Y-533062D01*
X170433D01*
G01X188650Y-464479D02*
Y-539479D01*
G01Y-514479D02*
X291650D01*
Y-489479D01*
G01X188650D02*
X291650D01*
G01Y-464479D02*
Y-539479D01*
G01X293650Y-464479D02*
Y-539479D01*
G01X299157Y-524479D02*
Y-519479D01*
X300423D01*
X300930Y-519729D01*
X301310Y-520062D01*
X301627Y-520562D01*
X301880Y-521146D01*
X301943Y-521979D01*
X301880Y-522812D01*
X301627Y-523396D01*
X301310Y-523896D01*
X300930Y-524229D01*
X300423Y-524479D01*
X299157D01*
G01X304067D02*
X305650Y-519479D01*
X307233Y-524479D01*
G01X306663Y-522729D02*
X304637D01*
G01X310750Y-519479D02*
Y-524479D01*
G01X309293Y-519479D02*
X312207D01*
G01X317117Y-524479D02*
X314583D01*
Y-519479D01*
X317117D01*
G01X316103Y-521896D02*
X314583D01*
G01X320950Y-524646D02*
X320823Y-524562D01*
Y-524396D01*
X320950Y-524312D01*
X321077Y-524396D01*
Y-524562D01*
X320950Y-524646D01*
G01Y-522396D02*
X320823Y-522312D01*
Y-522146D01*
X320950Y-522062D01*
X321077Y-522146D01*
Y-522312D01*
X320950Y-522396D01*
G01X299283Y-499479D02*
Y-494479D01*
X300803D01*
X301310Y-494729D01*
X301690Y-495312D01*
X301817Y-495979D01*
X301690Y-496646D01*
X301373Y-497146D01*
X300803Y-497396D01*
X299283D01*
G01X304510Y-499646D02*
X306790Y-494479D01*
G01X309293Y-499479D02*
Y-494479D01*
X312207Y-499479D01*
Y-494479D01*
G01X315850Y-499646D02*
X315723Y-499562D01*
Y-499396D01*
X315850Y-499312D01*
X315977Y-499396D01*
Y-499562D01*
X315850Y-499646D01*
G01Y-497396D02*
X315723Y-497312D01*
Y-497146D01*
X315850Y-497062D01*
X315977Y-497146D01*
Y-497312D01*
X315850Y-497396D01*
G01X293650Y-514479D02*
X493650D01*
G01X293650Y-489479D02*
X493650D01*
G01X299283Y-474479D02*
Y-469479D01*
X300803D01*
X301310Y-469729D01*
X301690Y-470312D01*
X301817Y-470979D01*
X301690Y-471646D01*
X301373Y-472146D01*
X300803Y-472396D01*
X299283D01*
G01X304383Y-474479D02*
Y-469479D01*
X305967D01*
X306473Y-469729D01*
X306790Y-470062D01*
X306917Y-470729D01*
X306790Y-471396D01*
X306410Y-471812D01*
X305967Y-472062D01*
X304383D01*
G01X305967D02*
X306917Y-474479D01*
G01X310750D02*
X310243Y-474396D01*
X309800Y-474062D01*
X309420Y-473562D01*
X309167Y-472979D01*
X309040Y-472312D01*
Y-471646D01*
X309167Y-470979D01*
X309420Y-470396D01*
X309800Y-469896D01*
X310243Y-469562D01*
X310750Y-469479D01*
X311257Y-469562D01*
X311700Y-469896D01*
X312080Y-470396D01*
X312333Y-470979D01*
X312460Y-471646D01*
Y-472312D01*
X312333Y-472979D01*
X312080Y-473562D01*
X311700Y-474062D01*
X311257Y-474396D01*
X310750Y-474479D01*
G01X314583Y-473479D02*
X314900Y-473979D01*
X315280Y-474312D01*
X315723Y-474479D01*
X316230Y-474312D01*
X316610Y-473979D01*
X316990Y-473479D01*
X317117Y-472812D01*
Y-469479D01*
G01X322217Y-474479D02*
X319683D01*
Y-469479D01*
X322217D01*
G01X321203Y-471896D02*
X319683D01*
G01X327443Y-469896D02*
X327063Y-469646D01*
X326620Y-469479D01*
X326113D01*
X325543Y-469729D01*
X325100Y-470146D01*
X324783Y-470646D01*
X324530Y-471479D01*
X324467Y-472229D01*
X324593Y-472979D01*
X324783Y-473479D01*
X325163Y-473979D01*
X325607Y-474312D01*
X326050Y-474479D01*
X326493D01*
X326937Y-474312D01*
X327317Y-474062D01*
X327633Y-473729D01*
G01X331150Y-469479D02*
Y-474479D01*
G01X329693Y-469479D02*
X332607D01*
G01X336250Y-474646D02*
X336123Y-474562D01*
Y-474396D01*
X336250Y-474312D01*
X336377Y-474396D01*
Y-474562D01*
X336250Y-474646D01*
G01Y-472396D02*
X336123Y-472312D01*
Y-472146D01*
X336250Y-472062D01*
X336377Y-472146D01*
Y-472312D01*
X336250Y-472396D01*
G01X408650Y-514479D02*
Y-539479D01*
G01X411283Y-516979D02*
Y-521979D01*
X413817D01*
G01X416890Y-516979D02*
X418410D01*
G01X417650D02*
Y-521979D01*
G01X416890D02*
X418410D01*
G01X423257Y-519312D02*
X423510Y-519062D01*
X423700Y-518646D01*
X423827Y-518062D01*
X423700Y-517562D01*
X423447Y-517229D01*
X423003Y-516979D01*
X421293D01*
Y-521979D01*
X423383D01*
X423827Y-521646D01*
X424080Y-521146D01*
X424207Y-520562D01*
X424080Y-519979D01*
X423700Y-519479D01*
X423257Y-519312D01*
X421293D01*
G01X427850Y-522146D02*
X427723Y-522062D01*
Y-521896D01*
X427850Y-521812D01*
X427977Y-521896D01*
Y-522062D01*
X427850Y-522146D01*
G01Y-519896D02*
X427723Y-519812D01*
Y-519646D01*
X427850Y-519562D01*
X427977Y-519646D01*
Y-519812D01*
X427850Y-519896D01*
G01X451650Y-514479D02*
Y-539479D01*
G01Y-489479D02*
Y-514479D01*
G01X456663Y-541646D02*
X456770Y-541521D01*
X456850Y-541312D01*
X456903Y-541021D01*
X456850Y-540771D01*
X456743Y-540604D01*
X456557Y-540479D01*
X455837D01*
Y-542979D01*
X456717D01*
X456903Y-542812D01*
X457010Y-542562D01*
X457063Y-542271D01*
X457010Y-541979D01*
X456850Y-541729D01*
X456663Y-541646D01*
X455837D01*
G01X459130Y-542979D02*
Y-541312D01*
G01Y-541604D02*
X459023Y-541437D01*
X458863Y-541354D01*
X458677Y-541312D01*
X458490Y-541396D01*
X458330Y-541562D01*
X458223Y-541812D01*
X458170Y-542146D01*
X458223Y-542479D01*
X458330Y-542729D01*
X458490Y-542896D01*
X458677Y-542979D01*
X458863Y-542937D01*
X459023Y-542812D01*
X459130Y-542646D01*
G01X460450Y-542687D02*
X460583Y-542854D01*
X460770Y-542979D01*
X460930D01*
X461090Y-542896D01*
X461197Y-542771D01*
X461250Y-542604D01*
X461223Y-542354D01*
X461117Y-542229D01*
X460637Y-541979D01*
X460530Y-541687D01*
X460583Y-541479D01*
X460690Y-541354D01*
X460850Y-541312D01*
X461010Y-541354D01*
X461170Y-541479D01*
G01X462650Y-541854D02*
X463503D01*
X463423Y-541562D01*
X463290Y-541396D01*
X463103Y-541312D01*
X462917Y-541354D01*
X462757Y-541479D01*
X462650Y-541771D01*
X462597Y-542021D01*
Y-542271D01*
X462650Y-542521D01*
X462783Y-542771D01*
X462943Y-542937D01*
X463130Y-542979D01*
X463317Y-542896D01*
X463503Y-542646D01*
G01X464770Y-542979D02*
Y-540479D01*
G01Y-541729D02*
X464903Y-541479D01*
X465063Y-541354D01*
X465223Y-541312D01*
X465463Y-541396D01*
X465623Y-541562D01*
X465730Y-541854D01*
Y-542187D01*
X465677Y-542521D01*
X465570Y-542771D01*
X465383Y-542937D01*
X465223Y-542979D01*
X465063Y-542937D01*
X464903Y-542812D01*
X464770Y-542604D01*
G01X467450Y-542979D02*
X467290Y-542937D01*
X467130Y-542771D01*
X467023Y-542479D01*
X466970Y-542146D01*
X467023Y-541812D01*
X467130Y-541521D01*
X467290Y-541354D01*
X467450Y-541312D01*
X467610Y-541354D01*
X467770Y-541521D01*
X467877Y-541812D01*
X467903Y-542146D01*
X467877Y-542479D01*
X467770Y-542771D01*
X467610Y-542937D01*
X467450Y-542979D01*
G01X470130D02*
Y-541312D01*
G01Y-541604D02*
X470023Y-541437D01*
X469863Y-541354D01*
X469677Y-541312D01*
X469490Y-541396D01*
X469330Y-541562D01*
X469223Y-541812D01*
X469170Y-542146D01*
X469223Y-542479D01*
X469330Y-542729D01*
X469490Y-542896D01*
X469677Y-542979D01*
X469863Y-542937D01*
X470023Y-542812D01*
X470130Y-542646D01*
G01X471477Y-542979D02*
Y-541312D01*
G01Y-541646D02*
X471610Y-541479D01*
X471743Y-541354D01*
X471930Y-541312D01*
X472063Y-541354D01*
X472223Y-541479D01*
G01X474530Y-540479D02*
Y-542979D01*
G01Y-542604D02*
X474423Y-542812D01*
X474263Y-542937D01*
X474077Y-542979D01*
X473863Y-542896D01*
X473703Y-542687D01*
X473597Y-542437D01*
X473570Y-542146D01*
X473597Y-541854D01*
X473703Y-541604D01*
X473863Y-541396D01*
X474077Y-541312D01*
X474263Y-541354D01*
X474397Y-541437D01*
X474530Y-541604D01*
G01X477917Y-542979D02*
Y-540479D01*
X478583D01*
X478797Y-540604D01*
X478930Y-540771D01*
X478983Y-541104D01*
X478930Y-541437D01*
X478770Y-541646D01*
X478583Y-541771D01*
X477917D01*
G01X478583D02*
X478983Y-542979D01*
G01X480250Y-541854D02*
X481103D01*
X481023Y-541562D01*
X480890Y-541396D01*
X480703Y-541312D01*
X480517Y-541354D01*
X480357Y-541479D01*
X480250Y-541771D01*
X480197Y-542021D01*
Y-542271D01*
X480250Y-542521D01*
X480383Y-542771D01*
X480543Y-542937D01*
X480730Y-542979D01*
X480917Y-542896D01*
X481103Y-542646D01*
G01X482370Y-541312D02*
X482850Y-542979D01*
X483330Y-541312D01*
G01X485050Y-543062D02*
X484997Y-543021D01*
Y-542937D01*
X485050Y-542896D01*
X485103Y-542937D01*
Y-543021D01*
X485050Y-543062D01*
G01X487250Y-542979D02*
X487437Y-542937D01*
X487650Y-542812D01*
X487783Y-542604D01*
X487837Y-542312D01*
X487783Y-542021D01*
X487623Y-541771D01*
X487383Y-541646D01*
X487117D01*
X486957Y-541562D01*
X486823Y-541354D01*
X486770Y-541062D01*
X486850Y-540771D01*
X487037Y-540562D01*
X487250Y-540479D01*
X487463Y-540562D01*
X487650Y-540771D01*
X487730Y-541062D01*
X487677Y-541354D01*
X487543Y-541562D01*
X487383Y-541646D01*
X487117D01*
X486877Y-541771D01*
X486717Y-542021D01*
X486663Y-542312D01*
X486717Y-542604D01*
X486850Y-542812D01*
X487063Y-542937D01*
X487250Y-542979D01*
G01X489663Y-541646D02*
X489770Y-541521D01*
X489850Y-541312D01*
X489903Y-541021D01*
X489850Y-540771D01*
X489743Y-540604D01*
X489557Y-540479D01*
X488837D01*
Y-542979D01*
X489717D01*
X489903Y-542812D01*
X490010Y-542562D01*
X490063Y-542271D01*
X490010Y-541979D01*
X489850Y-541729D01*
X489663Y-541646D01*
X488837D01*
G01X455550Y-516979D02*
Y-521979D01*
G01X454093Y-516979D02*
X457007D01*
G01X460650Y-521979D02*
X460270Y-521896D01*
X459890Y-521562D01*
X459637Y-520979D01*
X459510Y-520312D01*
X459637Y-519646D01*
X459890Y-519062D01*
X460270Y-518729D01*
X460650Y-518646D01*
X461030Y-518729D01*
X461410Y-519062D01*
X461663Y-519646D01*
X461727Y-520312D01*
X461663Y-520979D01*
X461410Y-521562D01*
X461030Y-521896D01*
X460650Y-521979D01*
G01X465750D02*
X465370Y-521896D01*
X464990Y-521562D01*
X464737Y-520979D01*
X464610Y-520312D01*
X464737Y-519646D01*
X464990Y-519062D01*
X465370Y-518729D01*
X465750Y-518646D01*
X466130Y-518729D01*
X466510Y-519062D01*
X466763Y-519646D01*
X466827Y-520312D01*
X466763Y-520979D01*
X466510Y-521562D01*
X466130Y-521896D01*
X465750Y-521979D01*
G01X470850D02*
Y-516979D01*
G01X475950Y-522146D02*
X475823Y-522062D01*
Y-521896D01*
X475950Y-521812D01*
X476077Y-521896D01*
Y-522062D01*
X475950Y-522146D01*
G01Y-519896D02*
X475823Y-519812D01*
Y-519646D01*
X475950Y-519562D01*
X476077Y-519646D01*
Y-519812D01*
X475950Y-519896D01*
G01X454283Y-496979D02*
Y-491979D01*
X455867D01*
X456373Y-492229D01*
X456690Y-492562D01*
X456817Y-493229D01*
X456690Y-493896D01*
X456310Y-494312D01*
X455867Y-494562D01*
X454283D01*
G01X455867D02*
X456817Y-496979D01*
G01X461917D02*
X459383D01*
Y-491979D01*
X461917D01*
G01X460903Y-494396D02*
X459383D01*
G01X464167Y-491979D02*
X465750Y-496979D01*
X467333Y-491979D01*
G01X470850Y-497146D02*
X470723Y-497062D01*
Y-496896D01*
X470850Y-496812D01*
X470977Y-496896D01*
Y-497062D01*
X470850Y-497146D01*
G01Y-494896D02*
X470723Y-494812D01*
Y-494646D01*
X470850Y-494562D01*
X470977Y-494646D01*
Y-494812D01*
X470850Y-494896D01*
G01X-984580Y-698988D02*
Y4193602D01*
X5868320D01*
Y-698988D01*
X-984580D01*
G01X7723Y-521204D02*
X7253Y-520889D01*
X6705Y-520679D01*
X6078D01*
X5373Y-520994D01*
X4825Y-521519D01*
X4433Y-522149D01*
X4120Y-523199D01*
X4042Y-524144D01*
X4198Y-525089D01*
X4433Y-525719D01*
X4903Y-526349D01*
X5452Y-526769D01*
X6000Y-526979D01*
X6548D01*
X7097Y-526769D01*
X7567Y-526454D01*
X7958Y-526034D01*
G01X11360Y-520679D02*
X13240D01*
G01X12300D02*
Y-526979D01*
G01X11360D02*
X13240D01*
G01X18600Y-520679D02*
Y-526979D01*
G01X16798Y-520679D02*
X20402D01*
G01X24900Y-526979D02*
Y-524144D01*
X23333Y-520679D01*
G01X26467D02*
X24900Y-524144D01*
G01X35777Y-525719D02*
X36247Y-526454D01*
X36873Y-526874D01*
X37578Y-526979D01*
X38205Y-526874D01*
X38832Y-526349D01*
X39223Y-525719D01*
X39302Y-525089D01*
X39145Y-524354D01*
X38597Y-523829D01*
X38048Y-523619D01*
X37343D01*
G01X38048D02*
X38518Y-523304D01*
X38910Y-522779D01*
X39067Y-522149D01*
X38910Y-521519D01*
X38518Y-520994D01*
X37813Y-520679D01*
X37108Y-520784D01*
X36403Y-521204D01*
G01X42077Y-525719D02*
X42547Y-526454D01*
X43173Y-526874D01*
X43878Y-526979D01*
X44505Y-526874D01*
X45132Y-526349D01*
X45523Y-525719D01*
X45602Y-525089D01*
X45445Y-524354D01*
X44897Y-523829D01*
X44348Y-523619D01*
X43643D01*
G01X44348D02*
X44818Y-523304D01*
X45210Y-522779D01*
X45367Y-522149D01*
X45210Y-521519D01*
X44818Y-520994D01*
X44113Y-520679D01*
X43408Y-520784D01*
X42703Y-521204D01*
G01X48377Y-525719D02*
X48847Y-526454D01*
X49473Y-526874D01*
X50178Y-526979D01*
X50805Y-526874D01*
X51432Y-526349D01*
X51823Y-525719D01*
X51902Y-525089D01*
X51745Y-524354D01*
X51197Y-523829D01*
X50648Y-523619D01*
X49943D01*
G01X50648D02*
X51118Y-523304D01*
X51510Y-522779D01*
X51667Y-522149D01*
X51510Y-521519D01*
X51118Y-520994D01*
X50413Y-520679D01*
X49708Y-520784D01*
X49003Y-521204D01*
G01X56243Y-526979D02*
X56400Y-525614D01*
X56635Y-524459D01*
X56948Y-523409D01*
X57340Y-522254D01*
X57967Y-520679D01*
X54833D01*
G01X62543Y-526979D02*
X62700Y-525614D01*
X62935Y-524459D01*
X63248Y-523409D01*
X63640Y-522254D01*
X64267Y-520679D01*
X61133D01*
G01X68843Y-528134D02*
X69157Y-526769D01*
G01X75300Y-520679D02*
Y-526979D01*
G01X73498Y-520679D02*
X77102D01*
G01X79642Y-526979D02*
X81600Y-520679D01*
X83558Y-526979D01*
G01X82853Y-524774D02*
X80347D01*
G01X86960Y-520679D02*
X88840D01*
G01X87900D02*
Y-526979D01*
G01X86960D02*
X88840D01*
G01X91850Y-520679D02*
X92947Y-526979D01*
X94200Y-520679D01*
X95453Y-526979D01*
X96550Y-520679D01*
G01X98542Y-526979D02*
X100500Y-520679D01*
X102458Y-526979D01*
G01X101753Y-524774D02*
X99247D01*
G01X104998Y-526979D02*
Y-520679D01*
X108602Y-526979D01*
Y-520679D01*
G01X119008Y-529079D02*
X118225Y-528029D01*
X117833Y-526979D01*
Y-522779D01*
X118225Y-521729D01*
X119008Y-520679D01*
G01X130433Y-526979D02*
Y-520679D01*
X132392D01*
X133018Y-520994D01*
X133410Y-521414D01*
X133567Y-522254D01*
X133410Y-523094D01*
X132940Y-523619D01*
X132392Y-523934D01*
X130433D01*
G01X132392D02*
X133567Y-526979D01*
G01X138300Y-527189D02*
X138143Y-527084D01*
Y-526874D01*
X138300Y-526769D01*
X138457Y-526874D01*
Y-527084D01*
X138300Y-527189D01*
G01X144600Y-526979D02*
X143973Y-526874D01*
X143425Y-526454D01*
X142955Y-525824D01*
X142642Y-525089D01*
X142485Y-524249D01*
Y-523409D01*
X142642Y-522569D01*
X142955Y-521834D01*
X143425Y-521204D01*
X143973Y-520784D01*
X144600Y-520679D01*
X145227Y-520784D01*
X145775Y-521204D01*
X146245Y-521834D01*
X146558Y-522569D01*
X146715Y-523409D01*
Y-524249D01*
X146558Y-525089D01*
X146245Y-525824D01*
X145775Y-526454D01*
X145227Y-526874D01*
X144600Y-526979D01*
G01X150900Y-527189D02*
X150743Y-527084D01*
Y-526874D01*
X150900Y-526769D01*
X151057Y-526874D01*
Y-527084D01*
X150900Y-527189D01*
G01X158923Y-521204D02*
X158453Y-520889D01*
X157905Y-520679D01*
X157278D01*
X156573Y-520994D01*
X156025Y-521519D01*
X155633Y-522149D01*
X155320Y-523199D01*
X155242Y-524144D01*
X155398Y-525089D01*
X155633Y-525719D01*
X156103Y-526349D01*
X156652Y-526769D01*
X157200Y-526979D01*
X157748D01*
X158297Y-526769D01*
X158767Y-526454D01*
X159158Y-526034D01*
G01X163500Y-527189D02*
X163343Y-527084D01*
Y-526874D01*
X163500Y-526769D01*
X163657Y-526874D01*
Y-527084D01*
X163500Y-527189D01*
G01X170192Y-529079D02*
X170975Y-528029D01*
X171367Y-526979D01*
Y-522779D01*
X170975Y-521729D01*
X170192Y-520679D01*
G01X6470Y-513829D02*
X8037D01*
Y-515719D01*
X7567Y-516349D01*
X7018Y-516769D01*
X6235Y-516979D01*
X5452Y-516769D01*
X4903Y-516349D01*
X4433Y-515719D01*
X4120Y-514984D01*
X3963Y-514144D01*
Y-513409D01*
X4120Y-512779D01*
X4433Y-512044D01*
X4903Y-511414D01*
X5373Y-510994D01*
X6000Y-510679D01*
X6548D01*
X7175Y-510889D01*
X7645Y-511309D01*
G01X10577Y-510679D02*
Y-515194D01*
X10890Y-516139D01*
X11517Y-516769D01*
X12300Y-516979D01*
X13083Y-516769D01*
X13710Y-516139D01*
X14023Y-515194D01*
Y-510679D01*
G01X17660D02*
X19540D01*
G01X18600D02*
Y-516979D01*
G01X17660D02*
X19540D01*
G01X23255Y-516139D02*
X23882Y-516664D01*
X24587Y-516979D01*
X25213D01*
X25840Y-516664D01*
X26310Y-516139D01*
X26545Y-515404D01*
X26388Y-514669D01*
X25997Y-514039D01*
X25292Y-513619D01*
X24352Y-513409D01*
X23803Y-512989D01*
X23568Y-512254D01*
X23725Y-511519D01*
X24117Y-510994D01*
X24665Y-510679D01*
X25213D01*
X25762Y-510889D01*
X26232Y-511414D01*
G01X29555Y-516979D02*
Y-510679D01*
G01X32845D02*
Y-516979D01*
G01Y-513829D02*
X29555D01*
G01X35542Y-516979D02*
X37500Y-510679D01*
X39458Y-516979D01*
G01X38753Y-514774D02*
X36247D01*
G01X41998Y-516979D02*
Y-510679D01*
X45602Y-516979D01*
Y-510679D01*
G01X54677Y-516979D02*
Y-510679D01*
X56243D01*
X56870Y-510994D01*
X57340Y-511414D01*
X57732Y-512044D01*
X58045Y-512779D01*
X58123Y-513829D01*
X58045Y-514879D01*
X57732Y-515614D01*
X57340Y-516244D01*
X56870Y-516664D01*
X56243Y-516979D01*
X54677D01*
G01X61760Y-510679D02*
X63640D01*
G01X62700D02*
Y-516979D01*
G01X61760D02*
X63640D01*
G01X67355Y-516139D02*
X67982Y-516664D01*
X68687Y-516979D01*
X69313D01*
X69940Y-516664D01*
X70410Y-516139D01*
X70645Y-515404D01*
X70488Y-514669D01*
X70097Y-514039D01*
X69392Y-513619D01*
X68452Y-513409D01*
X67903Y-512989D01*
X67668Y-512254D01*
X67825Y-511519D01*
X68217Y-510994D01*
X68765Y-510679D01*
X69313D01*
X69862Y-510889D01*
X70332Y-511414D01*
G01X75300Y-510679D02*
Y-516979D01*
G01X73498Y-510679D02*
X77102D01*
G01X81600Y-517189D02*
X81443Y-517084D01*
Y-516874D01*
X81600Y-516769D01*
X81757Y-516874D01*
Y-517084D01*
X81600Y-517189D01*
G01X87743Y-518134D02*
X88057Y-516769D01*
G01X94200Y-510679D02*
Y-516979D01*
G01X92398Y-510679D02*
X96002D01*
G01X98542Y-516979D02*
X100500Y-510679D01*
X102458Y-516979D01*
G01X101753Y-514774D02*
X99247D01*
G01X106800Y-516979D02*
X106173Y-516874D01*
X105625Y-516454D01*
X105155Y-515824D01*
X104842Y-515089D01*
X104685Y-514249D01*
Y-513409D01*
X104842Y-512569D01*
X105155Y-511834D01*
X105625Y-511204D01*
X106173Y-510784D01*
X106800Y-510679D01*
X107427Y-510784D01*
X107975Y-511204D01*
X108445Y-511834D01*
X108758Y-512569D01*
X108915Y-513409D01*
Y-514249D01*
X108758Y-515089D01*
X108445Y-515824D01*
X107975Y-516454D01*
X107427Y-516874D01*
X106800Y-516979D01*
G01X113100D02*
Y-514144D01*
X111533Y-510679D01*
G01X114667D02*
X113100Y-514144D01*
G01X117677Y-510679D02*
Y-515194D01*
X117990Y-516139D01*
X118617Y-516769D01*
X119400Y-516979D01*
X120183Y-516769D01*
X120810Y-516139D01*
X121123Y-515194D01*
Y-510679D01*
G01X123742Y-516979D02*
X125700Y-510679D01*
X127658Y-516979D01*
G01X126953Y-514774D02*
X124447D01*
G01X130198Y-516979D02*
Y-510679D01*
X133802Y-516979D01*
Y-510679D01*
G01X4198Y-506979D02*
Y-500679D01*
X7802Y-506979D01*
Y-500679D01*
G01X12300Y-506979D02*
X11673Y-506874D01*
X11125Y-506454D01*
X10655Y-505824D01*
X10342Y-505089D01*
X10185Y-504249D01*
Y-503409D01*
X10342Y-502569D01*
X10655Y-501834D01*
X11125Y-501204D01*
X11673Y-500784D01*
X12300Y-500679D01*
X12927Y-500784D01*
X13475Y-501204D01*
X13945Y-501834D01*
X14258Y-502569D01*
X14415Y-503409D01*
Y-504249D01*
X14258Y-505089D01*
X13945Y-505824D01*
X13475Y-506454D01*
X12927Y-506874D01*
X12300Y-506979D01*
G01X18600Y-507189D02*
X18443Y-507084D01*
Y-506874D01*
X18600Y-506769D01*
X18757Y-506874D01*
Y-507084D01*
X18600Y-507189D01*
G01X23412Y-501729D02*
X23882Y-501099D01*
X24430Y-500784D01*
X25057Y-500679D01*
X25840Y-500889D01*
X26388Y-501414D01*
X26545Y-502044D01*
X26467Y-502674D01*
X26153Y-503199D01*
X24587Y-504249D01*
X23882Y-504984D01*
X23412Y-506034D01*
X23255Y-506979D01*
X26545D01*
G01X31200D02*
Y-500679D01*
X30260Y-501939D01*
G01Y-506979D02*
X32140D01*
G01X37500D02*
Y-500679D01*
X36560Y-501939D01*
G01Y-506979D02*
X38440D01*
G01X43643Y-508134D02*
X43957Y-506769D01*
G01X47750Y-500679D02*
X48847Y-506979D01*
X50100Y-500679D01*
X51353Y-506979D01*
X52450Y-500679D01*
G01X57967Y-506979D02*
X54833D01*
Y-500679D01*
X57967D01*
G01X56713Y-503724D02*
X54833D01*
G01X60898Y-506979D02*
Y-500679D01*
X64502Y-506979D01*
Y-500679D01*
G01X67355Y-506979D02*
Y-500679D01*
G01X70645D02*
Y-506979D01*
G01Y-503829D02*
X67355D01*
G01X73577Y-500679D02*
Y-505194D01*
X73890Y-506139D01*
X74517Y-506769D01*
X75300Y-506979D01*
X76083Y-506769D01*
X76710Y-506139D01*
X77023Y-505194D01*
Y-500679D01*
G01X79642Y-506979D02*
X81600Y-500679D01*
X83558Y-506979D01*
G01X82853Y-504774D02*
X80347D01*
G01X92712Y-501729D02*
X93182Y-501099D01*
X93730Y-500784D01*
X94357Y-500679D01*
X95140Y-500889D01*
X95688Y-501414D01*
X95845Y-502044D01*
X95767Y-502674D01*
X95453Y-503199D01*
X93887Y-504249D01*
X93182Y-504984D01*
X92712Y-506034D01*
X92555Y-506979D01*
X95845D01*
G01X98698D02*
Y-500679D01*
X102302Y-506979D01*
Y-500679D01*
G01X105077Y-506979D02*
Y-500679D01*
X106643D01*
X107270Y-500994D01*
X107740Y-501414D01*
X108132Y-502044D01*
X108445Y-502779D01*
X108523Y-503829D01*
X108445Y-504879D01*
X108132Y-505614D01*
X107740Y-506244D01*
X107270Y-506664D01*
X106643Y-506979D01*
X105077D01*
G01X117833D02*
Y-500679D01*
X119792D01*
X120418Y-500994D01*
X120810Y-501414D01*
X120967Y-502254D01*
X120810Y-503094D01*
X120340Y-503619D01*
X119792Y-503934D01*
X117833D01*
G01X119792D02*
X120967Y-506979D01*
G01X123977D02*
Y-500679D01*
X125543D01*
X126170Y-500994D01*
X126640Y-501414D01*
X127032Y-502044D01*
X127345Y-502779D01*
X127423Y-503829D01*
X127345Y-504879D01*
X127032Y-505614D01*
X126640Y-506244D01*
X126170Y-506664D01*
X125543Y-506979D01*
X123977D01*
G01X132000Y-507189D02*
X131843Y-507084D01*
Y-506874D01*
X132000Y-506769D01*
X132157Y-506874D01*
Y-507084D01*
X132000Y-507189D01*
G01X28300Y-494279D02*
X25780Y-493862D01*
X23575Y-492196D01*
X21685Y-489696D01*
X20425Y-486779D01*
X19795Y-483446D01*
Y-480112D01*
X20425Y-476779D01*
X21685Y-473862D01*
X23575Y-471363D01*
X25780Y-469696D01*
X28300Y-469279D01*
X30820Y-469696D01*
X33025Y-471363D01*
X34915Y-473862D01*
X36175Y-476779D01*
X36805Y-480112D01*
Y-483446D01*
X36175Y-486779D01*
X34915Y-489696D01*
X33025Y-492196D01*
X30820Y-493862D01*
X28300Y-494279D01*
G01X30820Y-487612D02*
X34600Y-494279D01*
G01X48145Y-477613D02*
Y-489279D01*
X49405Y-492196D01*
X51295Y-493862D01*
X53500Y-494279D01*
X55705Y-493862D01*
X57595Y-492196D01*
X58855Y-489279D01*
G01Y-494279D02*
Y-477613D01*
G01X84370Y-494279D02*
Y-477613D01*
G01Y-480529D02*
X83110Y-478863D01*
X81220Y-478029D01*
X79015Y-477613D01*
X76810Y-478446D01*
X74920Y-480112D01*
X73660Y-482613D01*
X73030Y-485946D01*
X73660Y-489279D01*
X74920Y-491780D01*
X76810Y-493446D01*
X79015Y-494279D01*
X81220Y-493862D01*
X83110Y-492613D01*
X84370Y-490946D01*
G01X98545Y-494279D02*
Y-477613D01*
G01Y-481779D02*
X99805Y-479696D01*
X101695Y-478029D01*
X104215Y-477613D01*
X106420Y-478029D01*
X108310Y-479696D01*
X109255Y-482613D01*
Y-494279D01*
G01X129100Y-469279D02*
Y-494279D01*
G01X124690Y-477613D02*
X133510D01*
G01X159970Y-494279D02*
Y-477613D01*
G01Y-480529D02*
X158710Y-478863D01*
X156820Y-478029D01*
X154615Y-477613D01*
X152410Y-478446D01*
X150520Y-480112D01*
X149260Y-482613D01*
X148630Y-485946D01*
X149260Y-489279D01*
X150520Y-491780D01*
X152410Y-493446D01*
X154615Y-494279D01*
X156820Y-493862D01*
X158710Y-492613D01*
X159970Y-490946D01*
G01X199650Y-473979D02*
Y-481979D01*
X203650D01*
G01X211450D02*
Y-476646D01*
G01Y-477579D02*
X211050Y-477046D01*
X210450Y-476779D01*
X209750Y-476646D01*
X209050Y-476912D01*
X208450Y-477446D01*
X208050Y-478246D01*
X207850Y-479312D01*
X208050Y-480379D01*
X208450Y-481179D01*
X209050Y-481712D01*
X209750Y-481979D01*
X210450Y-481846D01*
X211050Y-481446D01*
X211450Y-480913D01*
G01X215550Y-484379D02*
X216150Y-484646D01*
X216950Y-484379D01*
X217450Y-483846D01*
X217850Y-483179D01*
X218450Y-481046D01*
X219750Y-476646D01*
G01X216550D02*
X218450Y-481046D01*
G01X224150Y-478379D02*
X227350D01*
X227050Y-477446D01*
X226550Y-476912D01*
X225850Y-476646D01*
X225150Y-476779D01*
X224550Y-477179D01*
X224150Y-478112D01*
X223950Y-478913D01*
Y-479712D01*
X224150Y-480512D01*
X224650Y-481312D01*
X225250Y-481846D01*
X225950Y-481979D01*
X226650Y-481712D01*
X227350Y-480913D01*
G01X232250Y-481979D02*
Y-476646D01*
G01Y-477712D02*
X232750Y-477179D01*
X233250Y-476779D01*
X233950Y-476646D01*
X234450Y-476779D01*
X235050Y-477179D01*
G01X223350Y-531979D02*
Y-523979D01*
X227950Y-531979D01*
Y-523979D01*
G01X233650Y-526646D02*
Y-531979D01*
G01Y-524512D02*
X233450Y-524379D01*
Y-524112D01*
X233650Y-523979D01*
X233850Y-524112D01*
Y-524379D01*
X233650Y-524512D01*
G01X239950Y-531979D02*
Y-526646D01*
G01Y-527979D02*
X240350Y-527312D01*
X240950Y-526779D01*
X241750Y-526646D01*
X242450Y-526779D01*
X243050Y-527312D01*
X243350Y-528246D01*
Y-531979D01*
G01X251450D02*
Y-526646D01*
G01Y-527579D02*
X251050Y-527046D01*
X250450Y-526779D01*
X249750Y-526646D01*
X249050Y-526912D01*
X248450Y-527446D01*
X248050Y-528246D01*
X247850Y-529312D01*
X248050Y-530379D01*
X248450Y-531179D01*
X249050Y-531712D01*
X249750Y-531979D01*
X250450Y-531846D01*
X251050Y-531446D01*
X251450Y-530913D01*
G01X220479Y-503336D02*
X222479D01*
Y-505736D01*
X221879Y-506536D01*
X221179Y-507069D01*
X220179Y-507336D01*
X219179Y-507069D01*
X218479Y-506536D01*
X217879Y-505736D01*
X217479Y-504803D01*
X217279Y-503736D01*
Y-502803D01*
X217479Y-502003D01*
X217879Y-501069D01*
X218479Y-500269D01*
X219079Y-499736D01*
X219879Y-499336D01*
X220579D01*
X221379Y-499603D01*
X221979Y-500136D01*
G01X225579Y-507336D02*
Y-499336D01*
X230179Y-507336D01*
Y-499336D01*
G01X233679Y-507336D02*
Y-499336D01*
X235679D01*
X236479Y-499736D01*
X237079Y-500269D01*
X237579Y-501069D01*
X237979Y-502003D01*
X238079Y-503336D01*
X237979Y-504669D01*
X237579Y-505603D01*
X237079Y-506403D01*
X236479Y-506936D01*
X235679Y-507336D01*
X233679D01*
G01X241979Y-504003D02*
X242679Y-503069D01*
X243279Y-502536D01*
X244079Y-502269D01*
X244779Y-502536D01*
X245279Y-503069D01*
X245679Y-503869D01*
X245779Y-504803D01*
X245679Y-505603D01*
X245279Y-506403D01*
X244679Y-507069D01*
X243979Y-507336D01*
X243179Y-507069D01*
X242479Y-506270D01*
X242079Y-505069D01*
X241979Y-503736D01*
X242179Y-502003D01*
X242479Y-501069D01*
X242979Y-500136D01*
X243679Y-499469D01*
X244379Y-499336D01*
X245079Y-499603D01*
X245579Y-500269D01*
G01X252079Y-483936D02*
Y-475936D01*
X250879Y-477536D01*
G01Y-483936D02*
X253279D01*
G01X257879Y-482736D02*
X258479Y-483403D01*
X259179Y-483803D01*
X260079Y-483936D01*
X260979Y-483669D01*
X261679Y-483136D01*
X262179Y-482203D01*
X262279Y-481136D01*
X262079Y-480069D01*
X261579Y-479403D01*
X260879Y-478869D01*
X260179Y-478736D01*
X259479Y-478869D01*
X258579Y-479403D01*
X258879Y-475936D01*
X261579D01*
G01X326250Y-525312D02*
X326850Y-524512D01*
X327550Y-524112D01*
X328350Y-523979D01*
X329350Y-524246D01*
X330050Y-524912D01*
X330250Y-525712D01*
X330150Y-526513D01*
X329750Y-527179D01*
X327750Y-528512D01*
X326850Y-529446D01*
X326250Y-530779D01*
X326050Y-531979D01*
X330250D01*
G01X336150Y-523979D02*
X335350Y-524246D01*
X334750Y-524912D01*
X334350Y-525712D01*
X334050Y-526779D01*
X333950Y-527979D01*
X334050Y-529179D01*
X334350Y-530246D01*
X334750Y-531046D01*
X335350Y-531712D01*
X336150Y-531979D01*
X336950Y-531712D01*
X337550Y-531046D01*
X337950Y-530246D01*
X338250Y-529179D01*
X338350Y-527979D01*
X338250Y-526779D01*
X337950Y-525712D01*
X337550Y-524912D01*
X336950Y-524246D01*
X336150Y-523979D01*
G01X342250Y-525312D02*
X342850Y-524512D01*
X343550Y-524112D01*
X344350Y-523979D01*
X345350Y-524246D01*
X346050Y-524912D01*
X346250Y-525712D01*
X346150Y-526513D01*
X345750Y-527179D01*
X343750Y-528512D01*
X342850Y-529446D01*
X342250Y-530779D01*
X342050Y-531979D01*
X346250D01*
G01X349950Y-530379D02*
X350550Y-531312D01*
X351350Y-531846D01*
X352250Y-531979D01*
X353050Y-531846D01*
X353850Y-531179D01*
X354350Y-530379D01*
X354450Y-529579D01*
X354250Y-528646D01*
X353550Y-527979D01*
X352850Y-527712D01*
X351950D01*
G01X352850D02*
X353450Y-527312D01*
X353950Y-526646D01*
X354150Y-525846D01*
X353950Y-525046D01*
X353450Y-524379D01*
X352550Y-523979D01*
X351650Y-524112D01*
X350750Y-524646D01*
G01X358350Y-532246D02*
X361950Y-523979D01*
G01X368150D02*
X367350Y-524246D01*
X366750Y-524912D01*
X366350Y-525712D01*
X366050Y-526779D01*
X365950Y-527979D01*
X366050Y-529179D01*
X366350Y-530246D01*
X366750Y-531046D01*
X367350Y-531712D01*
X368150Y-531979D01*
X368950Y-531712D01*
X369550Y-531046D01*
X369950Y-530246D01*
X370250Y-529179D01*
X370350Y-527979D01*
X370250Y-526779D01*
X369950Y-525712D01*
X369550Y-524912D01*
X368950Y-524246D01*
X368150Y-523979D01*
G01X373950Y-530379D02*
X374550Y-531312D01*
X375350Y-531846D01*
X376250Y-531979D01*
X377050Y-531846D01*
X377850Y-531179D01*
X378350Y-530379D01*
X378450Y-529579D01*
X378250Y-528646D01*
X377550Y-527979D01*
X376850Y-527712D01*
X375950D01*
G01X376850D02*
X377450Y-527312D01*
X377950Y-526646D01*
X378150Y-525846D01*
X377950Y-525046D01*
X377450Y-524379D01*
X376550Y-523979D01*
X375650Y-524112D01*
X374750Y-524646D01*
G01X382350Y-532246D02*
X385950Y-523979D01*
G01X390250Y-525312D02*
X390850Y-524512D01*
X391550Y-524112D01*
X392350Y-523979D01*
X393350Y-524246D01*
X394050Y-524912D01*
X394250Y-525712D01*
X394150Y-526513D01*
X393750Y-527179D01*
X391750Y-528512D01*
X390850Y-529446D01*
X390250Y-530779D01*
X390050Y-531979D01*
X394250D01*
G01X401350D02*
Y-523979D01*
X397650Y-529712D01*
X402650D01*
G01X325950Y-506979D02*
Y-498979D01*
X327950D01*
X328750Y-499379D01*
X329350Y-499912D01*
X329850Y-500712D01*
X330250Y-501646D01*
X330350Y-502979D01*
X330250Y-504312D01*
X329850Y-505246D01*
X329350Y-506046D01*
X328750Y-506579D01*
X327950Y-506979D01*
X325950D01*
G01X333650D02*
X336150Y-498979D01*
X338650Y-506979D01*
G01X337750Y-504179D02*
X334550D01*
G01X344150Y-498979D02*
X343350Y-499246D01*
X342750Y-499912D01*
X342350Y-500712D01*
X342050Y-501779D01*
X341950Y-502979D01*
X342050Y-504179D01*
X342350Y-505246D01*
X342750Y-506046D01*
X343350Y-506712D01*
X344150Y-506979D01*
X344950Y-506712D01*
X345550Y-506046D01*
X345950Y-505246D01*
X346250Y-504179D01*
X346350Y-502979D01*
X346250Y-501779D01*
X345950Y-500712D01*
X345550Y-499912D01*
X344950Y-499246D01*
X344150Y-498979D01*
G01X350250Y-506979D02*
Y-498979D01*
X354050D01*
G01X352650Y-502846D02*
X350250D01*
G01X360150Y-498979D02*
X359350Y-499246D01*
X358750Y-499912D01*
X358350Y-500712D01*
X358050Y-501779D01*
X357950Y-502979D01*
X358050Y-504179D01*
X358350Y-505246D01*
X358750Y-506046D01*
X359350Y-506712D01*
X360150Y-506979D01*
X360950Y-506712D01*
X361550Y-506046D01*
X361950Y-505246D01*
X362250Y-504179D01*
X362350Y-502979D01*
X362250Y-501779D01*
X361950Y-500712D01*
X361550Y-499912D01*
X360950Y-499246D01*
X360150Y-498979D01*
G01X368150D02*
Y-506979D01*
G01X365850Y-498979D02*
X370450D01*
G01X373550Y-506979D02*
Y-498979D01*
X376150Y-505646D01*
X378750Y-498979D01*
Y-506979D01*
G01X384950Y-502712D02*
X385350Y-502312D01*
X385650Y-501646D01*
X385850Y-500712D01*
X385650Y-499912D01*
X385250Y-499379D01*
X384550Y-498979D01*
X381850D01*
Y-506979D01*
X385150D01*
X385850Y-506446D01*
X386250Y-505646D01*
X386450Y-504712D01*
X386250Y-503779D01*
X385650Y-502979D01*
X384950Y-502712D01*
X381850D01*
G01X390950Y-498979D02*
X393350D01*
G01X392150D02*
Y-506979D01*
G01X390950D02*
X393350D01*
G01X398150Y-505379D02*
X398650Y-506179D01*
X399250Y-506712D01*
X399950Y-506979D01*
X400750Y-506712D01*
X401350Y-506179D01*
X401950Y-505379D01*
X402150Y-504312D01*
Y-498979D01*
G01X408150D02*
X407350Y-499246D01*
X406750Y-499912D01*
X406350Y-500712D01*
X406050Y-501779D01*
X405950Y-502979D01*
X406050Y-504179D01*
X406350Y-505246D01*
X406750Y-506046D01*
X407350Y-506712D01*
X408150Y-506979D01*
X408950Y-506712D01*
X409550Y-506046D01*
X409950Y-505246D01*
X410250Y-504179D01*
X410350Y-502979D01*
X410250Y-501779D01*
X409950Y-500712D01*
X409550Y-499912D01*
X408950Y-499246D01*
X408150Y-498979D01*
G01X343750Y-481979D02*
Y-473979D01*
X347550D01*
G01X346150Y-477846D02*
X343750D01*
G01X353650Y-473979D02*
X352850Y-474246D01*
X352250Y-474912D01*
X351850Y-475712D01*
X351550Y-476779D01*
X351450Y-477979D01*
X351550Y-479179D01*
X351850Y-480246D01*
X352250Y-481046D01*
X352850Y-481712D01*
X353650Y-481979D01*
X354450Y-481712D01*
X355050Y-481046D01*
X355450Y-480246D01*
X355750Y-479179D01*
X355850Y-477979D01*
X355750Y-476779D01*
X355450Y-475712D01*
X355050Y-474912D01*
X354450Y-474246D01*
X353650Y-473979D01*
G01X361650D02*
Y-481979D01*
G01X359350Y-473979D02*
X363950D01*
G01X366650Y-484646D02*
X372650D01*
G01X375050Y-481979D02*
Y-473979D01*
X377650Y-480646D01*
X380250Y-473979D01*
Y-481979D01*
G01X386450Y-477712D02*
X386850Y-477312D01*
X387150Y-476646D01*
X387350Y-475712D01*
X387150Y-474912D01*
X386750Y-474379D01*
X386050Y-473979D01*
X383350D01*
Y-481979D01*
X386650D01*
X387350Y-481446D01*
X387750Y-480646D01*
X387950Y-479712D01*
X387750Y-478779D01*
X387150Y-477979D01*
X386450Y-477712D01*
X383350D01*
G01X390650Y-484646D02*
X396650D01*
G01X403650Y-481979D02*
X399650D01*
Y-473979D01*
X403650D01*
G01X402050Y-477846D02*
X399650D01*
G01X407050Y-481979D02*
Y-473979D01*
X409650Y-480646D01*
X412250Y-473979D01*
Y-481979D01*
G01X417650D02*
X418350Y-481846D01*
X419150Y-481446D01*
X419650Y-480779D01*
X419850Y-479846D01*
X419650Y-478913D01*
X419050Y-478112D01*
X418150Y-477712D01*
X417150D01*
X416550Y-477446D01*
X416050Y-476779D01*
X415850Y-475846D01*
X416150Y-474912D01*
X416850Y-474246D01*
X417650Y-473979D01*
X418450Y-474246D01*
X419150Y-474912D01*
X419450Y-475846D01*
X419250Y-476779D01*
X418750Y-477446D01*
X418150Y-477712D01*
X417150D01*
X416250Y-478112D01*
X415650Y-478913D01*
X415450Y-479846D01*
X415650Y-480779D01*
X416150Y-481446D01*
X416950Y-481846D01*
X417650Y-481979D01*
G01X423950Y-481046D02*
X424650Y-481712D01*
X425450Y-481979D01*
X426250Y-481712D01*
X426950Y-480913D01*
X427450Y-479712D01*
X427650Y-478512D01*
Y-477046D01*
X427450Y-475846D01*
X426950Y-474779D01*
X426350Y-474246D01*
X425650Y-473979D01*
X424850Y-474246D01*
X424250Y-474779D01*
X423850Y-475579D01*
X423650Y-476646D01*
X423850Y-477579D01*
X424350Y-478512D01*
X424950Y-479046D01*
X425650Y-479179D01*
X426450Y-478913D01*
X427050Y-478246D01*
X427650Y-477046D01*
G01X433650Y-473979D02*
X432850Y-474246D01*
X432250Y-474912D01*
X431850Y-475712D01*
X431550Y-476779D01*
X431450Y-477979D01*
X431550Y-479179D01*
X431850Y-480246D01*
X432250Y-481046D01*
X432850Y-481712D01*
X433650Y-481979D01*
X434450Y-481712D01*
X435050Y-481046D01*
X435450Y-480246D01*
X435750Y-479179D01*
X435850Y-477979D01*
X435750Y-476779D01*
X435450Y-475712D01*
X435050Y-474912D01*
X434450Y-474246D01*
X433650Y-473979D01*
G01X439450Y-481979D02*
Y-473979D01*
G01X443250D02*
X439450Y-478913D01*
G01X443850Y-481979D02*
X441150Y-476646D01*
G01X414650Y-534979D02*
Y-526979D01*
X413450Y-528579D01*
G01Y-534979D02*
X415850D01*
G01X420750Y-531646D02*
X421450Y-530712D01*
X422050Y-530179D01*
X422850Y-529912D01*
X423550Y-530179D01*
X424050Y-530712D01*
X424450Y-531512D01*
X424550Y-532446D01*
X424450Y-533246D01*
X424050Y-534046D01*
X423450Y-534712D01*
X422750Y-534979D01*
X421950Y-534712D01*
X421250Y-533913D01*
X420850Y-532712D01*
X420750Y-531379D01*
X420950Y-529646D01*
X421250Y-528712D01*
X421750Y-527779D01*
X422450Y-527112D01*
X423150Y-526979D01*
X423850Y-527246D01*
X424350Y-527912D01*
G01X430650Y-535246D02*
X430450Y-535112D01*
Y-534846D01*
X430650Y-534712D01*
X430850Y-534846D01*
Y-535112D01*
X430650Y-535246D01*
G01X436750Y-531646D02*
X437450Y-530712D01*
X438050Y-530179D01*
X438850Y-529912D01*
X439550Y-530179D01*
X440050Y-530712D01*
X440450Y-531512D01*
X440550Y-532446D01*
X440450Y-533246D01*
X440050Y-534046D01*
X439450Y-534712D01*
X438750Y-534979D01*
X437950Y-534712D01*
X437250Y-533913D01*
X436850Y-532712D01*
X436750Y-531379D01*
X436950Y-529646D01*
X437250Y-528712D01*
X437750Y-527779D01*
X438450Y-527112D01*
X439150Y-526979D01*
X439850Y-527246D01*
X440350Y-527912D01*
G01X459650Y-534979D02*
Y-526979D01*
X458450Y-528579D01*
G01Y-534979D02*
X460850D01*
G01X467450D02*
X467650Y-533246D01*
X467950Y-531779D01*
X468350Y-530446D01*
X468850Y-528979D01*
X469650Y-526979D01*
X465650D01*
G01X475650Y-535246D02*
X475450Y-535112D01*
Y-534846D01*
X475650Y-534712D01*
X475850Y-534846D01*
Y-535112D01*
X475650Y-535246D01*
G01X481750Y-528312D02*
X482350Y-527512D01*
X483050Y-527112D01*
X483850Y-526979D01*
X484850Y-527246D01*
X485550Y-527912D01*
X485750Y-528712D01*
X485650Y-529513D01*
X485250Y-530179D01*
X483250Y-531512D01*
X482350Y-532446D01*
X481750Y-533779D01*
X481550Y-534979D01*
X485750D01*
G01X479650Y-508379D02*
X480150Y-509179D01*
X480750Y-509712D01*
X481450Y-509979D01*
X482250Y-509712D01*
X482850Y-509179D01*
X483450Y-508379D01*
X483650Y-507312D01*
Y-501979D01*
M02*
